(lib_symbols
	(symbol "kria-k26-devboard:1N4148WS" (pin_numbers hide) (pin_names hide) (in_bom yes) (on_board yes)
      (property "Reference" "D" (at 21.59 -5.08 0)
        (effects (font (size 1.27 1.27) (thickness 0.15)) (justify left bottom))
      )
      (property "Value" "1N4148WS" (at 21.59 -7.62 0)
        (effects (font (size 1.27 1.27) (thickness 0.15)) (justify left bottom))
      )
      (property "Footprint" "kria-k26-devboard-footprints:D_SOD-323F" (at 21.59 -10.16 0)
        (effects (font (size 1.27 1.27) (thickness 0.15)) (justify left bottom) hide)
      )
      (property "Datasheet" "https://www.onsemi.com/pub/Collateral/1N914BWS-D.pdf" (at 21.59 -12.7 0)
        (effects (font (size 1.27 1.27) (thickness 0.15)) (justify left bottom) hide)
      )
      (property "MPN" "1N4148WS" (at 21.59 -15.24 0)
        (effects (font (size 1.27 1.27) (thickness 0.15)) (justify left bottom) hide)
      )
      (property "Manufacturer" "ON Semiconductor" (at 21.59 -17.78 0)
        (effects (font (size 1.27 1.27) (thickness 0.15)) (justify left bottom) hide)
      )
      (property "Author" "Antmicro" (at 21.59 -20.32 0)
        (effects (font (size 1.27 1.27) (thickness 0.15)) (justify left bottom) hide)
      )
      (property "License" "Apache-2.0" (at 21.59 -22.86 0)
        (effects (font (size 1.27 1.27) (thickness 0.15)) (justify left bottom) hide)
      )
      (property "ki_description" "Small Signal Fast Switching Diode" (at 0 0 0)
        (effects (font (size 1.27 1.27)) hide)
      )
      (symbol "1N4148WS_1_1"
        (polyline
          (pts
            (xy 5.08 1.27)
            (xy 5.08 -1.27)
          )
          (stroke (width 0.254) (type default))
          (fill (type none))
        )
        (polyline
          (pts
            (xy 2.54 1.27)
            (xy 2.54 -1.27)
            (xy 5.08 0)
            (xy 2.54 1.27)
          )
          (stroke (width 0.254) (type default))
          (fill (type outline))
        )
        (pin passive line (at 0 0 0) (length 2.54)
          (name "A" (effects (font (size 1.27 1.27))))
          (number "A" (effects (font (size 1.27 1.27))))
        )
        (pin passive line (at 7.62 0 180) (length 2.54)
          (name "K" (effects (font (size 1.27 1.27))))
          (number "K" (effects (font (size 1.27 1.27))))
        )
      )
    )
	(symbol "kria-k26-devboard:74AVC4T245_UQFN" (in_bom yes) (on_board yes)
      (property "Reference" "U" (at 38.1 -2.54 0)
        (effects (font (size 1.27 1.27) (thickness 0.15)) (justify left bottom))
      )
      (property "Value" "74AVC4T245_UQFN" (at 38.1 -5.08 0)
        (effects (font (size 1.27 1.27) (thickness 0.15)) (justify left bottom))
      )
      (property "Footprint" "kria-k26-devboard-footprints:UQFN-16-1.8x2.6mm_P0.4mm_Texas_RSV0016A" (at 38.1 -7.62 0)
        (effects (font (size 1.27 1.27) (thickness 0.15)) (justify left bottom) hide)
      )
      (property "Datasheet" "https://www.ti.com/lit/ds/symlink/sn74avc4t245.pdf" (at 38.1 -10.16 0)
        (effects (font (size 1.27 1.27) (thickness 0.15)) (justify left bottom) hide)
      )
      (property "MPN" "74AVC4T245RSVRG4" (at 38.1 -12.7 0)
        (effects (font (size 1.27 1.27) (thickness 0.15)) (justify left bottom) hide)
      )
      (property "Manufacturer" "Texas Instruments" (at 38.1 -15.24 0)
        (effects (font (size 1.27 1.27) (thickness 0.15)) (justify left bottom) hide)
      )
      (property "Author" "Antmicro" (at 38.1 -17.78 0)
        (effects (font (size 1.27 1.27) (thickness 0.15)) (justify left bottom) hide)
      )
      (property "License" "Apache-2.0" (at 38.1 -20.32 0)
        (effects (font (size 1.27 1.27) (thickness 0.15)) (justify left bottom) hide)
      )
      (property "ki_keywords" "SMT, LOGIC, IC, LEVEL-SHIFTER" (at 0 0 0)
        (effects (font (size 1.27 1.27)) hide)
      )
      (property "ki_description" "Logic translator/level shifter" (at 0 0 0)
        (effects (font (size 1.27 1.27)) hide)
      )
      (symbol "74AVC4T245_UQFN_1_1"
        (rectangle (start 2.54 5.08) (end 16.51 -20.32)
          (stroke (width 0.254) (type default))
          (fill (type background))
        )
        (pin input line (at 0 0 0) (length 2.54)
          (name "1~{OE}" (effects (font (size 1.27 1.27))))
          (number "1" (effects (font (size 1.27 1.27))))
        )
        (pin power_in line (at 19.05 0 180) (length 2.54)
          (name "GND" (effects (font (size 1.27 1.27))))
          (number "10" (effects (font (size 1.27 1.27))))
        )
        (pin passive line (at 19.05 0 180) (length 2.54) hide
          (name "GND" (effects (font (size 1.27 1.27))))
          (number "11" (effects (font (size 1.27 1.27))))
        )
        (pin bidirectional line (at 19.05 -17.78 180) (length 2.54)
          (name "2B2" (effects (font (size 1.27 1.27))))
          (number "12" (effects (font (size 1.27 1.27))))
        )
        (pin bidirectional line (at 19.05 -15.24 180) (length 2.54)
          (name "2B1" (effects (font (size 1.27 1.27))))
          (number "13" (effects (font (size 1.27 1.27))))
        )
        (pin bidirectional line (at 19.05 -12.7 180) (length 2.54)
          (name "1B2" (effects (font (size 1.27 1.27))))
          (number "14" (effects (font (size 1.27 1.27))))
        )
        (pin bidirectional line (at 19.05 -10.16 180) (length 2.54)
          (name "1B1" (effects (font (size 1.27 1.27))))
          (number "15" (effects (font (size 1.27 1.27))))
        )
        (pin input line (at 0 -2.54 0) (length 2.54)
          (name "2~{OE}" (effects (font (size 1.27 1.27))))
          (number "16" (effects (font (size 1.27 1.27))))
        )
        (pin power_in line (at 19.05 2.54 180) (length 2.54)
          (name "VCCB" (effects (font (size 1.27 1.27))))
          (number "2" (effects (font (size 1.27 1.27))))
        )
        (pin power_in line (at 0 2.54 0) (length 2.54)
          (name "VCCA" (effects (font (size 1.27 1.27))))
          (number "3" (effects (font (size 1.27 1.27))))
        )
        (pin input line (at 0 -5.08 0) (length 2.54)
          (name "1DIR" (effects (font (size 1.27 1.27))))
          (number "4" (effects (font (size 1.27 1.27))))
        )
        (pin input line (at 0 -7.62 0) (length 2.54)
          (name "2DIR" (effects (font (size 1.27 1.27))))
          (number "5" (effects (font (size 1.27 1.27))))
        )
        (pin bidirectional line (at 0 -10.16 0) (length 2.54)
          (name "1A1" (effects (font (size 1.27 1.27))))
          (number "6" (effects (font (size 1.27 1.27))))
        )
        (pin bidirectional line (at 0 -12.7 0) (length 2.54)
          (name "1A2" (effects (font (size 1.27 1.27))))
          (number "7" (effects (font (size 1.27 1.27))))
        )
        (pin bidirectional line (at 0 -15.24 0) (length 2.54)
          (name "2A1" (effects (font (size 1.27 1.27))))
          (number "8" (effects (font (size 1.27 1.27))))
        )
        (pin bidirectional line (at 0 -17.78 0) (length 2.54)
          (name "2A2" (effects (font (size 1.27 1.27))))
          (number "9" (effects (font (size 1.27 1.27))))
        )
      )
    )
	(symbol "kria-k26-devboard:74LCX07_QFN" (in_bom yes) (on_board yes)
      (property "Reference" "U" (at 25.4 -2.54 0)
        (effects (font (size 1.27 1.27) (thickness 0.15)) (justify left bottom))
      )
      (property "Value" "74LCX07_QFN" (at 25.4 -5.08 0)
        (effects (font (size 1.27 1.27) (thickness 0.15)) (justify left bottom))
      )
      (property "Footprint" "kria-k26-devboard-footprints:QFN-14-1EP_2.5x3mm_EP1.15x1.65mm_ONSemi_MLP14A" (at 25.4 -7.62 0)
        (effects (font (size 1.27 1.27) (thickness 0.15)) (justify left bottom) hide)
      )
      (property "Datasheet" "https://www.mouser.com/datasheet/2/308/74LCX07_D-2309542.pdf" (at 25.4 -10.16 0)
        (effects (font (size 1.27 1.27) (thickness 0.15)) (justify left bottom) hide)
      )
      (property "Manufacturer" "ON Semiconductor" (at 25.4 -12.7 0)
        (effects (font (size 1.27 1.27) (thickness 0.15)) (justify left bottom) hide)
      )
      (property "MPN" "74LCX07BQX" (at 25.4 -15.24 0)
        (effects (font (size 1.27 1.27) (thickness 0.15)) (justify left bottom) hide)
      )
      (property "Author" "Antmicro" (at 25.4 -17.78 0)
        (effects (font (size 1.27 1.27) (thickness 0.15)) (justify left bottom) hide)
      )
      (property "License" "Apache-2.0" (at 25.4 -20.32 0)
        (effects (font (size 1.27 1.27) (thickness 0.15)) (justify left bottom) hide)
      )
      (property "ki_locked" "" (at 0 0 0)
        (effects (font (size 1.27 1.27)))
      )
      (property "ki_keywords" "SMT, LOGIC, IC, DRIVER" (at 0 0 0)
        (effects (font (size 1.27 1.27)) hide)
      )
      (property "ki_description" "Buffer, Non-Inverting 6 Element 1 Bit per Element Open Drain Output 14-DQFN (3x2.5)" (at 0 0 0)
        (effects (font (size 1.27 1.27)) hide)
      )
      (symbol "74LCX07_QFN_1_0"
        (pin input line (at 0 0 0) (length 2.54)
          (name "~" (effects (font (size 1.27 1.27))))
          (number "1" (effects (font (size 1.27 1.27))))
        )
        (pin open_collector line (at 10.16 0 180) (length 2.54)
          (name "~" (effects (font (size 1.27 1.27))))
          (number "2" (effects (font (size 1.27 1.27))))
        )
      )
      (symbol "74LCX07_QFN_1_1"
        (polyline
          (pts
            (xy 3.175 -0.635)
            (xy 4.445 -0.635)
          )
          (stroke (width 0.254) (type default))
          (fill (type background))
        )
        (polyline
          (pts
            (xy 2.54 2.54)
            (xy 7.62 0)
            (xy 2.54 -2.54)
            (xy 2.54 2.54)
          )
          (stroke (width 0.254) (type default))
          (fill (type background))
        )
        (polyline
          (pts
            (xy 3.175 0)
            (xy 3.81 0.635)
            (xy 4.445 0)
            (xy 3.81 -0.635)
            (xy 3.175 0)
          )
          (stroke (width 0.254) (type default))
          (fill (type background))
        )
      )
      (symbol "74LCX07_QFN_2_0"
        (pin input line (at 0 0 0) (length 2.54)
          (name "~" (effects (font (size 1.27 1.27))))
          (number "3" (effects (font (size 1.27 1.27))))
        )
        (pin open_collector line (at 10.16 0 180) (length 2.54)
          (name "~" (effects (font (size 1.27 1.27))))
          (number "4" (effects (font (size 1.27 1.27))))
        )
      )
      (symbol "74LCX07_QFN_2_1"
        (polyline
          (pts
            (xy 3.175 -0.635)
            (xy 4.445 -0.635)
          )
          (stroke (width 0.254) (type default))
          (fill (type background))
        )
        (polyline
          (pts
            (xy 2.54 2.54)
            (xy 7.62 0)
            (xy 2.54 -2.54)
            (xy 2.54 2.54)
          )
          (stroke (width 0.254) (type default))
          (fill (type background))
        )
        (polyline
          (pts
            (xy 3.175 0)
            (xy 3.81 0.635)
            (xy 4.445 0)
            (xy 3.81 -0.635)
            (xy 3.175 0)
          )
          (stroke (width 0.254) (type default))
          (fill (type background))
        )
      )
      (symbol "74LCX07_QFN_3_0"
        (pin input line (at 0 0 0) (length 2.54)
          (name "~" (effects (font (size 1.27 1.27))))
          (number "5" (effects (font (size 1.27 1.27))))
        )
        (pin open_collector line (at 10.16 0 180) (length 2.54)
          (name "~" (effects (font (size 1.27 1.27))))
          (number "6" (effects (font (size 1.27 1.27))))
        )
      )
      (symbol "74LCX07_QFN_3_1"
        (polyline
          (pts
            (xy 3.175 -0.635)
            (xy 4.445 -0.635)
          )
          (stroke (width 0.254) (type default))
          (fill (type background))
        )
        (polyline
          (pts
            (xy 2.54 2.54)
            (xy 7.62 0)
            (xy 2.54 -2.54)
            (xy 2.54 2.54)
          )
          (stroke (width 0.254) (type default))
          (fill (type background))
        )
        (polyline
          (pts
            (xy 3.175 0)
            (xy 3.81 0.635)
            (xy 4.445 0)
            (xy 3.81 -0.635)
            (xy 3.175 0)
          )
          (stroke (width 0.254) (type default))
          (fill (type background))
        )
      )
      (symbol "74LCX07_QFN_4_0"
        (pin open_collector line (at 10.16 0 180) (length 2.54)
          (name "~" (effects (font (size 1.27 1.27))))
          (number "8" (effects (font (size 1.27 1.27))))
        )
        (pin input line (at 0 0 0) (length 2.54)
          (name "~" (effects (font (size 1.27 1.27))))
          (number "9" (effects (font (size 1.27 1.27))))
        )
      )
      (symbol "74LCX07_QFN_4_1"
        (polyline
          (pts
            (xy 3.175 -0.635)
            (xy 4.445 -0.635)
          )
          (stroke (width 0.254) (type default))
          (fill (type background))
        )
        (polyline
          (pts
            (xy 2.54 2.54)
            (xy 7.62 0)
            (xy 2.54 -2.54)
            (xy 2.54 2.54)
          )
          (stroke (width 0.254) (type default))
          (fill (type background))
        )
        (polyline
          (pts
            (xy 3.175 0)
            (xy 3.81 0.635)
            (xy 4.445 0)
            (xy 3.81 -0.635)
            (xy 3.175 0)
          )
          (stroke (width 0.254) (type default))
          (fill (type background))
        )
      )
      (symbol "74LCX07_QFN_5_0"
        (pin open_collector line (at 10.16 0 180) (length 2.54)
          (name "~" (effects (font (size 1.27 1.27))))
          (number "10" (effects (font (size 1.27 1.27))))
        )
        (pin input line (at 0 0 0) (length 2.54)
          (name "~" (effects (font (size 1.27 1.27))))
          (number "11" (effects (font (size 1.27 1.27))))
        )
      )
      (symbol "74LCX07_QFN_5_1"
        (polyline
          (pts
            (xy 3.175 -0.635)
            (xy 4.445 -0.635)
          )
          (stroke (width 0.254) (type default))
          (fill (type background))
        )
        (polyline
          (pts
            (xy 2.54 2.54)
            (xy 7.62 0)
            (xy 2.54 -2.54)
            (xy 2.54 2.54)
          )
          (stroke (width 0.254) (type default))
          (fill (type background))
        )
        (polyline
          (pts
            (xy 3.175 0)
            (xy 3.81 0.635)
            (xy 4.445 0)
            (xy 3.81 -0.635)
            (xy 3.175 0)
          )
          (stroke (width 0.254) (type default))
          (fill (type background))
        )
      )
      (symbol "74LCX07_QFN_6_0"
        (pin open_collector line (at 10.16 0 180) (length 2.54)
          (name "~" (effects (font (size 1.27 1.27))))
          (number "12" (effects (font (size 1.27 1.27))))
        )
        (pin input line (at 0 0 0) (length 2.54)
          (name "~" (effects (font (size 1.27 1.27))))
          (number "13" (effects (font (size 1.27 1.27))))
        )
      )
      (symbol "74LCX07_QFN_6_1"
        (polyline
          (pts
            (xy 3.175 -0.635)
            (xy 4.445 -0.635)
          )
          (stroke (width 0.254) (type default))
          (fill (type background))
        )
        (polyline
          (pts
            (xy 2.54 2.54)
            (xy 7.62 0)
            (xy 2.54 -2.54)
            (xy 2.54 2.54)
          )
          (stroke (width 0.254) (type default))
          (fill (type background))
        )
        (polyline
          (pts
            (xy 3.175 0)
            (xy 3.81 0.635)
            (xy 4.445 0)
            (xy 3.81 -0.635)
            (xy 3.175 0)
          )
          (stroke (width 0.254) (type default))
          (fill (type background))
        )
      )
      (symbol "74LCX07_QFN_7_0"
        (pin power_in line (at 0 0 0) (length 2.54)
          (name "VCC" (effects (font (size 1.27 1.27))))
          (number "14" (effects (font (size 1.27 1.27))))
        )
        (pin no_connect line (at 2.54 -2.54 0) (length 2.54) hide
          (name "DAP" (effects (font (size 1.27 1.27))))
          (number "15" (effects (font (size 1.27 1.27))))
        )
        (pin power_in line (at 0 -5.08 0) (length 2.54)
          (name "GND" (effects (font (size 1.27 1.27))))
          (number "7" (effects (font (size 1.27 1.27))))
        )
      )
      (symbol "74LCX07_QFN_7_1"
        (rectangle (start 2.54 2.54) (end 10.16 -7.62)
          (stroke (width 0.254) (type default))
          (fill (type background))
        )
      )
    )
	(symbol "kria-k26-devboard:82400152" (in_bom yes) (on_board yes)
      (property "Reference" "U" (at 30.48 -5.08 0)
        (effects (font (size 1.27 1.27) (thickness 0.15)) (justify left bottom))
      )
      (property "Value" "82400152" (at 30.48 -7.62 0)
        (effects (font (size 1.27 1.27) (thickness 0.15)) (justify left bottom))
      )
      (property "Footprint" "kria-k26-devboard-footprints:SOT-563" (at 30.48 -10.16 0)
        (effects (font (size 1.27 1.27) (thickness 0.15)) (justify left bottom) hide)
      )
      (property "Datasheet" "https://www.we-online.com/components/products/datasheet/82400152.pdf" (at 30.48 -12.7 0)
        (effects (font (size 1.27 1.27) (thickness 0.15)) (justify left bottom) hide)
      )
      (property "MPN" "82400152" (at 30.48 -15.24 0)
        (effects (font (size 1.27 1.27) (thickness 0.15)) (justify left bottom) hide)
      )
      (property "Manufacturer" "Würth Elektronik" (at 30.48 -17.78 0)
        (effects (font (size 1.27 1.27) (thickness 0.15)) (justify left bottom) hide)
      )
      (property "Author" "Antmicro" (at 30.48 -20.32 0)
        (effects (font (size 1.27 1.27) (thickness 0.15)) (justify left bottom) hide)
      )
      (property "License" "Apache-2.0" (at 30.48 -22.86 0)
        (effects (font (size 1.27 1.27) (thickness 0.15)) (justify left bottom) hide)
      )
      (property "ki_keywords" "ESD Protection TVS High-speed USB" (at 0 0 0)
        (effects (font (size 1.27 1.27)) hide)
      )
      (property "ki_description" "Low Capacitance TVS Diode Array, 2 Channels, SOT563" (at 0 0 0)
        (effects (font (size 1.27 1.27)) hide)
      )
      (property "ki_fp_filters" "SOT?23*" (at 0 0 0)
        (effects (font (size 1.27 1.27)) hide)
      )
      (symbol "82400152_1_1"
        (polyline
          (pts
            (xy 2.54 -5.08)
            (xy 12.7 -5.08)
          )
          (stroke (width 0.254) (type default))
          (fill (type background))
        )
        (polyline
          (pts
            (xy 2.54 0)
            (xy 12.7 0)
          )
          (stroke (width 0.254) (type default))
          (fill (type background))
        )
        (polyline
          (pts
            (xy 3.556 -2.54)
            (xy 2.54 -2.54)
          )
          (stroke (width 0.254) (type default))
          (fill (type background))
        )
        (polyline
          (pts
            (xy 3.556 -2.54)
            (xy 9.906 -2.54)
          )
          (stroke (width 0.254) (type default))
          (fill (type background))
        )
        (polyline
          (pts
            (xy 5.461 -3.556)
            (xy 5.461 -4.826)
          )
          (stroke (width 0.254) (type default))
          (fill (type background))
        )
        (polyline
          (pts
            (xy 5.461 -0.254)
            (xy 5.461 -1.524)
          )
          (stroke (width 0.254) (type default))
          (fill (type background))
        )
        (polyline
          (pts
            (xy 6.731 -4.191)
            (xy 6.731 -4.953)
          )
          (stroke (width 0.254) (type default))
          (fill (type background))
        )
        (polyline
          (pts
            (xy 6.731 -0.889)
            (xy 6.731 0)
          )
          (stroke (width 0.254) (type default))
          (fill (type background))
        )
        (polyline
          (pts
            (xy 7.112 -3.175)
            (xy 7.112 -3.175)
          )
          (stroke (width 0.254) (type default))
          (fill (type background))
        )
        (polyline
          (pts
            (xy 9.271 -3.556)
            (xy 9.271 -4.826)
          )
          (stroke (width 0.254) (type default))
          (fill (type background))
        )
        (polyline
          (pts
            (xy 9.271 -0.254)
            (xy 9.271 -1.524)
          )
          (stroke (width 0.254) (type default))
          (fill (type background))
        )
        (polyline
          (pts
            (xy 9.906 -2.54)
            (xy 12.7 -2.54)
          )
          (stroke (width 0.254) (type default))
          (fill (type background))
        )
        (polyline
          (pts
            (xy 10.795 -1.905)
            (xy 10.795 -3.175)
          )
          (stroke (width 0.254) (type default))
          (fill (type background))
        )
        (polyline
          (pts
            (xy 4.191 -3.556)
            (xy 4.191 -4.826)
            (xy 5.461 -4.191)
            (xy 4.191 -3.556)
          )
          (stroke (width 0.254) (type default))
          (fill (type background))
        )
        (polyline
          (pts
            (xy 4.191 -1.524)
            (xy 4.191 -0.254)
            (xy 5.461 -0.889)
            (xy 4.191 -1.524)
          )
          (stroke (width 0.254) (type default))
          (fill (type background))
        )
        (polyline
          (pts
            (xy 6.096 -1.905)
            (xy 6.096 -3.175)
            (xy 7.366 -2.54)
            (xy 6.096 -1.905)
          )
          (stroke (width 0.254) (type default))
          (fill (type background))
        )
        (polyline
          (pts
            (xy 7.62 -1.905)
            (xy 7.366 -2.159)
            (xy 7.366 -2.921)
            (xy 7.112 -3.175)
          )
          (stroke (width 0.254) (type default))
          (fill (type background))
        )
        (polyline
          (pts
            (xy 8.001 -3.556)
            (xy 8.001 -4.826)
            (xy 9.271 -4.191)
            (xy 8.001 -3.556)
          )
          (stroke (width 0.254) (type default))
          (fill (type background))
        )
        (polyline
          (pts
            (xy 8.001 -1.524)
            (xy 8.001 -0.254)
            (xy 9.271 -0.889)
            (xy 8.001 -1.524)
          )
          (stroke (width 0.254) (type default))
          (fill (type background))
        )
        (polyline
          (pts
            (xy 12.065 -1.905)
            (xy 12.065 -3.175)
            (xy 10.795 -2.54)
            (xy 12.065 -1.905)
          )
          (stroke (width 0.254) (type default))
          (fill (type background))
        )
        (rectangle (start 2.54 1.27) (end 12.7 -6.35)
          (stroke (width 0.254) (type default))
          (fill (type background))
        )
        (circle (center 3.556 -2.54) (radius 0.127)
          (stroke (width 0.254) (type default))
          (fill (type background))
        )
        (rectangle (start 3.556 -0.889) (end 9.906 -4.191)
          (stroke (width 0.254) (type default))
          (fill (type background))
        )
        (circle (center 6.731 -5.08) (radius 0.127)
          (stroke (width 0.254) (type default))
          (fill (type background))
        )
        (circle (center 6.731 -4.191) (radius 0.127)
          (stroke (width 0.254) (type default))
          (fill (type background))
        )
        (circle (center 6.731 -0.889) (radius 0.127)
          (stroke (width 0.254) (type default))
          (fill (type background))
        )
        (circle (center 6.731 0) (radius 0.127)
          (stroke (width 0.254) (type default))
          (fill (type background))
        )
        (circle (center 9.906 -2.54) (radius 0.127)
          (stroke (width 0.254) (type default))
          (fill (type background))
        )
        (pin passive line (at 0 0 0) (length 2.54)
          (name "~" (effects (font (size 1.27 1.27))))
          (number "1" (effects (font (size 1.27 1.27))))
        )
        (pin passive line (at 0 -2.54 0) (length 2.54)
          (name "~" (effects (font (size 1.27 1.27))))
          (number "2" (effects (font (size 1.27 1.27))))
        )
        (pin passive line (at 0 -5.08 0) (length 2.54)
          (name "~" (effects (font (size 1.27 1.27))))
          (number "3" (effects (font (size 1.27 1.27))))
        )
        (pin passive line (at 15.24 -5.08 180) (length 2.54)
          (name "~" (effects (font (size 1.27 1.27))))
          (number "4" (effects (font (size 1.27 1.27))))
        )
        (pin passive line (at 15.24 -2.54 180) (length 2.54)
          (name "~" (effects (font (size 1.27 1.27))))
          (number "5" (effects (font (size 1.27 1.27))))
        )
        (pin passive line (at 15.24 0 180) (length 2.54)
          (name "~" (effects (font (size 1.27 1.27))))
          (number "6" (effects (font (size 1.27 1.27))))
        )
      )
    )
	(symbol "kria-k26-devboard:824012823" (in_bom yes) (on_board yes)
      (property "Reference" "U" (at 30.48 -5.08 0)
        (effects (font (size 1.27 1.27) (thickness 0.15)) (justify left bottom))
      )
      (property "Value" "824012823" (at 30.48 -7.62 0)
        (effects (font (size 1.27 1.27) (thickness 0.15)) (justify left bottom))
      )
      (property "Footprint" "kria-k26-devboard-footprints:DFN1210-6" (at 30.48 -10.16 0)
        (effects (font (size 1.27 1.27) (thickness 0.15)) (justify left bottom) hide)
      )
      (property "Datasheet" "https://www.we-online.com/catalog/datasheet/824012823.pdf" (at 30.48 -12.7 0)
        (effects (font (size 1.27 1.27) (thickness 0.15)) (justify left bottom) hide)
      )
      (property "MPN" "824012823" (at 30.48 -15.24 0)
        (effects (font (size 1.27 1.27) (thickness 0.15)) (justify left bottom) hide)
      )
      (property "Manufacturer" "Würth Elektronik" (at 30.48 -17.78 0)
        (effects (font (size 1.27 1.27) (thickness 0.15)) (justify left bottom) hide)
      )
      (property "Author" "Antmicro" (at 30.48 -20.32 0)
        (effects (font (size 1.27 1.27) (thickness 0.15)) (justify left bottom) hide)
      )
      (property "License" "Apache-2.0" (at 30.48 -22.86 0)
        (effects (font (size 1.27 1.27) (thickness 0.15)) (justify left bottom) hide)
      )
      (property "ki_keywords" "ESD Protection TVS USB 3.1 Gen1&2 (5Gb/s, 10Gb/s), USB 3.1 Type C, Display Port (1.1, 1.2, 1.3, 1.4), HDMI 2.0" (at 0 0 0)
        (effects (font (size 1.27 1.27)) hide)
      )
      (property "ki_description" "Low Capacitance TVS Diode Array, 2 Channels, DFN1210-6L" (at 0 0 0)
        (effects (font (size 1.27 1.27)) hide)
      )
      (property "ki_fp_filters" "SOT?23*" (at 0 0 0)
        (effects (font (size 1.27 1.27)) hide)
      )
      (symbol "824012823_1_1"
        (polyline
          (pts
            (xy 6.35 -3.048)
            (xy 6.35 -4.318)
          )
          (stroke (width 0.254) (type default))
          (fill (type background))
        )
        (polyline
          (pts
            (xy 6.35 -0.508)
            (xy 6.35 -1.778)
          )
          (stroke (width 0.254) (type default))
          (fill (type background))
        )
        (polyline
          (pts
            (xy 7.874 -5.715)
            (xy 7.874 -5.715)
          )
          (stroke (width 0.254) (type default))
          (fill (type background))
        )
        (polyline
          (pts
            (xy 10.16 -3.048)
            (xy 10.16 -4.318)
          )
          (stroke (width 0.254) (type default))
          (fill (type background))
        )
        (polyline
          (pts
            (xy 10.16 -0.508)
            (xy 10.16 -1.778)
          )
          (stroke (width 0.254) (type default))
          (fill (type background))
        )
        (polyline
          (pts
            (xy 5.08 -3.048)
            (xy 5.08 -4.318)
            (xy 6.35 -3.683)
            (xy 5.08 -3.048)
          )
          (stroke (width 0.254) (type default))
          (fill (type background))
        )
        (polyline
          (pts
            (xy 5.08 -1.778)
            (xy 5.08 -0.508)
            (xy 6.35 -1.143)
            (xy 5.08 -1.778)
          )
          (stroke (width 0.254) (type default))
          (fill (type background))
        )
        (polyline
          (pts
            (xy 6.858 -4.445)
            (xy 6.858 -5.715)
            (xy 8.128 -5.08)
            (xy 6.858 -4.445)
          )
          (stroke (width 0.254) (type default))
          (fill (type background))
        )
        (polyline
          (pts
            (xy 8.382 -4.445)
            (xy 8.128 -4.699)
            (xy 8.128 -5.461)
            (xy 7.874 -5.715)
          )
          (stroke (width 0.254) (type default))
          (fill (type background))
        )
        (polyline
          (pts
            (xy 8.89 -3.048)
            (xy 8.89 -4.318)
            (xy 10.16 -3.683)
            (xy 8.89 -3.048)
          )
          (stroke (width 0.254) (type default))
          (fill (type background))
        )
        (polyline
          (pts
            (xy 8.89 -1.778)
            (xy 8.89 -0.508)
            (xy 10.16 -1.143)
            (xy 8.89 -1.778)
          )
          (stroke (width 0.254) (type default))
          (fill (type background))
        )
        (rectangle (start 2.54 -5.08) (end 4.445 -5.08)
          (stroke (width 0.254) (type default))
          (fill (type background))
        )
        (rectangle (start 2.54 -2.54) (end 7.62 -2.54)
          (stroke (width 0.254) (type default))
          (fill (type background))
        )
        (rectangle (start 2.54 0) (end 7.62 0)
          (stroke (width 0.254) (type default))
          (fill (type background))
        )
        (rectangle (start 2.54 1.27) (end 12.7 -7.62)
          (stroke (width 0.254) (type default))
          (fill (type background))
        )
        (rectangle (start 4.445 -6.604) (end 4.445 -6.223)
          (stroke (width 0.254) (type default))
          (fill (type background))
        )
        (rectangle (start 4.445 -6.604) (end 4.826 -6.604)
          (stroke (width 0.254) (type default))
          (fill (type background))
        )
        (rectangle (start 4.445 -5.842) (end 4.445 -5.461)
          (stroke (width 0.254) (type default))
          (fill (type background))
        )
        (circle (center 4.445 -5.08) (radius 0.127)
          (stroke (width 0.254) (type default))
          (fill (type background))
        )
        (rectangle (start 4.445 -5.08) (end 6.858 -5.08)
          (stroke (width 0.254) (type default))
          (fill (type background))
        )
        (rectangle (start 4.445 -3.683) (end 4.445 -5.08)
          (stroke (width 0.254) (type default))
          (fill (type background))
        )
        (circle (center 4.445 -3.683) (radius 0.127)
          (stroke (width 0.254) (type default))
          (fill (type background))
        )
        (rectangle (start 4.445 -3.683) (end 5.08 -3.683)
          (stroke (width 0.254) (type default))
          (fill (type background))
        )
        (rectangle (start 4.445 -1.143) (end 4.445 -3.683)
          (stroke (width 0.254) (type default))
          (fill (type background))
        )
        (rectangle (start 5.08 -1.143) (end 4.445 -1.143)
          (stroke (width 0.254) (type default))
          (fill (type background))
        )
        (rectangle (start 5.207 -6.604) (end 5.588 -6.604)
          (stroke (width 0.254) (type default))
          (fill (type background))
        )
        (rectangle (start 5.969 -6.604) (end 6.35 -6.604)
          (stroke (width 0.254) (type default))
          (fill (type background))
        )
        (rectangle (start 6.35 -3.683) (end 8.89 -3.683)
          (stroke (width 0.254) (type default))
          (fill (type background))
        )
        (rectangle (start 6.35 -1.143) (end 7.62 -1.143)
          (stroke (width 0.254) (type default))
          (fill (type background))
        )
        (rectangle (start 6.731 -6.604) (end 7.112 -6.604)
          (stroke (width 0.254) (type default))
          (fill (type background))
        )
        (rectangle (start 7.493 -6.604) (end 7.874 -6.604)
          (stroke (width 0.254) (type default))
          (fill (type background))
        )
        (circle (center 7.62 -3.683) (radius 0.127)
          (stroke (width 0.254) (type default))
          (fill (type background))
        )
        (rectangle (start 7.62 -2.54) (end 7.62 -3.683)
          (stroke (width 0.254) (type default))
          (fill (type background))
        )
        (circle (center 7.62 -2.54) (radius 0.127)
          (stroke (width 0.254) (type default))
          (fill (type background))
        )
        (circle (center 7.62 -1.143) (radius 0.127)
          (stroke (width 0.254) (type default))
          (fill (type background))
        )
        (rectangle (start 7.62 -1.143) (end 8.89 -1.143)
          (stroke (width 0.254) (type default))
          (fill (type background))
        )
        (rectangle (start 7.62 -1.016) (end 7.62 0)
          (stroke (width 0.254) (type default))
          (fill (type background))
        )
        (circle (center 7.62 0) (radius 0.127)
          (stroke (width 0.254) (type default))
          (fill (type background))
        )
        (rectangle (start 8.001 -2.54) (end 8.382 -2.54)
          (stroke (width 0.254) (type default))
          (fill (type background))
        )
        (rectangle (start 8.001 0) (end 8.382 0)
          (stroke (width 0.254) (type default))
          (fill (type background))
        )
        (rectangle (start 8.128 -5.08) (end 10.541 -5.08)
          (stroke (width 0.254) (type default))
          (fill (type background))
        )
        (rectangle (start 8.255 -6.604) (end 8.636 -6.604)
          (stroke (width 0.254) (type default))
          (fill (type background))
        )
        (rectangle (start 8.763 -2.54) (end 9.144 -2.54)
          (stroke (width 0.254) (type default))
          (fill (type background))
        )
        (rectangle (start 8.763 0) (end 9.144 0)
          (stroke (width 0.254) (type default))
          (fill (type background))
        )
        (rectangle (start 9.017 -6.604) (end 9.398 -6.604)
          (stroke (width 0.254) (type default))
          (fill (type background))
        )
        (rectangle (start 9.525 -2.54) (end 9.906 -2.54)
          (stroke (width 0.254) (type default))
          (fill (type background))
        )
        (rectangle (start 9.525 0) (end 9.906 0)
          (stroke (width 0.254) (type default))
          (fill (type background))
        )
        (rectangle (start 9.779 -6.604) (end 10.16 -6.604)
          (stroke (width 0.254) (type default))
          (fill (type background))
        )
        (rectangle (start 10.16 -3.683) (end 10.795 -3.683)
          (stroke (width 0.254) (type default))
          (fill (type background))
        )
        (rectangle (start 10.16 -1.143) (end 10.795 -1.143)
          (stroke (width 0.254) (type default))
          (fill (type background))
        )
        (rectangle (start 10.287 -2.54) (end 10.668 -2.54)
          (stroke (width 0.254) (type default))
          (fill (type background))
        )
        (rectangle (start 10.287 0) (end 10.668 0)
          (stroke (width 0.254) (type default))
          (fill (type background))
        )
        (rectangle (start 10.541 -6.604) (end 10.922 -6.604)
          (stroke (width 0.254) (type default))
          (fill (type background))
        )
        (rectangle (start 10.541 -5.08) (end 10.795 -5.08)
          (stroke (width 0.254) (type default))
          (fill (type background))
        )
        (rectangle (start 10.795 -3.683) (end 10.795 -5.08)
          (stroke (width 0.254) (type default))
          (fill (type background))
        )
        (rectangle (start 10.795 -3.683) (end 10.795 -1.143)
          (stroke (width 0.254) (type default))
          (fill (type background))
        )
        (circle (center 10.795 -3.683) (radius 0.127)
          (stroke (width 0.254) (type default))
          (fill (type background))
        )
        (rectangle (start 11.049 -2.54) (end 11.43 -2.54)
          (stroke (width 0.254) (type default))
          (fill (type background))
        )
        (rectangle (start 11.049 0) (end 11.43 0)
          (stroke (width 0.254) (type default))
          (fill (type background))
        )
        (rectangle (start 11.303 -6.604) (end 11.684 -6.604)
          (stroke (width 0.254) (type default))
          (fill (type background))
        )
        (rectangle (start 11.684 -6.604) (end 11.684 -6.223)
          (stroke (width 0.254) (type default))
          (fill (type background))
        )
        (rectangle (start 11.684 -5.842) (end 11.684 -5.461)
          (stroke (width 0.254) (type default))
          (fill (type background))
        )
        (rectangle (start 11.684 -5.08) (end 12.065 -5.08)
          (stroke (width 0.254) (type default))
          (fill (type background))
        )
        (rectangle (start 11.811 -2.54) (end 12.192 -2.54)
          (stroke (width 0.254) (type default))
          (fill (type background))
        )
        (rectangle (start 11.811 0) (end 12.192 0)
          (stroke (width 0.254) (type default))
          (fill (type background))
        )
        (rectangle (start 12.446 -5.08) (end 12.827 -5.08)
          (stroke (width 0.254) (type default))
          (fill (type background))
        )
        (pin passive line (at 0 0 0) (length 2.54)
          (name "~" (effects (font (size 1.27 1.27))))
          (number "1" (effects (font (size 1.27 1.27))))
        )
        (pin passive line (at 0 -2.54 0) (length 2.54)
          (name "~" (effects (font (size 1.27 1.27))))
          (number "2" (effects (font (size 1.27 1.27))))
        )
        (pin passive line (at 0 -5.08 0) (length 2.54)
          (name "~" (effects (font (size 1.27 1.27))))
          (number "3" (effects (font (size 1.27 1.27))))
        )
        (pin passive line (at 15.24 -5.08 180) (length 2.54)
          (name "~" (effects (font (size 1.27 1.27))))
          (number "4" (effects (font (size 1.27 1.27))))
        )
        (pin passive line (at 15.24 -2.54 180) (length 2.54)
          (name "~" (effects (font (size 1.27 1.27))))
          (number "5" (effects (font (size 1.27 1.27))))
        )
        (pin passive line (at 15.24 0 180) (length 2.54)
          (name "~" (effects (font (size 1.27 1.27))))
          (number "6" (effects (font (size 1.27 1.27))))
        )
      )
    )
	(symbol "kria-k26-devboard:93LC66BT_DFN" (in_bom yes) (on_board yes)
      (property "Reference" "U" (at 35.56 -2.54 0)
        (effects (font (size 1.27 1.27) (thickness 0.15)) (justify left bottom))
      )
      (property "Value" "93LC66BT_DFN" (at 35.56 -5.08 0)
        (effects (font (size 1.27 1.27) (thickness 0.15)) (justify left bottom))
      )
      (property "Footprint" "kria-k26-devboard-footprints:DFN-8-1EP_3x2mm_P0.5mm_EP1.36x1.46mm" (at 35.56 -7.62 0)
        (effects (font (size 1.27 1.27) (thickness 0.15)) (justify left bottom) hide)
      )
      (property "Datasheet" "https://www.mouser.com/datasheet/2/268/21795C-64371.pdf" (at 35.56 -10.16 0)
        (effects (font (size 1.27 1.27) (thickness 0.15)) (justify left bottom) hide)
      )
      (property "MPN" "93LC66BT-I/MC" (at 35.56 -19.05 0)
        (effects (font (size 1.27 1.27)) (justify left) hide)
      )
      (property "Manufacturer" "Microchip Technology" (at 35.56 -16.51 0)
        (effects (font (size 1.27 1.27)) (justify left) hide)
      )
      (property "Author" "Antmicro" (at 35.56 -12.7 0)
        (effects (font (size 1.27 1.27) (thickness 0.15)) (justify left bottom) hide)
      )
      (property "License" "Apache-2.0" (at 35.56 -15.24 0)
        (effects (font (size 1.27 1.27) (thickness 0.15)) (justify left bottom) hide)
      )
      (property "ki_keywords" "SMT, MEMORY, IC, EEPROM" (at 0 0 0)
        (effects (font (size 1.27 1.27)) hide)
      )
      (property "ki_description" "EEPROM, 4 Kbit, 256 x 16bit, Serial Microwire, 2 MHz, DFN-EP-8" (at 0 0 0)
        (effects (font (size 1.27 1.27)) hide)
      )
      (property "ki_fp_filters" "DIP*W7.62mm* SOIC*3.9x4.9mm*" (at 0 0 0)
        (effects (font (size 1.27 1.27)) hide)
      )
      (symbol "93LC66BT_DFN_1_1"
        (rectangle (start 2.54 2.54) (end 17.78 -12.7)
          (stroke (width 0.254) (type default))
          (fill (type background))
        )
        (pin input line (at 20.32 0 180) (length 2.54)
          (name "CS" (effects (font (size 1.27 1.27))))
          (number "1" (effects (font (size 1.27 1.27))))
        )
        (pin input line (at 20.32 -2.54 180) (length 2.54)
          (name "SCLK" (effects (font (size 1.27 1.27))))
          (number "2" (effects (font (size 1.27 1.27))))
        )
        (pin input line (at 20.32 -5.08 180) (length 2.54)
          (name "DI" (effects (font (size 1.27 1.27))))
          (number "3" (effects (font (size 1.27 1.27))))
        )
        (pin tri_state line (at 20.32 -7.62 180) (length 2.54)
          (name "DO" (effects (font (size 1.27 1.27))))
          (number "4" (effects (font (size 1.27 1.27))))
        )
        (pin power_in line (at 0 -10.16 0) (length 2.54)
          (name "GND" (effects (font (size 1.27 1.27))))
          (number "5" (effects (font (size 1.27 1.27))))
        )
        (pin input line (at 0 -5.08 0) (length 2.54)
          (name "ORG" (effects (font (size 1.27 1.27))))
          (number "6" (effects (font (size 1.27 1.27))))
        )
        (pin no_connect line (at 2.54 -2.54 0) (length 2.54) hide
          (name "NC" (effects (font (size 1.27 1.27))))
          (number "7" (effects (font (size 1.27 1.27))))
        )
        (pin power_in line (at 0 0 0) (length 2.54)
          (name "VCC" (effects (font (size 1.27 1.27))))
          (number "8" (effects (font (size 1.27 1.27))))
        )
        (pin passive line (at 0 -7.62 0) (length 2.54)
          (name "EP" (effects (font (size 1.27 1.27))))
          (number "9" (effects (font (size 1.27 1.27))))
        )
      )
    )
	(symbol "kria-k26-devboard:AO3401A" (pin_names (offset 0)) (in_bom yes) (on_board yes)
      (property "Reference" "Q" (at 22.86 -6.35 0)
        (effects (font (size 1.27 1.27) (thickness 0.15)) (justify left bottom))
      )
      (property "Value" "AO3401A" (at 22.86 -8.89 0)
        (effects (font (size 1.27 1.27) (thickness 0.15)) (justify left bottom))
      )
      (property "Footprint" "kria-k26-devboard-footprints:SOT-23-3" (at 22.86 -11.43 0)
        (effects (font (size 1.27 1.27) (thickness 0.15)) (justify left bottom) hide)
      )
      (property "Datasheet" "http://aosmd.com/res/data_sheets/AO3401A.pdf" (at 22.86 -13.97 0)
        (effects (font (size 1.27 1.27) (thickness 0.15)) (justify left bottom) hide)
      )
      (property "MPN" "AO3401A" (at 22.86 -16.51 0)
        (effects (font (size 1.27 1.27) (thickness 0.15)) (justify left bottom) hide)
      )
      (property "Manufacturer" "Alpha & Omega Semiconductor Inc." (at 22.86 -19.05 0)
        (effects (font (size 1.27 1.27) (thickness 0.15)) (justify left bottom) hide)
      )
      (property "Author" "Antmicro" (at 22.86 -21.59 0)
        (effects (font (size 1.27 1.27) (thickness 0.15)) (justify left bottom) hide)
      )
      (property "License" "Apache-2.0" (at 22.86 -24.13 0)
        (effects (font (size 1.27 1.27) (thickness 0.15)) (justify left bottom) hide)
      )
      (symbol "AO3401A_1_1"
        (polyline
          (pts
            (xy 5.08 1.143)
            (xy 5.08 0.635)
          )
          (stroke (width 0.254) (type default))
          (fill (type background))
        )
        (polyline
          (pts
            (xy 5.08 1.143)
            (xy 5.08 1.651)
          )
          (stroke (width 0.254) (type default))
          (fill (type background))
        )
        (polyline
          (pts
            (xy 5.08 2.54)
            (xy 5.08 2.032)
          )
          (stroke (width 0.254) (type default))
          (fill (type background))
        )
        (polyline
          (pts
            (xy 5.08 2.54)
            (xy 5.08 3.048)
          )
          (stroke (width 0.254) (type default))
          (fill (type background))
        )
        (polyline
          (pts
            (xy 5.08 4.445)
            (xy 5.08 3.429)
          )
          (stroke (width 0.254) (type default))
          (fill (type background))
        )
        (polyline
          (pts
            (xy 7.62 1.143)
            (xy 5.08 1.143)
          )
          (stroke (width 0.254) (type default))
          (fill (type background))
        )
        (polyline
          (pts
            (xy 9.144 2.2352)
            (xy 8.128 2.2352)
          )
          (stroke (width 0.254) (type default))
          (fill (type background))
        )
        (polyline
          (pts
            (xy 2.54 0)
            (xy 4.572 0)
            (xy 4.572 3.937)
          )
          (stroke (width 0.254) (type default))
          (fill (type none))
        )
        (polyline
          (pts
            (xy 7.62 -1.27)
            (xy 7.62 2.54)
            (xy 5.08 2.54)
          )
          (stroke (width 0.254) (type default))
          (fill (type none))
        )
        (polyline
          (pts
            (xy 7.62 6.35)
            (xy 7.62 3.937)
            (xy 5.08 3.937)
          )
          (stroke (width 0.254) (type default))
          (fill (type none))
        )
        (polyline
          (pts
            (xy 7.239 2.54)
            (xy 6.477 3.048)
            (xy 6.477 2.032)
            (xy 7.239 2.54)
          )
          (stroke (width 0.254) (type default))
          (fill (type outline))
        )
        (polyline
          (pts
            (xy 8.636 2.286)
            (xy 8.128 3.048)
            (xy 9.144 3.048)
            (xy 8.636 2.286)
          )
          (stroke (width 0.254) (type default))
          (fill (type outline))
        )
        (polyline
          (pts
            (xy 7.493 0.635)
            (xy 8.636 0.635)
            (xy 8.636 3.937)
            (xy 8.636 4.445)
            (xy 7.493 4.445)
          )
          (stroke (width 0.254) (type default))
          (fill (type background))
        )
        (circle (center 6.35 2.54) (radius 3.302)
          (stroke (width 0.254) (type default))
          (fill (type background))
        )
        (circle (center 7.62 0.635) (radius 0.127)
          (stroke (width 0.254) (type default))
          (fill (type background))
        )
        (circle (center 7.62 1.143) (radius 0.127)
          (stroke (width 0.254) (type default))
          (fill (type background))
        )
        (circle (center 7.62 4.445) (radius 0.127)
          (stroke (width 0.254) (type default))
          (fill (type background))
        )
        (pin bidirectional line (at 0 0 0) (length 2.54)
          (name "G" (effects (font (size 1.27 1.27))))
          (number "1" (effects (font (size 1.27 1.27))))
        )
        (pin bidirectional line (at 7.62 -3.81 90) (length 2.54)
          (name "S" (effects (font (size 1.27 1.27))))
          (number "2" (effects (font (size 1.27 1.27))))
        )
        (pin bidirectional line (at 7.62 8.89 270) (length 2.54)
          (name "D" (effects (font (size 1.27 1.27))))
          (number "3" (effects (font (size 1.27 1.27))))
        )
      )
    )
	(symbol "kria-k26-devboard:AP62301_TSOT" (in_bom yes) (on_board yes)
      (property "Reference" "U" (at 35.56 -2.54 0)
        (effects (font (size 1.27 1.27) (thickness 0.15)) (justify left bottom))
      )
      (property "Value" "AP62301_TSOT" (at 35.56 -7.62 0)
        (effects (font (size 1.27 1.27) (thickness 0.15)) (justify left bottom) hide)
      )
      (property "Footprint" "kria-k26-devboard-footprints:TSOT23-6" (at 35.56 -10.16 0)
        (effects (font (size 1.27 1.27) (thickness 0.15)) (justify left bottom) hide)
      )
      (property "Datasheet" "https://www.diodes.com/assets/Datasheets/AP62300_AP62301_AP62300T.pdf" (at 35.56 -12.7 0)
        (effects (font (size 1.27 1.27) (thickness 0.15)) (justify left bottom) hide)
      )
      (property "MPN" "AP62301WU-7" (at 35.56 -5.08 0)
        (effects (font (size 1.27 1.27) (thickness 0.15)) (justify left bottom))
      )
      (property "Manufacturer" "Diodes Incorporated" (at 35.56 -15.24 0)
        (effects (font (size 1.27 1.27) (thickness 0.15)) (justify left bottom) hide)
      )
      (property "Author" "Antmicro" (at 35.56 -17.78 0)
        (effects (font (size 1.27 1.27) (thickness 0.15)) (justify left bottom) hide)
      )
      (property "License" "Apache-2.0" (at 35.56 -20.32 0)
        (effects (font (size 1.27 1.27) (thickness 0.15)) (justify left bottom) hide)
      )
      (property "ki_keywords" "SMT, PMIC, IC, VOLTAGE" (at 0 0 0)
        (effects (font (size 1.27 1.27)) hide)
      )
      (property "ki_description" "DC-DC Switching Synchronous Buck Regulator, Adjustable, 4.2V-18Vin, 0.8V-7V/3A out, TSOT-26-6" (at 0 0 0)
        (effects (font (size 1.27 1.27)) hide)
      )
      (symbol "AP62301_TSOT_1_1"
        (rectangle (start 2.54 2.54) (end 17.78 -12.7)
          (stroke (width 0.254) (type default))
          (fill (type background))
        )
        (pin power_in line (at 0 -10.16 0) (length 2.54)
          (name "GND" (effects (font (size 1.27 1.27))))
          (number "1" (effects (font (size 1.27 1.27))))
        )
        (pin power_out line (at 20.32 0 180) (length 2.54)
          (name "SW" (effects (font (size 1.27 1.27))))
          (number "2" (effects (font (size 1.27 1.27))))
        )
        (pin power_in line (at 0 0 0) (length 2.54)
          (name "VIN" (effects (font (size 1.27 1.27))))
          (number "3" (effects (font (size 1.27 1.27))))
        )
        (pin input line (at 20.32 -10.16 180) (length 2.54)
          (name "FB" (effects (font (size 1.27 1.27))))
          (number "4" (effects (font (size 1.27 1.27))))
        )
        (pin input line (at 0 -5.08 0) (length 2.54)
          (name "EN" (effects (font (size 1.27 1.27))))
          (number "5" (effects (font (size 1.27 1.27))))
        )
        (pin output line (at 20.32 -5.08 180) (length 2.54)
          (name "BST" (effects (font (size 1.27 1.27))))
          (number "6" (effects (font (size 1.27 1.27))))
        )
      )
    )
	(symbol "kria-k26-devboard:AP7340-18FS4-7" (in_bom yes) (on_board yes)
      (property "Reference" "U" (at 30.48 -2.54 0)
        (effects (font (size 1.27 1.27) (thickness 0.15)) (justify left bottom))
      )
      (property "Value" "AP7340-18FS4-7" (at 30.48 -5.08 0)
        (effects (font (size 1.27 1.27) (thickness 0.15)) (justify left bottom))
      )
      (property "Footprint" "kria-k26-devboard-footprints:XDFN4" (at 30.48 -7.62 0)
        (effects (font (size 1.27 1.27) (thickness 0.15)) (justify left bottom) hide)
      )
      (property "Datasheet" "https://www.diodes.com/assets/Datasheets/AP7340.pdf" (at 30.48 -10.16 0)
        (effects (font (size 1.27 1.27) (thickness 0.15)) (justify left bottom) hide)
      )
      (property "MPN" "AP7340-18FS4-7" (at 30.48 -12.7 0)
        (effects (font (size 1.27 1.27) (thickness 0.15)) (justify left bottom) hide)
      )
      (property "Manufacturer" "Diodes Incorporated" (at 30.48 -15.24 0)
        (effects (font (size 1.27 1.27) (thickness 0.15)) (justify left bottom) hide)
      )
      (property "Author" "Antmicro" (at 30.48 -17.78 0)
        (effects (font (size 1.27 1.27) (thickness 0.15)) (justify left bottom) hide)
      )
      (property "License" "Apache-2.0" (at 30.48 -20.32 0)
        (effects (font (size 1.27 1.27) (thickness 0.15)) (justify left bottom) hide)
      )
      (property "ki_keywords" "SMT, PMIC, IC, VOLTAGE, LDO" (at 0 0 0)
        (effects (font (size 1.27 1.27)) hide)
      )
      (property "ki_description" "Linear voltage regulator" (at 0 0 0)
        (effects (font (size 1.27 1.27)) hide)
      )
      (symbol "AP7340-18FS4-7_1_1"
        (rectangle (start 2.54 2.54) (end 12.7 -7.62)
          (stroke (width 0.254) (type default))
          (fill (type background))
        )
        (pin power_out line (at 15.24 0 180) (length 2.54)
          (name "VOUT" (effects (font (size 1.27 1.27))))
          (number "1" (effects (font (size 1.27 1.27))))
        )
        (pin power_in line (at 0 -5.08 0) (length 2.54)
          (name "GND" (effects (font (size 1.27 1.27))))
          (number "2" (effects (font (size 1.27 1.27))))
        )
        (pin input line (at 0 -2.54 0) (length 2.54)
          (name "EN" (effects (font (size 1.27 1.27))))
          (number "3" (effects (font (size 1.27 1.27))))
        )
        (pin power_in line (at 0 0 0) (length 2.54)
          (name "VIN" (effects (font (size 1.27 1.27))))
          (number "4" (effects (font (size 1.27 1.27))))
        )
        (pin passive line (at 15.24 -2.54 180) (length 2.54)
          (name "EP" (effects (font (size 1.27 1.27))))
          (number "5" (effects (font (size 1.27 1.27))))
        )
      )
    )
	(symbol "kria-k26-devboard:BSS123" (pin_names (offset 0)) (in_bom yes) (on_board yes)
      (property "Reference" "Q" (at 22.86 -6.35 0)
        (effects (font (size 1.27 1.27) (thickness 0.15)) (justify left bottom))
      )
      (property "Value" "BSS123" (at 22.86 -8.89 0)
        (effects (font (size 1.27 1.27) (thickness 0.15)) (justify left bottom))
      )
      (property "Footprint" "kria-k26-devboard-footprints:SOT-23-3" (at 22.86 -11.43 0)
        (effects (font (size 1.27 1.27) (thickness 0.15)) (justify left bottom) hide)
      )
      (property "Datasheet" "https://www.onsemi.com/pub/Collateral/BSS123-D.PDF" (at 22.86 -13.97 0)
        (effects (font (size 1.27 1.27) (thickness 0.15)) (justify left bottom) hide)
      )
      (property "MPN" "BSS123" (at 22.86 -16.51 0)
        (effects (font (size 1.27 1.27) (thickness 0.15)) (justify left bottom) hide)
      )
      (property "Manufacturer" "ON Semiconductor" (at 22.86 -19.05 0)
        (effects (font (size 1.27 1.27) (thickness 0.15)) (justify left bottom) hide)
      )
      (property "Author" "Antmicro" (at 22.86 -21.59 0)
        (effects (font (size 1.27 1.27) (thickness 0.15)) (justify left bottom) hide)
      )
      (property "License" "Apache-2.0" (at 22.86 -24.13 0)
        (effects (font (size 1.27 1.27) (thickness 0.15)) (justify left bottom) hide)
      )
      (symbol "BSS123_1_1"
        (polyline
          (pts
            (xy 5.08 1.143)
            (xy 5.08 0.635)
          )
          (stroke (width 0.254) (type default))
          (fill (type background))
        )
        (polyline
          (pts
            (xy 5.08 1.143)
            (xy 5.08 1.651)
          )
          (stroke (width 0.254) (type default))
          (fill (type background))
        )
        (polyline
          (pts
            (xy 5.08 2.54)
            (xy 5.08 2.032)
          )
          (stroke (width 0.254) (type default))
          (fill (type background))
        )
        (polyline
          (pts
            (xy 5.08 2.54)
            (xy 5.08 3.048)
          )
          (stroke (width 0.254) (type default))
          (fill (type background))
        )
        (polyline
          (pts
            (xy 5.08 4.445)
            (xy 5.08 3.429)
          )
          (stroke (width 0.254) (type default))
          (fill (type background))
        )
        (polyline
          (pts
            (xy 7.62 1.143)
            (xy 5.08 1.143)
          )
          (stroke (width 0.254) (type default))
          (fill (type background))
        )
        (polyline
          (pts
            (xy 9.144 3.048)
            (xy 8.128 3.048)
          )
          (stroke (width 0.254) (type default))
          (fill (type background))
        )
        (polyline
          (pts
            (xy 2.54 0)
            (xy 4.572 0)
            (xy 4.572 3.937)
          )
          (stroke (width 0.254) (type default))
          (fill (type none))
        )
        (polyline
          (pts
            (xy 7.62 0)
            (xy 7.62 2.54)
            (xy 5.08 2.54)
          )
          (stroke (width 0.254) (type default))
          (fill (type background))
        )
        (polyline
          (pts
            (xy 7.62 5.08)
            (xy 7.62 3.937)
            (xy 5.08 3.937)
          )
          (stroke (width 0.254) (type default))
          (fill (type background))
        )
        (polyline
          (pts
            (xy 5.08 2.54)
            (xy 5.842 3.048)
            (xy 5.842 2.032)
            (xy 5.08 2.54)
          )
          (stroke (width 0.254) (type default))
          (fill (type outline))
        )
        (polyline
          (pts
            (xy 8.636 3.048)
            (xy 8.128 2.286)
            (xy 9.144 2.286)
            (xy 8.636 3.048)
          )
          (stroke (width 0.254) (type default))
          (fill (type outline))
        )
        (polyline
          (pts
            (xy 7.493 0.635)
            (xy 8.636 0.635)
            (xy 8.636 3.937)
            (xy 8.636 4.445)
            (xy 7.493 4.445)
          )
          (stroke (width 0.254) (type default))
          (fill (type background))
        )
        (circle (center 6.35 2.54) (radius 3.302)
          (stroke (width 0.254) (type default))
          (fill (type background))
        )
        (circle (center 7.62 0.635) (radius 0.127)
          (stroke (width 0.254) (type default))
          (fill (type background))
        )
        (circle (center 7.62 1.143) (radius 0.127)
          (stroke (width 0.254) (type default))
          (fill (type background))
        )
        (circle (center 7.62 4.445) (radius 0.127)
          (stroke (width 0.254) (type default))
          (fill (type background))
        )
        (pin bidirectional line (at 0 0 0) (length 2.54)
          (name "G" (effects (font (size 1.27 1.27))))
          (number "1" (effects (font (size 1.27 1.27))))
        )
        (pin bidirectional line (at 7.62 -2.54 90) (length 2.54)
          (name "S" (effects (font (size 1.27 1.27))))
          (number "2" (effects (font (size 1.27 1.27))))
        )
        (pin bidirectional line (at 7.62 7.62 270) (length 2.54)
          (name "D" (effects (font (size 1.27 1.27))))
          (number "3" (effects (font (size 1.27 1.27))))
        )
      )
    )
	(symbol "kria-k26-devboard:BarrelJack_Pin2mm_MJ-179PH" (pin_names hide) (in_bom yes) (on_board yes)
      (property "Reference" "J" (at 17.78 -5.08 0)
        (effects (font (size 1.27 1.27) (thickness 0.15)) (justify left bottom))
      )
      (property "Value" "BarrelJack_Pin2mm_MJ-179PH" (at 17.78 -10.16 0)
        (effects (font (size 1.27 1.27) (thickness 0.15)) (justify left bottom) hide)
      )
      (property "Footprint" "kria-k26-devboard-footprints:BarrelJack_Pin2mm_MJ-179PH" (at 17.78 -12.7 0)
        (effects (font (size 1.27 1.27) (thickness 0.15)) (justify left bottom) hide)
      )
      (property "Datasheet" "https://www.farnell.com/datasheets/3167288.pdf" (at 17.78 -15.24 0)
        (effects (font (size 1.27 1.27) (thickness 0.15)) (justify left bottom) hide)
      )
      (property "MPN" "MJ-179PH" (at 17.78 -7.62 0)
        (effects (font (size 1.27 1.27) (thickness 0.15)) (justify left bottom))
      )
      (property "Manufacturer" "Multicomp Pro" (at 17.78 -17.78 0)
        (effects (font (size 1.27 1.27) (thickness 0.15)) (justify left bottom) hide)
      )
      (property "Author" "Antmicro" (at 17.78 -20.32 0)
        (effects (font (size 1.27 1.27) (thickness 0.15)) (justify left bottom) hide)
      )
      (property "License" "Apache-2.0" (at 17.78 -22.86 0)
        (effects (font (size 1.27 1.27) (thickness 0.15)) (justify left bottom) hide)
      )
      (property "ki_keywords" "HORIZONTAL, THT, JACK, CONNECTOR, POWER" (at 0 0 0)
        (effects (font (size 1.27 1.27)) hide)
      )
      (property "ki_description" "DC Power Connector, Jack, 4 A, 1.95 mm, PCB Mount, Through Hole" (at 0 0 0)
        (effects (font (size 1.27 1.27)) hide)
      )
      (symbol "BarrelJack_Pin2mm_MJ-179PH_0_1"
        (polyline
          (pts
            (xy -5.08 -5.08)
            (xy -5.334 -4.064)
            (xy -4.826 -4.064)
            (xy -5.08 -5.08)
          )
          (stroke (width 0) (type default))
          (fill (type outline))
        )
      )
      (symbol "BarrelJack_Pin2mm_MJ-179PH_1_1"
        (rectangle (start -12.7 1.27) (end -2.54 -6.35)
          (stroke (width 0.254) (type default))
          (fill (type background))
        )
        (arc (start -10.795 0) (mid -10.609 -0.449) (end -10.16 -0.635)
          (stroke (width 0.254) (type default))
          (fill (type outline))
        )
        (rectangle (start -10.16 -0.635) (end -6.985 0.635)
          (stroke (width 0.254) (type default))
          (fill (type outline))
        )
        (arc (start -10.16 0.635) (mid -10.609 0.449) (end -10.795 0)
          (stroke (width 0.254) (type default))
          (fill (type outline))
        )
        (arc (start -8.89 -3.175) (mid -10.237 -3.733) (end -10.795 -5.08)
          (stroke (width 0.254) (type default))
          (fill (type none))
        )
        (arc (start -6.985 -5.08) (mid -7.543 -3.733) (end -8.89 -3.175)
          (stroke (width 0.254) (type default))
          (fill (type none))
        )
        (polyline
          (pts
            (xy -5.08 -2.54)
            (xy -5.08 -5.08)
          )
          (stroke (width 0.254) (type default))
          (fill (type background))
        )
        (polyline
          (pts
            (xy -2.54 -5.08)
            (xy -6.985 -5.08)
          )
          (stroke (width 0.254) (type default))
          (fill (type background))
        )
        (polyline
          (pts
            (xy -2.54 -2.54)
            (xy -5.08 -2.54)
          )
          (stroke (width 0.254) (type default))
          (fill (type background))
        )
        (polyline
          (pts
            (xy -2.54 0)
            (xy -6.985 0)
          )
          (stroke (width 0.254) (type default))
          (fill (type background))
        )
        (pin passive line (at 0 0 180) (length 2.54)
          (name "1" (effects (font (size 1.27 1.27))))
          (number "1" (effects (font (size 1.27 1.27))))
        )
        (pin passive line (at 0 -2.54 180) (length 2.54)
          (name "2" (effects (font (size 1.27 1.27))))
          (number "2" (effects (font (size 1.27 1.27))))
        )
        (pin passive line (at 0 -5.08 180) (length 2.54)
          (name "3" (effects (font (size 1.27 1.27))))
          (number "3" (effects (font (size 1.27 1.27))))
        )
      )
    )
	(symbol "kria-k26-devboard:Bus_M.2_2199119-6" (in_bom yes) (on_board yes)
      (property "Reference" "J" (at 48.26 -2.54 0)
        (effects (font (size 1.27 1.27) (thickness 0.15)) (justify left bottom))
      )
      (property "Value" "Bus_M.2_2199119-6" (at 48.26 -5.08 0)
        (effects (font (size 1.27 1.27) (thickness 0.15)) (justify left bottom))
      )
      (property "Footprint" "kria-k26-devboard-footprints:Bus_M.2_Socket_Key_E_TE_1-2199119-6" (at 48.26 -7.62 0)
        (effects (font (size 1.27 1.27) (thickness 0.15)) (justify left bottom) hide)
      )
      (property "Datasheet" "https://www.te.com/usa-en/product-1-2199119-6.datasheet.pdf" (at 48.26 -10.16 0)
        (effects (font (size 1.27 1.27) (thickness 0.15)) (justify left bottom) hide)
      )
      (property "MPN" "2199119-6" (at 48.26 -12.7 0)
        (effects (font (size 1.27 1.27) (thickness 0.15)) (justify left bottom) hide)
      )
      (property "Manufacturer" "TE Connectivity" (at 48.26 -15.24 0)
        (effects (font (size 1.27 1.27) (thickness 0.15)) (justify left bottom) hide)
      )
      (property "Author" "Antmicro" (at 48.26 -17.78 0)
        (effects (font (size 1.27 1.27) (thickness 0.15)) (justify left bottom) hide)
      )
      (property "License" "Apache-2.0" (at 48.26 -20.32 0)
        (effects (font (size 1.27 1.27) (thickness 0.15)) (justify left bottom) hide)
      )
      (property "ki_keywords" "HORIZONTAL, SMT, PCIE, CONNECTOR" (at 0 0 0)
        (effects (font (size 1.27 1.27)) hide)
      )
      (property "ki_description" "Key E, PCI connector" (at 0 0 0)
        (effects (font (size 1.27 1.27)) hide)
      )
      (symbol "Bus_M.2_2199119-6_1_1"
        (rectangle (start 2.54 2.54) (end 31.75 -83.82)
          (stroke (width 0.254) (type default))
          (fill (type background))
        )
        (pin power_in line (at 0 -81.28 0) (length 2.54)
          (name "GND" (effects (font (size 1.27 1.27))))
          (number "1" (effects (font (size 1.27 1.27))))
        )
        (pin bidirectional line (at 34.29 -5.08 180) (length 2.54)
          (name "PCM_SYNC" (effects (font (size 1.27 1.27))))
          (number "10" (effects (font (size 1.27 1.27))))
        )
        (pin bidirectional line (at 0 -15.24 0) (length 2.54)
          (name "SDIO_CMD" (effects (font (size 1.27 1.27))))
          (number "11" (effects (font (size 1.27 1.27))))
        )
        (pin bidirectional line (at 34.29 -7.62 180) (length 2.54)
          (name "PCM_OUT" (effects (font (size 1.27 1.27))))
          (number "12" (effects (font (size 1.27 1.27))))
        )
        (pin bidirectional line (at 0 -17.78 0) (length 2.54)
          (name "SDIO_D0" (effects (font (size 1.27 1.27))))
          (number "13" (effects (font (size 1.27 1.27))))
        )
        (pin bidirectional line (at 34.29 -10.16 180) (length 2.54)
          (name "PCM_IN" (effects (font (size 1.27 1.27))))
          (number "14" (effects (font (size 1.27 1.27))))
        )
        (pin bidirectional line (at 0 -20.32 0) (length 2.54)
          (name "SDIO_D1" (effects (font (size 1.27 1.27))))
          (number "15" (effects (font (size 1.27 1.27))))
        )
        (pin output line (at 34.29 -12.7 180) (length 2.54)
          (name "~{LED_2}" (effects (font (size 1.27 1.27))))
          (number "16" (effects (font (size 1.27 1.27))))
        )
        (pin bidirectional line (at 0 -22.86 0) (length 2.54)
          (name "SDIO_D2" (effects (font (size 1.27 1.27))))
          (number "17" (effects (font (size 1.27 1.27))))
        )
        (pin passive line (at 0 -81.28 0) (length 2.54) hide
          (name "GND" (effects (font (size 1.27 1.27))))
          (number "18" (effects (font (size 1.27 1.27))))
        )
        (pin bidirectional line (at 0 -25.4 0) (length 2.54)
          (name "SDIO_D3" (effects (font (size 1.27 1.27))))
          (number "19" (effects (font (size 1.27 1.27))))
        )
        (pin power_in line (at 0 0 0) (length 2.54)
          (name "3.3V" (effects (font (size 1.27 1.27))))
          (number "2" (effects (font (size 1.27 1.27))))
        )
        (pin output line (at 34.29 -15.24 180) (length 2.54)
          (name "~{UART_WAKE}" (effects (font (size 1.27 1.27))))
          (number "20" (effects (font (size 1.27 1.27))))
        )
        (pin bidirectional line (at 0 -27.94 0) (length 2.54)
          (name "SDIO_~{WAKE}" (effects (font (size 1.27 1.27))))
          (number "21" (effects (font (size 1.27 1.27))))
        )
        (pin bidirectional line (at 34.29 -20.32 180) (length 2.54)
          (name "UART_TXD" (effects (font (size 1.27 1.27))))
          (number "22" (effects (font (size 1.27 1.27))))
        )
        (pin input line (at 0 -30.48 0) (length 2.54)
          (name "SDIO_~{RESET}" (effects (font (size 1.27 1.27))))
          (number "23" (effects (font (size 1.27 1.27))))
        )
        (pin bidirectional line (at 0 -5.08 0) (length 2.54)
          (name "USB_D+" (effects (font (size 1.27 1.27))))
          (number "3" (effects (font (size 1.27 1.27))))
        )
        (pin bidirectional line (at 34.29 -22.86 180) (length 2.54)
          (name "UART_RXD" (effects (font (size 1.27 1.27))))
          (number "32" (effects (font (size 1.27 1.27))))
        )
        (pin passive line (at 0 -81.28 0) (length 2.54) hide
          (name "GND" (effects (font (size 1.27 1.27))))
          (number "33" (effects (font (size 1.27 1.27))))
        )
        (pin bidirectional line (at 34.29 -25.4 180) (length 2.54)
          (name "UART_RTS" (effects (font (size 1.27 1.27))))
          (number "34" (effects (font (size 1.27 1.27))))
        )
        (pin input line (at 0 -34.29 0) (length 2.54)
          (name "PET0+" (effects (font (size 1.27 1.27))))
          (number "35" (effects (font (size 1.27 1.27))))
        )
        (pin bidirectional line (at 34.29 -27.94 180) (length 2.54)
          (name "UART_CTS" (effects (font (size 1.27 1.27))))
          (number "36" (effects (font (size 1.27 1.27))))
        )
        (pin input line (at 0 -36.83 0) (length 2.54)
          (name "PET0-" (effects (font (size 1.27 1.27))))
          (number "37" (effects (font (size 1.27 1.27))))
        )
        (pin bidirectional line (at 34.29 -33.02 180) (length 2.54)
          (name "VENDOR_1" (effects (font (size 1.27 1.27))))
          (number "38" (effects (font (size 1.27 1.27))))
        )
        (pin passive line (at 0 -81.28 0) (length 2.54) hide
          (name "GND" (effects (font (size 1.27 1.27))))
          (number "39" (effects (font (size 1.27 1.27))))
        )
        (pin passive line (at 0 0 0) (length 2.54) hide
          (name "3.3V" (effects (font (size 1.27 1.27))))
          (number "4" (effects (font (size 1.27 1.27))))
        )
        (pin bidirectional line (at 34.29 -35.56 180) (length 2.54)
          (name "VENDOR_2" (effects (font (size 1.27 1.27))))
          (number "40" (effects (font (size 1.27 1.27))))
        )
        (pin output line (at 0 -40.64 0) (length 2.54)
          (name "PER0+" (effects (font (size 1.27 1.27))))
          (number "41" (effects (font (size 1.27 1.27))))
        )
        (pin bidirectional line (at 34.29 -38.1 180) (length 2.54)
          (name "VENDOR_3" (effects (font (size 1.27 1.27))))
          (number "42" (effects (font (size 1.27 1.27))))
        )
        (pin output line (at 0 -43.18 0) (length 2.54)
          (name "PER0-" (effects (font (size 1.27 1.27))))
          (number "43" (effects (font (size 1.27 1.27))))
        )
        (pin bidirectional line (at 34.29 -43.18 180) (length 2.54)
          (name "COEX3" (effects (font (size 1.27 1.27))))
          (number "44" (effects (font (size 1.27 1.27))))
        )
        (pin passive line (at 0 -81.28 0) (length 2.54) hide
          (name "GND" (effects (font (size 1.27 1.27))))
          (number "45" (effects (font (size 1.27 1.27))))
        )
        (pin bidirectional line (at 34.29 -45.72 180) (length 2.54)
          (name "COEX_TXD" (effects (font (size 1.27 1.27))))
          (number "46" (effects (font (size 1.27 1.27))))
        )
        (pin input line (at 0 -45.72 0) (length 2.54)
          (name "REFCLK0+" (effects (font (size 1.27 1.27))))
          (number "47" (effects (font (size 1.27 1.27))))
        )
        (pin bidirectional line (at 34.29 -48.26 180) (length 2.54)
          (name "COEX_RXD" (effects (font (size 1.27 1.27))))
          (number "48" (effects (font (size 1.27 1.27))))
        )
        (pin input line (at 0 -48.26 0) (length 2.54)
          (name "REFCLK0-" (effects (font (size 1.27 1.27))))
          (number "49" (effects (font (size 1.27 1.27))))
        )
        (pin bidirectional line (at 0 -7.62 0) (length 2.54)
          (name "USB_D-" (effects (font (size 1.27 1.27))))
          (number "5" (effects (font (size 1.27 1.27))))
        )
        (pin input line (at 34.29 -52.07 180) (length 2.54)
          (name "SUSCLK" (effects (font (size 1.27 1.27))))
          (number "50" (effects (font (size 1.27 1.27))))
        )
        (pin passive line (at 0 -81.28 0) (length 2.54) hide
          (name "GND" (effects (font (size 1.27 1.27))))
          (number "51" (effects (font (size 1.27 1.27))))
        )
        (pin input line (at 34.29 -54.61 180) (length 2.54)
          (name "~{PERST0}" (effects (font (size 1.27 1.27))))
          (number "52" (effects (font (size 1.27 1.27))))
        )
        (pin output line (at 0 -68.58 0) (length 2.54)
          (name "~{CLKREQ0}" (effects (font (size 1.27 1.27))))
          (number "53" (effects (font (size 1.27 1.27))))
        )
        (pin input line (at 34.29 -57.15 180) (length 2.54)
          (name "W_DISABLE2" (effects (font (size 1.27 1.27))))
          (number "54" (effects (font (size 1.27 1.27))))
        )
        (pin output line (at 0 -71.12 0) (length 2.54)
          (name "~{PEWAKE0}" (effects (font (size 1.27 1.27))))
          (number "55" (effects (font (size 1.27 1.27))))
        )
        (pin input line (at 34.29 -60.96 180) (length 2.54)
          (name "W_DISABLE1" (effects (font (size 1.27 1.27))))
          (number "56" (effects (font (size 1.27 1.27))))
        )
        (pin passive line (at 0 -81.28 0) (length 2.54) hide
          (name "GND" (effects (font (size 1.27 1.27))))
          (number "57" (effects (font (size 1.27 1.27))))
        )
        (pin bidirectional line (at 34.29 -66.04 180) (length 2.54)
          (name "I2C_DATA" (effects (font (size 1.27 1.27))))
          (number "58" (effects (font (size 1.27 1.27))))
        )
        (pin input line (at 0 -50.8 0) (length 2.54)
          (name "PET1+" (effects (font (size 1.27 1.27))))
          (number "59" (effects (font (size 1.27 1.27))))
        )
        (pin output line (at 34.29 0 180) (length 2.54)
          (name "~{LED_1}" (effects (font (size 1.27 1.27))))
          (number "6" (effects (font (size 1.27 1.27))))
        )
        (pin bidirectional line (at 34.29 -68.58 180) (length 2.54)
          (name "I2C_CLK" (effects (font (size 1.27 1.27))))
          (number "60" (effects (font (size 1.27 1.27))))
        )
        (pin input line (at 0 -53.34 0) (length 2.54)
          (name "PET1-" (effects (font (size 1.27 1.27))))
          (number "61" (effects (font (size 1.27 1.27))))
        )
        (pin output line (at 34.29 -73.66 180) (length 2.54)
          (name "~{ALERT}" (effects (font (size 1.27 1.27))))
          (number "62" (effects (font (size 1.27 1.27))))
        )
        (pin passive line (at 0 -81.28 0) (length 2.54) hide
          (name "GND" (effects (font (size 1.27 1.27))))
          (number "63" (effects (font (size 1.27 1.27))))
        )
        (pin no_connect line (at 2.54 -76.2 0) (length 2.54) hide
          (name "RFU" (effects (font (size 1.27 1.27))))
          (number "64" (effects (font (size 1.27 1.27))))
        )
        (pin output line (at 0 -55.88 0) (length 2.54)
          (name "PER1+" (effects (font (size 1.27 1.27))))
          (number "65" (effects (font (size 1.27 1.27))))
        )
        (pin bidirectional line (at 34.29 -76.2 180) (length 2.54)
          (name "UIM_SWP" (effects (font (size 1.27 1.27))))
          (number "66" (effects (font (size 1.27 1.27))))
        )
        (pin output line (at 0 -58.42 0) (length 2.54)
          (name "PER1-" (effects (font (size 1.27 1.27))))
          (number "67" (effects (font (size 1.27 1.27))))
        )
        (pin bidirectional line (at 34.29 -78.74 180) (length 2.54)
          (name "UIM_POWER_SNK" (effects (font (size 1.27 1.27))))
          (number "68" (effects (font (size 1.27 1.27))))
        )
        (pin passive line (at 0 -81.28 0) (length 2.54) hide
          (name "GND" (effects (font (size 1.27 1.27))))
          (number "69" (effects (font (size 1.27 1.27))))
        )
        (pin passive line (at 0 -81.28 0) (length 2.54) hide
          (name "GND" (effects (font (size 1.27 1.27))))
          (number "7" (effects (font (size 1.27 1.27))))
        )
        (pin bidirectional line (at 34.29 -81.28 180) (length 2.54)
          (name "UIM_POWER_SRC" (effects (font (size 1.27 1.27))))
          (number "70" (effects (font (size 1.27 1.27))))
        )
        (pin input line (at 0 -60.96 0) (length 2.54)
          (name "REFCLK1+" (effects (font (size 1.27 1.27))))
          (number "71" (effects (font (size 1.27 1.27))))
        )
        (pin passive line (at 0 0 0) (length 2.54) hide
          (name "3.3V" (effects (font (size 1.27 1.27))))
          (number "72" (effects (font (size 1.27 1.27))))
        )
        (pin input line (at 0 -63.5 0) (length 2.54)
          (name "REFCLK1-" (effects (font (size 1.27 1.27))))
          (number "73" (effects (font (size 1.27 1.27))))
        )
        (pin passive line (at 0 0 0) (length 2.54) hide
          (name "3.3V" (effects (font (size 1.27 1.27))))
          (number "74" (effects (font (size 1.27 1.27))))
        )
        (pin passive line (at 0 -81.28 0) (length 2.54) hide
          (name "GND" (effects (font (size 1.27 1.27))))
          (number "75" (effects (font (size 1.27 1.27))))
        )
        (pin bidirectional line (at 34.29 -2.54 180) (length 2.54)
          (name "PCM_CLK" (effects (font (size 1.27 1.27))))
          (number "8" (effects (font (size 1.27 1.27))))
        )
        (pin input line (at 0 -12.7 0) (length 2.54)
          (name "SDIO_CLK" (effects (font (size 1.27 1.27))))
          (number "9" (effects (font (size 1.27 1.27))))
        )
        (pin passive line (at 0 -78.74 0) (length 2.54)
          (name "MP" (effects (font (size 1.27 1.27))))
          (number "MP" (effects (font (size 1.27 1.27))))
        )
      )
    )
	(symbol "kria-k26-devboard:Bus_RJ45_5-2337992-8" (in_bom yes) (on_board yes)
      (property "Reference" "J" (at 35.56 -2.54 0)
        (effects (font (size 1.27 1.27) (thickness 0.15)) (justify left bottom))
      )
      (property "Value" "Bus_RJ45_5-2337992-8" (at 35.56 -5.08 0)
        (effects (font (size 1.27 1.27) (thickness 0.15)) (justify left bottom))
      )
      (property "Footprint" "kria-k26-devboard-footprints:RJ45_5-2337992-8_Horizontal" (at 35.56 -7.62 0)
        (effects (font (size 1.27 1.27) (thickness 0.15)) (justify left bottom) hide)
      )
      (property "Datasheet" "https://www.te.com/commerce/DocumentDelivery/DDEController?Action=showdoc&DocId=Customer+Drawing%7F5-2337992-8%7FA%7Fpdf%7FEnglish%7FENG_CD_5-2337992-8_A.pdf%7F5-2337992-8" (at 35.56 -10.16 0)
        (effects (font (size 1.27 1.27) (thickness 0.15)) (justify left bottom) hide)
      )
      (property "MPN" "5-2337992-8" (at 35.56 -12.7 0)
        (effects (font (size 1.27 1.27) (thickness 0.15)) (justify left bottom) hide)
      )
      (property "Manufacturer" "TE Connectivity" (at 35.56 -15.24 0)
        (effects (font (size 1.27 1.27) (thickness 0.15)) (justify left bottom) hide)
      )
      (property "Author" "Antmicro" (at 35.56 -17.78 0)
        (effects (font (size 1.27 1.27) (thickness 0.15)) (justify left bottom) hide)
      )
      (property "License" "Apache-2.0" (at 35.56 -20.32 0)
        (effects (font (size 1.27 1.27) (thickness 0.15)) (justify left bottom) hide)
      )
      (property "VSD_Class" "Ethernet" (at 35.56 -22.86 0)
        (effects (font (size 1.27 1.27)) (justify left bottom) hide)
      )
      (property "ki_keywords" "RJ45, HORIZONTAL, THT, ETHERNET, CONNECTOR, FEMALE" (at 0 0 0)
        (effects (font (size 1.27 1.27)) hide)
      )
      (property "ki_description" "Modular Connector, RJ45 Jack, 1 x 1 (Port), 8P8C, Cat5e, Through Hole Mount" (at 0 0 0)
        (effects (font (size 1.27 1.27)) hide)
      )
      (property "ki_fp_filters" "CONN18_5-2337992-8_TEC" (at 0 0 0)
        (effects (font (size 1.27 1.27)) hide)
      )
      (symbol "Bus_RJ45_5-2337992-8_1_1"
        (polyline
          (pts
            (xy 8.89 -13.97)
            (xy 13.97 -13.97)
          )
          (stroke (width 0.254) (type default))
          (fill (type background))
        )
        (polyline
          (pts
            (xy 8.89 -1.27)
            (xy 8.89 -13.97)
          )
          (stroke (width 0.254) (type default))
          (fill (type background))
        )
        (polyline
          (pts
            (xy 8.89 -1.27)
            (xy 13.97 -1.27)
          )
          (stroke (width 0.254) (type default))
          (fill (type background))
        )
        (polyline
          (pts
            (xy 13.97 -13.97)
            (xy 13.97 -12.7)
          )
          (stroke (width 0.254) (type default))
          (fill (type background))
        )
        (polyline
          (pts
            (xy 13.97 -12.7)
            (xy 15.24 -12.7)
          )
          (stroke (width 0.254) (type default))
          (fill (type background))
        )
        (polyline
          (pts
            (xy 13.97 -2.54)
            (xy 15.24 -2.54)
          )
          (stroke (width 0.254) (type default))
          (fill (type background))
        )
        (polyline
          (pts
            (xy 13.97 -1.27)
            (xy 13.97 -2.54)
          )
          (stroke (width 0.254) (type default))
          (fill (type background))
        )
        (polyline
          (pts
            (xy 15.24 -12.7)
            (xy 15.24 -11.43)
          )
          (stroke (width 0.254) (type default))
          (fill (type background))
        )
        (polyline
          (pts
            (xy 15.24 -11.43)
            (xy 16.51 -11.43)
          )
          (stroke (width 0.254) (type default))
          (fill (type background))
        )
        (polyline
          (pts
            (xy 15.24 -3.81)
            (xy 16.51 -3.81)
          )
          (stroke (width 0.254) (type default))
          (fill (type background))
        )
        (polyline
          (pts
            (xy 15.24 -2.54)
            (xy 15.24 -3.81)
          )
          (stroke (width 0.254) (type default))
          (fill (type background))
        )
        (polyline
          (pts
            (xy 16.51 -3.81)
            (xy 16.51 -11.43)
          )
          (stroke (width 0.254) (type default))
          (fill (type background))
        )
        (rectangle (start 2.54 2.54) (end 19.05 -38.1)
          (stroke (width 0.254) (type default))
          (fill (type background))
        )
        (pin bidirectional line (at 0 0 0) (length 2.54)
          (name "P1" (effects (font (size 1.27 1.27))))
          (number "1" (effects (font (size 1.27 1.27))))
        )
        (pin bidirectional line (at 0 -17.78 0) (length 2.54)
          (name "P10" (effects (font (size 1.27 1.27))))
          (number "10" (effects (font (size 1.27 1.27))))
        )
        (pin bidirectional line (at 0 -27.94 0) (length 2.54)
          (name "VC1" (effects (font (size 1.27 1.27))))
          (number "11" (effects (font (size 1.27 1.27))))
        )
        (pin bidirectional line (at 0 -30.48 0) (length 2.54)
          (name "VC2" (effects (font (size 1.27 1.27))))
          (number "12" (effects (font (size 1.27 1.27))))
        )
        (pin bidirectional line (at 0 -33.02 0) (length 2.54)
          (name "VC3" (effects (font (size 1.27 1.27))))
          (number "13" (effects (font (size 1.27 1.27))))
        )
        (pin bidirectional line (at 0 -35.56 0) (length 2.54)
          (name "VC4" (effects (font (size 1.27 1.27))))
          (number "14" (effects (font (size 1.27 1.27))))
        )
        (pin passive line (at 21.59 -27.94 180) (length 2.54)
          (name "LED_GRN+" (effects (font (size 1.27 1.27))))
          (number "15" (effects (font (size 1.27 1.27))))
        )
        (pin passive line (at 21.59 -30.48 180) (length 2.54)
          (name "LED_GRN-" (effects (font (size 1.27 1.27))))
          (number "16" (effects (font (size 1.27 1.27))))
        )
        (pin passive line (at 21.59 -22.86 180) (length 2.54)
          (name "LED_YEL+" (effects (font (size 1.27 1.27))))
          (number "17" (effects (font (size 1.27 1.27))))
        )
        (pin passive line (at 21.59 -25.4 180) (length 2.54)
          (name "LED_YEL-" (effects (font (size 1.27 1.27))))
          (number "18" (effects (font (size 1.27 1.27))))
        )
        (pin passive line (at 21.59 -35.56 180) (length 2.54)
          (name "SHIELD" (effects (font (size 1.27 1.27))))
          (number "19" (effects (font (size 1.27 1.27))))
        )
        (pin bidirectional line (at 0 -2.54 0) (length 2.54)
          (name "P2" (effects (font (size 1.27 1.27))))
          (number "2" (effects (font (size 1.27 1.27))))
        )
        (pin passive line (at 21.59 -35.56 180) (length 2.54) hide
          (name "SHIELD" (effects (font (size 1.27 1.27))))
          (number "20" (effects (font (size 1.27 1.27))))
        )
        (pin bidirectional line (at 0 -5.08 0) (length 2.54)
          (name "P3" (effects (font (size 1.27 1.27))))
          (number "3" (effects (font (size 1.27 1.27))))
        )
        (pin bidirectional line (at 0 -22.86 0) (length 2.54)
          (name "P4" (effects (font (size 1.27 1.27))))
          (number "4" (effects (font (size 1.27 1.27))))
        )
        (pin bidirectional line (at 0 -25.4 0) (length 2.54)
          (name "P5" (effects (font (size 1.27 1.27))))
          (number "5" (effects (font (size 1.27 1.27))))
        )
        (pin bidirectional line (at 0 -7.62 0) (length 2.54)
          (name "P6" (effects (font (size 1.27 1.27))))
          (number "6" (effects (font (size 1.27 1.27))))
        )
        (pin bidirectional line (at 0 -10.16 0) (length 2.54)
          (name "P7" (effects (font (size 1.27 1.27))))
          (number "7" (effects (font (size 1.27 1.27))))
        )
        (pin bidirectional line (at 0 -12.7 0) (length 2.54)
          (name "P8" (effects (font (size 1.27 1.27))))
          (number "8" (effects (font (size 1.27 1.27))))
        )
        (pin bidirectional line (at 0 -15.24 0) (length 2.54)
          (name "P9" (effects (font (size 1.27 1.27))))
          (number "9" (effects (font (size 1.27 1.27))))
        )
      )
    )
	(symbol "kria-k26-devboard:C_100n_0402" (pin_numbers hide) (pin_names hide) (in_bom yes) (on_board yes)
      (property "Reference" "C" (at 20.32 -5.08 0)
        (effects (font (size 1.27 1.27) (thickness 0.15)) (justify left bottom))
      )
      (property "Value" "C_100n_0402" (at 20.32 -10.16 0)
        (effects (font (size 1.27 1.27) (thickness 0.15)) (justify left bottom) hide)
      )
      (property "Footprint" "kria-k26-devboard-footprints:C_0402_1005Metric" (at 20.32 -12.7 0)
        (effects (font (size 1.27 1.27) (thickness 0.15)) (justify left bottom) hide)
      )
      (property "Datasheet" "https://www.murata.com/products/productdetail?partno=GRM155R61H104KE14%23" (at 20.32 -15.24 0)
        (effects (font (size 1.27 1.27) (thickness 0.15)) (justify left bottom) hide)
      )
      (property "MPN" "GRM155R61H104KE14D" (at 20.32 -17.78 0)
        (effects (font (size 1.27 1.27) (thickness 0.15)) (justify left bottom) hide)
      )
      (property "Manufacturer" "Murata" (at 20.32 -20.32 0)
        (effects (font (size 1.27 1.27) (thickness 0.15)) (justify left bottom) hide)
      )
      (property "License" "Apache-2.0" (at 20.32 -22.86 0)
        (effects (font (size 1.27 1.27) (thickness 0.15)) (justify left bottom) hide)
      )
      (property "Author" "Antmicro" (at 20.32 -25.4 0)
        (effects (font (size 1.27 1.27) (thickness 0.15)) (justify left bottom) hide)
      )
      (property "Val" "100n" (at 20.32 -7.62 0)
        (effects (font (size 1.27 1.27) (thickness 0.15)) (justify left bottom))
      )
      (property "Voltage" "50V" (at 20.32 -27.94 0)
        (effects (font (size 1.27 1.27)) (justify left bottom) hide)
      )
      (property "Dielectric" "X5R" (at 20.32 -30.48 0)
        (effects (font (size 1.27 1.27)) (justify left bottom) hide)
      )
      (property "ki_keywords" "0402, SMT, CAPACITOR, PASSIVE, CERAMIC, MLCC" (at 0 0 0)
        (effects (font (size 1.27 1.27)) hide)
      )
      (property "ki_description" "SMD Multilayer Ceramic Capacitor, 0.1 µF, 50 V, 0402 [1005 Metric], ± 10%, X5R, GRM Series" (at 0 0 0)
        (effects (font (size 1.27 1.27)) hide)
      )
      (symbol "C_100n_0402_0_1"
        (polyline
          (pts
            (xy 2.032 -1.524)
            (xy 2.032 1.524)
          )
          (stroke (width 0.3048) (type default))
          (fill (type none))
        )
        (polyline
          (pts
            (xy 3.048 -1.524)
            (xy 3.048 1.524)
          )
          (stroke (width 0.3302) (type default))
          (fill (type none))
        )
      )
      (symbol "C_100n_0402_1_1"
        (pin passive line (at 0 0 0) (length 2.032)
          (name "~" (effects (font (size 1.27 1.27))))
          (number "1" (effects (font (size 1.27 1.27))))
        )
        (pin passive line (at 5.08 0 180) (length 2.032)
          (name "~" (effects (font (size 1.27 1.27))))
          (number "2" (effects (font (size 1.27 1.27))))
        )
      )
    )
	(symbol "kria-k26-devboard:C_100n_0402_10" (pin_numbers hide) (pin_names hide) (in_bom yes) (on_board yes)
      (property "Reference" "C" (at 20.32 -5.08 0)
        (effects (font (size 1.27 1.27) (thickness 0.15)) (justify left bottom))
      )
      (property "Value" "C_100n_0402_10" (at 20.32 -10.16 0)
        (effects (font (size 1.27 1.27) (thickness 0.15)) (justify left bottom) hide)
      )
      (property "Footprint" "kria-k26-devboard-footprints:C_0402_1005Metric" (at 20.32 -12.7 0)
        (effects (font (size 1.27 1.27) (thickness 0.15)) (justify left bottom) hide)
      )
      (property "Datasheet" "https://search.murata.co.jp/Ceramy/image/img/A01X/G101/ENG/GRM155R61H104KE14-01.pdf" (at 20.32 -15.24 0)
        (effects (font (size 1.27 1.27) (thickness 0.15)) (justify left bottom) hide)
      )
      (property "MPN" "GRM155R61H104KE14D" (at 20.32 -17.78 0)
        (effects (font (size 1.27 1.27) (thickness 0.15)) (justify left bottom) hide)
      )
      (property "Manufacturer" "Murata" (at 20.32 -20.32 0)
        (effects (font (size 1.27 1.27) (thickness 0.15)) (justify left bottom) hide)
      )
      (property "License" "Apache-2.0" (at 20.32 -22.86 0)
        (effects (font (size 1.27 1.27) (thickness 0.15)) (justify left bottom) hide)
      )
      (property "Author" "Antmicro" (at 20.32 -25.4 0)
        (effects (font (size 1.27 1.27) (thickness 0.15)) (justify left bottom) hide)
      )
      (property "Val" "100n" (at 20.32 -7.62 0)
        (effects (font (size 1.27 1.27) (thickness 0.15)) (justify left bottom))
      )
      (property "Voltage" "50V" (at 20.32 -27.94 0)
        (effects (font (size 1.27 1.27)) (justify left bottom) hide)
      )
      (property "Dielectric" "X5R" (at 20.32 -30.48 0)
        (effects (font (size 1.27 1.27)) (justify left bottom) hide)
      )
      (property "ki_description" " " (at 0 0 0)
        (effects (font (size 1.27 1.27)) hide)
      )
      (symbol "C_100n_0402_10_0_1"
        (polyline
          (pts
            (xy 2.032 -1.524)
            (xy 2.032 1.524)
          )
          (stroke (width 0.3048) (type default))
          (fill (type none))
        )
        (polyline
          (pts
            (xy 3.048 -1.524)
            (xy 3.048 1.524)
          )
          (stroke (width 0.3302) (type default))
          (fill (type none))
        )
      )
      (symbol "C_100n_0402_10_1_1"
        (pin passive line (at 0 0 0) (length 2.032)
          (name "~" (effects (font (size 1.27 1.27))))
          (number "1" (effects (font (size 1.27 1.27))))
        )
        (pin passive line (at 5.08 0 180) (length 2.032)
          (name "~" (effects (font (size 1.27 1.27))))
          (number "2" (effects (font (size 1.27 1.27))))
        )
      )
    )
	(symbol "kria-k26-devboard:C_100n_0402_11" (pin_numbers hide) (pin_names hide) (in_bom yes) (on_board yes)
      (property "Reference" "C" (at 20.32 -5.08 0)
        (effects (font (size 1.27 1.27) (thickness 0.15)) (justify left bottom))
      )
      (property "Value" "C_100n_0402_11" (at 20.32 -10.16 0)
        (effects (font (size 1.27 1.27) (thickness 0.15)) (justify left bottom) hide)
      )
      (property "Footprint" "kria-k26-devboard-footprints:C_0402_1005Metric" (at 20.32 -12.7 0)
        (effects (font (size 1.27 1.27) (thickness 0.15)) (justify left bottom) hide)
      )
      (property "Datasheet" "https://search.murata.co.jp/Ceramy/image/img/A01X/G101/ENG/GRM155R61H104KE14-01.pdf" (at 20.32 -15.24 0)
        (effects (font (size 1.27 1.27) (thickness 0.15)) (justify left bottom) hide)
      )
      (property "MPN" "GRM155R61H104KE14D" (at 20.32 -17.78 0)
        (effects (font (size 1.27 1.27) (thickness 0.15)) (justify left bottom) hide)
      )
      (property "Manufacturer" "Murata" (at 20.32 -20.32 0)
        (effects (font (size 1.27 1.27) (thickness 0.15)) (justify left bottom) hide)
      )
      (property "License" "Apache-2.0" (at 20.32 -22.86 0)
        (effects (font (size 1.27 1.27) (thickness 0.15)) (justify left bottom) hide)
      )
      (property "Author" "Antmicro" (at 20.32 -25.4 0)
        (effects (font (size 1.27 1.27) (thickness 0.15)) (justify left bottom) hide)
      )
      (property "Val" "100n" (at 20.32 -7.62 0)
        (effects (font (size 1.27 1.27) (thickness 0.15)) (justify left bottom))
      )
      (property "Voltage" "50V" (at 20.32 -27.94 0)
        (effects (font (size 1.27 1.27)) (justify left bottom) hide)
      )
      (property "Dielectric" "X5R" (at 20.32 -30.48 0)
        (effects (font (size 1.27 1.27)) (justify left bottom) hide)
      )
      (property "ki_description" " " (at 0 0 0)
        (effects (font (size 1.27 1.27)) hide)
      )
      (symbol "C_100n_0402_11_0_1"
        (polyline
          (pts
            (xy 2.032 -1.524)
            (xy 2.032 1.524)
          )
          (stroke (width 0.3048) (type default))
          (fill (type none))
        )
        (polyline
          (pts
            (xy 3.048 -1.524)
            (xy 3.048 1.524)
          )
          (stroke (width 0.3302) (type default))
          (fill (type none))
        )
      )
      (symbol "C_100n_0402_11_1_1"
        (pin passive line (at 0 0 0) (length 2.032)
          (name "~" (effects (font (size 1.27 1.27))))
          (number "1" (effects (font (size 1.27 1.27))))
        )
        (pin passive line (at 5.08 0 180) (length 2.032)
          (name "~" (effects (font (size 1.27 1.27))))
          (number "2" (effects (font (size 1.27 1.27))))
        )
      )
    )
	(symbol "kria-k26-devboard:C_100n_0402_12" (pin_numbers hide) (pin_names hide) (in_bom yes) (on_board yes)
      (property "Reference" "C" (at 20.32 -5.08 0)
        (effects (font (size 1.27 1.27) (thickness 0.15)) (justify left bottom))
      )
      (property "Value" "C_100n_0402_12" (at 20.32 -10.16 0)
        (effects (font (size 1.27 1.27) (thickness 0.15)) (justify left bottom) hide)
      )
      (property "Footprint" "kria-k26-devboard-footprints:C_0402_1005Metric" (at 20.32 -12.7 0)
        (effects (font (size 1.27 1.27) (thickness 0.15)) (justify left bottom) hide)
      )
      (property "Datasheet" "https://search.murata.co.jp/Ceramy/image/img/A01X/G101/ENG/GRM155R61H104KE14-01.pdf" (at 20.32 -15.24 0)
        (effects (font (size 1.27 1.27) (thickness 0.15)) (justify left bottom) hide)
      )
      (property "MPN" "GRM155R61H104KE14D" (at 20.32 -17.78 0)
        (effects (font (size 1.27 1.27) (thickness 0.15)) (justify left bottom) hide)
      )
      (property "Manufacturer" "Murata" (at 20.32 -20.32 0)
        (effects (font (size 1.27 1.27) (thickness 0.15)) (justify left bottom) hide)
      )
      (property "License" "Apache-2.0" (at 20.32 -22.86 0)
        (effects (font (size 1.27 1.27) (thickness 0.15)) (justify left bottom) hide)
      )
      (property "Author" "Antmicro" (at 20.32 -25.4 0)
        (effects (font (size 1.27 1.27) (thickness 0.15)) (justify left bottom) hide)
      )
      (property "Val" "100n" (at 20.32 -7.62 0)
        (effects (font (size 1.27 1.27) (thickness 0.15)) (justify left bottom))
      )
      (property "Voltage" "50V" (at 20.32 -27.94 0)
        (effects (font (size 1.27 1.27)) (justify left bottom) hide)
      )
      (property "Dielectric" "X5R" (at 20.32 -30.48 0)
        (effects (font (size 1.27 1.27)) (justify left bottom) hide)
      )
      (property "ki_description" " " (at 0 0 0)
        (effects (font (size 1.27 1.27)) hide)
      )
      (symbol "C_100n_0402_12_0_1"
        (polyline
          (pts
            (xy 2.032 -1.524)
            (xy 2.032 1.524)
          )
          (stroke (width 0.3048) (type default))
          (fill (type none))
        )
        (polyline
          (pts
            (xy 3.048 -1.524)
            (xy 3.048 1.524)
          )
          (stroke (width 0.3302) (type default))
          (fill (type none))
        )
      )
      (symbol "C_100n_0402_12_1_1"
        (pin passive line (at 0 0 0) (length 2.032)
          (name "~" (effects (font (size 1.27 1.27))))
          (number "1" (effects (font (size 1.27 1.27))))
        )
        (pin passive line (at 5.08 0 180) (length 2.032)
          (name "~" (effects (font (size 1.27 1.27))))
          (number "2" (effects (font (size 1.27 1.27))))
        )
      )
    )
	(symbol "kria-k26-devboard:C_100n_0402_13" (pin_numbers hide) (pin_names hide) (in_bom yes) (on_board yes)
      (property "Reference" "C" (at 20.32 -5.08 0)
        (effects (font (size 1.27 1.27) (thickness 0.15)) (justify left bottom))
      )
      (property "Value" "C_100n_0402_13" (at 20.32 -10.16 0)
        (effects (font (size 1.27 1.27) (thickness 0.15)) (justify left bottom) hide)
      )
      (property "Footprint" "kria-k26-devboard-footprints:C_0402_1005Metric" (at 20.32 -12.7 0)
        (effects (font (size 1.27 1.27) (thickness 0.15)) (justify left bottom) hide)
      )
      (property "Datasheet" "https://search.murata.co.jp/Ceramy/image/img/A01X/G101/ENG/GRM155R61H104KE14-01.pdf" (at 20.32 -15.24 0)
        (effects (font (size 1.27 1.27) (thickness 0.15)) (justify left bottom) hide)
      )
      (property "MPN" "GRM155R61H104KE14D" (at 20.32 -17.78 0)
        (effects (font (size 1.27 1.27) (thickness 0.15)) (justify left bottom) hide)
      )
      (property "Manufacturer" "Murata" (at 20.32 -20.32 0)
        (effects (font (size 1.27 1.27) (thickness 0.15)) (justify left bottom) hide)
      )
      (property "License" "Apache-2.0" (at 20.32 -22.86 0)
        (effects (font (size 1.27 1.27) (thickness 0.15)) (justify left bottom) hide)
      )
      (property "Author" "Antmicro" (at 20.32 -25.4 0)
        (effects (font (size 1.27 1.27) (thickness 0.15)) (justify left bottom) hide)
      )
      (property "Val" "100n" (at 20.32 -7.62 0)
        (effects (font (size 1.27 1.27) (thickness 0.15)) (justify left bottom))
      )
      (property "Voltage" "50V" (at 20.32 -27.94 0)
        (effects (font (size 1.27 1.27)) (justify left bottom) hide)
      )
      (property "Dielectric" "X5R" (at 20.32 -30.48 0)
        (effects (font (size 1.27 1.27)) (justify left bottom) hide)
      )
      (property "ki_description" " " (at 0 0 0)
        (effects (font (size 1.27 1.27)) hide)
      )
      (symbol "C_100n_0402_13_0_1"
        (polyline
          (pts
            (xy 2.032 -1.524)
            (xy 2.032 1.524)
          )
          (stroke (width 0.3048) (type default))
          (fill (type none))
        )
        (polyline
          (pts
            (xy 3.048 -1.524)
            (xy 3.048 1.524)
          )
          (stroke (width 0.3302) (type default))
          (fill (type none))
        )
      )
      (symbol "C_100n_0402_13_1_1"
        (pin passive line (at 0 0 0) (length 2.032)
          (name "~" (effects (font (size 1.27 1.27))))
          (number "1" (effects (font (size 1.27 1.27))))
        )
        (pin passive line (at 5.08 0 180) (length 2.032)
          (name "~" (effects (font (size 1.27 1.27))))
          (number "2" (effects (font (size 1.27 1.27))))
        )
      )
    )
	(symbol "kria-k26-devboard:C_100n_0402_14" (pin_numbers hide) (pin_names hide) (in_bom yes) (on_board yes)
      (property "Reference" "C" (at 20.32 -5.08 0)
        (effects (font (size 1.27 1.27) (thickness 0.15)) (justify left bottom))
      )
      (property "Value" "C_100n_0402_14" (at 20.32 -10.16 0)
        (effects (font (size 1.27 1.27) (thickness 0.15)) (justify left bottom) hide)
      )
      (property "Footprint" "kria-k26-devboard-footprints:C_0402_1005Metric" (at 20.32 -12.7 0)
        (effects (font (size 1.27 1.27) (thickness 0.15)) (justify left bottom) hide)
      )
      (property "Datasheet" "https://search.murata.co.jp/Ceramy/image/img/A01X/G101/ENG/GRM155R61H104KE14-01.pdf" (at 20.32 -15.24 0)
        (effects (font (size 1.27 1.27) (thickness 0.15)) (justify left bottom) hide)
      )
      (property "MPN" "GRM155R61H104KE14D" (at 20.32 -17.78 0)
        (effects (font (size 1.27 1.27) (thickness 0.15)) (justify left bottom) hide)
      )
      (property "Manufacturer" "Murata" (at 20.32 -20.32 0)
        (effects (font (size 1.27 1.27) (thickness 0.15)) (justify left bottom) hide)
      )
      (property "License" "Apache-2.0" (at 20.32 -22.86 0)
        (effects (font (size 1.27 1.27) (thickness 0.15)) (justify left bottom) hide)
      )
      (property "Author" "Antmicro" (at 20.32 -25.4 0)
        (effects (font (size 1.27 1.27) (thickness 0.15)) (justify left bottom) hide)
      )
      (property "Val" "100n" (at 20.32 -7.62 0)
        (effects (font (size 1.27 1.27) (thickness 0.15)) (justify left bottom))
      )
      (property "Voltage" "50V" (at 20.32 -27.94 0)
        (effects (font (size 1.27 1.27)) (justify left bottom) hide)
      )
      (property "Dielectric" "X5R" (at 20.32 -30.48 0)
        (effects (font (size 1.27 1.27)) (justify left bottom) hide)
      )
      (property "ki_description" " " (at 0 0 0)
        (effects (font (size 1.27 1.27)) hide)
      )
      (symbol "C_100n_0402_14_0_1"
        (polyline
          (pts
            (xy 2.032 -1.524)
            (xy 2.032 1.524)
          )
          (stroke (width 0.3048) (type default))
          (fill (type none))
        )
        (polyline
          (pts
            (xy 3.048 -1.524)
            (xy 3.048 1.524)
          )
          (stroke (width 0.3302) (type default))
          (fill (type none))
        )
      )
      (symbol "C_100n_0402_14_1_1"
        (pin passive line (at 0 0 0) (length 2.032)
          (name "~" (effects (font (size 1.27 1.27))))
          (number "1" (effects (font (size 1.27 1.27))))
        )
        (pin passive line (at 5.08 0 180) (length 2.032)
          (name "~" (effects (font (size 1.27 1.27))))
          (number "2" (effects (font (size 1.27 1.27))))
        )
      )
    )
	(symbol "kria-k26-devboard:C_100n_0402_15" (pin_numbers hide) (pin_names hide) (in_bom yes) (on_board yes)
      (property "Reference" "C" (at 20.32 -5.08 0)
        (effects (font (size 1.27 1.27) (thickness 0.15)) (justify left bottom))
      )
      (property "Value" "C_100n_0402_15" (at 20.32 -10.16 0)
        (effects (font (size 1.27 1.27) (thickness 0.15)) (justify left bottom) hide)
      )
      (property "Footprint" "kria-k26-devboard-footprints:C_0402_1005Metric" (at 20.32 -12.7 0)
        (effects (font (size 1.27 1.27) (thickness 0.15)) (justify left bottom) hide)
      )
      (property "Datasheet" "https://search.murata.co.jp/Ceramy/image/img/A01X/G101/ENG/GRM155R61H104KE14-01.pdf" (at 20.32 -15.24 0)
        (effects (font (size 1.27 1.27) (thickness 0.15)) (justify left bottom) hide)
      )
      (property "MPN" "GRM155R61H104KE14D" (at 20.32 -17.78 0)
        (effects (font (size 1.27 1.27) (thickness 0.15)) (justify left bottom) hide)
      )
      (property "Manufacturer" "Murata" (at 20.32 -20.32 0)
        (effects (font (size 1.27 1.27) (thickness 0.15)) (justify left bottom) hide)
      )
      (property "License" "Apache-2.0" (at 20.32 -22.86 0)
        (effects (font (size 1.27 1.27) (thickness 0.15)) (justify left bottom) hide)
      )
      (property "Author" "Antmicro" (at 20.32 -25.4 0)
        (effects (font (size 1.27 1.27) (thickness 0.15)) (justify left bottom) hide)
      )
      (property "Val" "100n" (at 20.32 -7.62 0)
        (effects (font (size 1.27 1.27) (thickness 0.15)) (justify left bottom))
      )
      (property "Voltage" "50V" (at 20.32 -27.94 0)
        (effects (font (size 1.27 1.27)) (justify left bottom) hide)
      )
      (property "Dielectric" "X5R" (at 20.32 -30.48 0)
        (effects (font (size 1.27 1.27)) (justify left bottom) hide)
      )
      (property "ki_description" " " (at 0 0 0)
        (effects (font (size 1.27 1.27)) hide)
      )
      (symbol "C_100n_0402_15_0_1"
        (polyline
          (pts
            (xy 2.032 -1.524)
            (xy 2.032 1.524)
          )
          (stroke (width 0.3048) (type default))
          (fill (type none))
        )
        (polyline
          (pts
            (xy 3.048 -1.524)
            (xy 3.048 1.524)
          )
          (stroke (width 0.3302) (type default))
          (fill (type none))
        )
      )
      (symbol "C_100n_0402_15_1_1"
        (pin passive line (at 0 0 0) (length 2.032)
          (name "~" (effects (font (size 1.27 1.27))))
          (number "1" (effects (font (size 1.27 1.27))))
        )
        (pin passive line (at 5.08 0 180) (length 2.032)
          (name "~" (effects (font (size 1.27 1.27))))
          (number "2" (effects (font (size 1.27 1.27))))
        )
      )
    )
	(symbol "kria-k26-devboard:C_100n_0402_16" (pin_numbers hide) (pin_names hide) (in_bom yes) (on_board yes)
      (property "Reference" "C" (at 20.32 -5.08 0)
        (effects (font (size 1.27 1.27) (thickness 0.15)) (justify left bottom))
      )
      (property "Value" "C_100n_0402_16" (at 20.32 -10.16 0)
        (effects (font (size 1.27 1.27) (thickness 0.15)) (justify left bottom) hide)
      )
      (property "Footprint" "kria-k26-devboard-footprints:C_0402_1005Metric" (at 20.32 -12.7 0)
        (effects (font (size 1.27 1.27) (thickness 0.15)) (justify left bottom) hide)
      )
      (property "Datasheet" "https://search.murata.co.jp/Ceramy/image/img/A01X/G101/ENG/GRM155R61H104KE14-01.pdf" (at 20.32 -15.24 0)
        (effects (font (size 1.27 1.27) (thickness 0.15)) (justify left bottom) hide)
      )
      (property "MPN" "GRM155R61H104KE14D" (at 20.32 -17.78 0)
        (effects (font (size 1.27 1.27) (thickness 0.15)) (justify left bottom) hide)
      )
      (property "Manufacturer" "Murata" (at 20.32 -20.32 0)
        (effects (font (size 1.27 1.27) (thickness 0.15)) (justify left bottom) hide)
      )
      (property "License" "Apache-2.0" (at 20.32 -22.86 0)
        (effects (font (size 1.27 1.27) (thickness 0.15)) (justify left bottom) hide)
      )
      (property "Author" "Antmicro" (at 20.32 -25.4 0)
        (effects (font (size 1.27 1.27) (thickness 0.15)) (justify left bottom) hide)
      )
      (property "Val" "100n" (at 20.32 -7.62 0)
        (effects (font (size 1.27 1.27) (thickness 0.15)) (justify left bottom))
      )
      (property "Voltage" "50V" (at 20.32 -27.94 0)
        (effects (font (size 1.27 1.27)) (justify left bottom) hide)
      )
      (property "Dielectric" "X5R" (at 20.32 -30.48 0)
        (effects (font (size 1.27 1.27)) (justify left bottom) hide)
      )
      (property "ki_description" " " (at 0 0 0)
        (effects (font (size 1.27 1.27)) hide)
      )
      (symbol "C_100n_0402_16_0_1"
        (polyline
          (pts
            (xy 2.032 -1.524)
            (xy 2.032 1.524)
          )
          (stroke (width 0.3048) (type default))
          (fill (type none))
        )
        (polyline
          (pts
            (xy 3.048 -1.524)
            (xy 3.048 1.524)
          )
          (stroke (width 0.3302) (type default))
          (fill (type none))
        )
      )
      (symbol "C_100n_0402_16_1_1"
        (pin passive line (at 0 0 0) (length 2.032)
          (name "~" (effects (font (size 1.27 1.27))))
          (number "1" (effects (font (size 1.27 1.27))))
        )
        (pin passive line (at 5.08 0 180) (length 2.032)
          (name "~" (effects (font (size 1.27 1.27))))
          (number "2" (effects (font (size 1.27 1.27))))
        )
      )
    )
	(symbol "kria-k26-devboard:C_100n_0402_17" (pin_numbers hide) (pin_names hide) (in_bom yes) (on_board yes)
      (property "Reference" "C" (at 20.32 -5.08 0)
        (effects (font (size 1.27 1.27) (thickness 0.15)) (justify left bottom))
      )
      (property "Value" "C_100n_0402_17" (at 20.32 -10.16 0)
        (effects (font (size 1.27 1.27) (thickness 0.15)) (justify left bottom) hide)
      )
      (property "Footprint" "kria-k26-devboard-footprints:C_0402_1005Metric" (at 20.32 -12.7 0)
        (effects (font (size 1.27 1.27) (thickness 0.15)) (justify left bottom) hide)
      )
      (property "Datasheet" "https://search.murata.co.jp/Ceramy/image/img/A01X/G101/ENG/GRM155R61H104KE14-01.pdf" (at 20.32 -15.24 0)
        (effects (font (size 1.27 1.27) (thickness 0.15)) (justify left bottom) hide)
      )
      (property "MPN" "GRM155R61H104KE14D" (at 20.32 -17.78 0)
        (effects (font (size 1.27 1.27) (thickness 0.15)) (justify left bottom) hide)
      )
      (property "Manufacturer" "Murata" (at 20.32 -20.32 0)
        (effects (font (size 1.27 1.27) (thickness 0.15)) (justify left bottom) hide)
      )
      (property "License" "Apache-2.0" (at 20.32 -22.86 0)
        (effects (font (size 1.27 1.27) (thickness 0.15)) (justify left bottom) hide)
      )
      (property "Author" "Antmicro" (at 20.32 -25.4 0)
        (effects (font (size 1.27 1.27) (thickness 0.15)) (justify left bottom) hide)
      )
      (property "Val" "100n" (at 20.32 -7.62 0)
        (effects (font (size 1.27 1.27) (thickness 0.15)) (justify left bottom))
      )
      (property "Voltage" "50V" (at 20.32 -27.94 0)
        (effects (font (size 1.27 1.27)) (justify left bottom) hide)
      )
      (property "Dielectric" "X5R" (at 20.32 -30.48 0)
        (effects (font (size 1.27 1.27)) (justify left bottom) hide)
      )
      (property "ki_description" " " (at 0 0 0)
        (effects (font (size 1.27 1.27)) hide)
      )
      (symbol "C_100n_0402_17_0_1"
        (polyline
          (pts
            (xy 2.032 -1.524)
            (xy 2.032 1.524)
          )
          (stroke (width 0.3048) (type default))
          (fill (type none))
        )
        (polyline
          (pts
            (xy 3.048 -1.524)
            (xy 3.048 1.524)
          )
          (stroke (width 0.3302) (type default))
          (fill (type none))
        )
      )
      (symbol "C_100n_0402_17_1_1"
        (pin passive line (at 0 0 0) (length 2.032)
          (name "~" (effects (font (size 1.27 1.27))))
          (number "1" (effects (font (size 1.27 1.27))))
        )
        (pin passive line (at 5.08 0 180) (length 2.032)
          (name "~" (effects (font (size 1.27 1.27))))
          (number "2" (effects (font (size 1.27 1.27))))
        )
      )
    )
	(symbol "kria-k26-devboard:C_100n_0402_18" (pin_numbers hide) (pin_names hide) (in_bom yes) (on_board yes)
      (property "Reference" "C" (at 20.32 -5.08 0)
        (effects (font (size 1.27 1.27) (thickness 0.15)) (justify left bottom))
      )
      (property "Value" "C_100n_0402_18" (at 20.32 -10.16 0)
        (effects (font (size 1.27 1.27) (thickness 0.15)) (justify left bottom) hide)
      )
      (property "Footprint" "kria-k26-devboard-footprints:C_0402_1005Metric" (at 20.32 -12.7 0)
        (effects (font (size 1.27 1.27) (thickness 0.15)) (justify left bottom) hide)
      )
      (property "Datasheet" "https://search.murata.co.jp/Ceramy/image/img/A01X/G101/ENG/GRM155R61H104KE14-01.pdf" (at 20.32 -15.24 0)
        (effects (font (size 1.27 1.27) (thickness 0.15)) (justify left bottom) hide)
      )
      (property "MPN" "GRM155R61H104KE14D" (at 20.32 -17.78 0)
        (effects (font (size 1.27 1.27) (thickness 0.15)) (justify left bottom) hide)
      )
      (property "Manufacturer" "Murata" (at 20.32 -20.32 0)
        (effects (font (size 1.27 1.27) (thickness 0.15)) (justify left bottom) hide)
      )
      (property "License" "Apache-2.0" (at 20.32 -22.86 0)
        (effects (font (size 1.27 1.27) (thickness 0.15)) (justify left bottom) hide)
      )
      (property "Author" "Antmicro" (at 20.32 -25.4 0)
        (effects (font (size 1.27 1.27) (thickness 0.15)) (justify left bottom) hide)
      )
      (property "Val" "100n" (at 20.32 -7.62 0)
        (effects (font (size 1.27 1.27) (thickness 0.15)) (justify left bottom))
      )
      (property "Voltage" "50V" (at 20.32 -27.94 0)
        (effects (font (size 1.27 1.27)) (justify left bottom) hide)
      )
      (property "Dielectric" "X5R" (at 20.32 -30.48 0)
        (effects (font (size 1.27 1.27)) (justify left bottom) hide)
      )
      (property "ki_description" " " (at 0 0 0)
        (effects (font (size 1.27 1.27)) hide)
      )
      (symbol "C_100n_0402_18_0_1"
        (polyline
          (pts
            (xy 2.032 -1.524)
            (xy 2.032 1.524)
          )
          (stroke (width 0.3048) (type default))
          (fill (type none))
        )
        (polyline
          (pts
            (xy 3.048 -1.524)
            (xy 3.048 1.524)
          )
          (stroke (width 0.3302) (type default))
          (fill (type none))
        )
      )
      (symbol "C_100n_0402_18_1_1"
        (pin passive line (at 0 0 0) (length 2.032)
          (name "~" (effects (font (size 1.27 1.27))))
          (number "1" (effects (font (size 1.27 1.27))))
        )
        (pin passive line (at 5.08 0 180) (length 2.032)
          (name "~" (effects (font (size 1.27 1.27))))
          (number "2" (effects (font (size 1.27 1.27))))
        )
      )
    )
	(symbol "kria-k26-devboard:C_100n_0402_19" (pin_numbers hide) (pin_names hide) (in_bom yes) (on_board yes)
      (property "Reference" "C" (at 20.32 -5.08 0)
        (effects (font (size 1.27 1.27) (thickness 0.15)) (justify left bottom))
      )
      (property "Value" "C_100n_0402_19" (at 20.32 -10.16 0)
        (effects (font (size 1.27 1.27) (thickness 0.15)) (justify left bottom) hide)
      )
      (property "Footprint" "kria-k26-devboard-footprints:C_0402_1005Metric" (at 20.32 -12.7 0)
        (effects (font (size 1.27 1.27) (thickness 0.15)) (justify left bottom) hide)
      )
      (property "Datasheet" "https://search.murata.co.jp/Ceramy/image/img/A01X/G101/ENG/GRM155R61H104KE14-01.pdf" (at 20.32 -15.24 0)
        (effects (font (size 1.27 1.27) (thickness 0.15)) (justify left bottom) hide)
      )
      (property "MPN" "GRM155R61H104KE14D" (at 20.32 -17.78 0)
        (effects (font (size 1.27 1.27) (thickness 0.15)) (justify left bottom) hide)
      )
      (property "Manufacturer" "Murata" (at 20.32 -20.32 0)
        (effects (font (size 1.27 1.27) (thickness 0.15)) (justify left bottom) hide)
      )
      (property "License" "Apache-2.0" (at 20.32 -22.86 0)
        (effects (font (size 1.27 1.27) (thickness 0.15)) (justify left bottom) hide)
      )
      (property "Author" "Antmicro" (at 20.32 -25.4 0)
        (effects (font (size 1.27 1.27) (thickness 0.15)) (justify left bottom) hide)
      )
      (property "Val" "100n" (at 20.32 -7.62 0)
        (effects (font (size 1.27 1.27) (thickness 0.15)) (justify left bottom))
      )
      (property "Voltage" "50V" (at 20.32 -27.94 0)
        (effects (font (size 1.27 1.27)) (justify left bottom) hide)
      )
      (property "Dielectric" "X5R" (at 20.32 -30.48 0)
        (effects (font (size 1.27 1.27)) (justify left bottom) hide)
      )
      (property "ki_description" " " (at 0 0 0)
        (effects (font (size 1.27 1.27)) hide)
      )
      (symbol "C_100n_0402_19_0_1"
        (polyline
          (pts
            (xy 2.032 -1.524)
            (xy 2.032 1.524)
          )
          (stroke (width 0.3048) (type default))
          (fill (type none))
        )
        (polyline
          (pts
            (xy 3.048 -1.524)
            (xy 3.048 1.524)
          )
          (stroke (width 0.3302) (type default))
          (fill (type none))
        )
      )
      (symbol "C_100n_0402_19_1_1"
        (pin passive line (at 0 0 0) (length 2.032)
          (name "~" (effects (font (size 1.27 1.27))))
          (number "1" (effects (font (size 1.27 1.27))))
        )
        (pin passive line (at 5.08 0 180) (length 2.032)
          (name "~" (effects (font (size 1.27 1.27))))
          (number "2" (effects (font (size 1.27 1.27))))
        )
      )
    )
	(symbol "kria-k26-devboard:C_100n_0402_20" (pin_numbers hide) (pin_names hide) (in_bom yes) (on_board yes)
      (property "Reference" "C" (at 20.32 -5.08 0)
        (effects (font (size 1.27 1.27) (thickness 0.15)) (justify left bottom))
      )
      (property "Value" "C_100n_0402_20" (at 20.32 -10.16 0)
        (effects (font (size 1.27 1.27) (thickness 0.15)) (justify left bottom) hide)
      )
      (property "Footprint" "kria-k26-devboard-footprints:C_0402_1005Metric" (at 20.32 -12.7 0)
        (effects (font (size 1.27 1.27) (thickness 0.15)) (justify left bottom) hide)
      )
      (property "Datasheet" "https://search.murata.co.jp/Ceramy/image/img/A01X/G101/ENG/GRM155R61H104KE14-01.pdf" (at 20.32 -15.24 0)
        (effects (font (size 1.27 1.27) (thickness 0.15)) (justify left bottom) hide)
      )
      (property "MPN" "GRM155R61H104KE14D" (at 20.32 -17.78 0)
        (effects (font (size 1.27 1.27) (thickness 0.15)) (justify left bottom) hide)
      )
      (property "Manufacturer" "Murata" (at 20.32 -20.32 0)
        (effects (font (size 1.27 1.27) (thickness 0.15)) (justify left bottom) hide)
      )
      (property "License" "Apache-2.0" (at 20.32 -22.86 0)
        (effects (font (size 1.27 1.27) (thickness 0.15)) (justify left bottom) hide)
      )
      (property "Author" "Antmicro" (at 20.32 -25.4 0)
        (effects (font (size 1.27 1.27) (thickness 0.15)) (justify left bottom) hide)
      )
      (property "Val" "100n" (at 20.32 -7.62 0)
        (effects (font (size 1.27 1.27) (thickness 0.15)) (justify left bottom))
      )
      (property "Voltage" "50V" (at 20.32 -27.94 0)
        (effects (font (size 1.27 1.27)) (justify left bottom) hide)
      )
      (property "Dielectric" "X5R" (at 20.32 -30.48 0)
        (effects (font (size 1.27 1.27)) (justify left bottom) hide)
      )
      (property "ki_description" " " (at 0 0 0)
        (effects (font (size 1.27 1.27)) hide)
      )
      (symbol "C_100n_0402_20_0_1"
        (polyline
          (pts
            (xy 2.032 -1.524)
            (xy 2.032 1.524)
          )
          (stroke (width 0.3048) (type default))
          (fill (type none))
        )
        (polyline
          (pts
            (xy 3.048 -1.524)
            (xy 3.048 1.524)
          )
          (stroke (width 0.3302) (type default))
          (fill (type none))
        )
      )
      (symbol "C_100n_0402_20_1_1"
        (pin passive line (at 0 0 0) (length 2.032)
          (name "~" (effects (font (size 1.27 1.27))))
          (number "1" (effects (font (size 1.27 1.27))))
        )
        (pin passive line (at 5.08 0 180) (length 2.032)
          (name "~" (effects (font (size 1.27 1.27))))
          (number "2" (effects (font (size 1.27 1.27))))
        )
      )
    )
	(symbol "kria-k26-devboard:C_100n_0402_21" (pin_numbers hide) (pin_names hide) (in_bom yes) (on_board yes)
      (property "Reference" "C" (at 20.32 -5.08 0)
        (effects (font (size 1.27 1.27) (thickness 0.15)) (justify left bottom))
      )
      (property "Value" "C_100n_0402_21" (at 20.32 -10.16 0)
        (effects (font (size 1.27 1.27) (thickness 0.15)) (justify left bottom) hide)
      )
      (property "Footprint" "kria-k26-devboard-footprints:C_0402_1005Metric" (at 20.32 -12.7 0)
        (effects (font (size 1.27 1.27) (thickness 0.15)) (justify left bottom) hide)
      )
      (property "Datasheet" "https://search.murata.co.jp/Ceramy/image/img/A01X/G101/ENG/GRM155R61H104KE14-01.pdf" (at 20.32 -15.24 0)
        (effects (font (size 1.27 1.27) (thickness 0.15)) (justify left bottom) hide)
      )
      (property "MPN" "GRM155R61H104KE14D" (at 20.32 -17.78 0)
        (effects (font (size 1.27 1.27) (thickness 0.15)) (justify left bottom) hide)
      )
      (property "Manufacturer" "Murata" (at 20.32 -20.32 0)
        (effects (font (size 1.27 1.27) (thickness 0.15)) (justify left bottom) hide)
      )
      (property "License" "Apache-2.0" (at 20.32 -22.86 0)
        (effects (font (size 1.27 1.27) (thickness 0.15)) (justify left bottom) hide)
      )
      (property "Author" "Antmicro" (at 20.32 -25.4 0)
        (effects (font (size 1.27 1.27) (thickness 0.15)) (justify left bottom) hide)
      )
      (property "Val" "100n" (at 20.32 -7.62 0)
        (effects (font (size 1.27 1.27) (thickness 0.15)) (justify left bottom))
      )
      (property "Voltage" "50V" (at 20.32 -27.94 0)
        (effects (font (size 1.27 1.27)) (justify left bottom) hide)
      )
      (property "Dielectric" "X5R" (at 20.32 -30.48 0)
        (effects (font (size 1.27 1.27)) (justify left bottom) hide)
      )
      (property "ki_description" " " (at 0 0 0)
        (effects (font (size 1.27 1.27)) hide)
      )
      (symbol "C_100n_0402_21_0_1"
        (polyline
          (pts
            (xy 2.032 -1.524)
            (xy 2.032 1.524)
          )
          (stroke (width 0.3048) (type default))
          (fill (type none))
        )
        (polyline
          (pts
            (xy 3.048 -1.524)
            (xy 3.048 1.524)
          )
          (stroke (width 0.3302) (type default))
          (fill (type none))
        )
      )
      (symbol "C_100n_0402_21_1_1"
        (pin passive line (at 0 0 0) (length 2.032)
          (name "~" (effects (font (size 1.27 1.27))))
          (number "1" (effects (font (size 1.27 1.27))))
        )
        (pin passive line (at 5.08 0 180) (length 2.032)
          (name "~" (effects (font (size 1.27 1.27))))
          (number "2" (effects (font (size 1.27 1.27))))
        )
      )
    )
	(symbol "kria-k26-devboard:C_100n_0402_22" (pin_numbers hide) (pin_names hide) (in_bom yes) (on_board yes)
      (property "Reference" "C" (at 20.32 -5.08 0)
        (effects (font (size 1.27 1.27) (thickness 0.15)) (justify left bottom))
      )
      (property "Value" "C_100n_0402_22" (at 20.32 -10.16 0)
        (effects (font (size 1.27 1.27) (thickness 0.15)) (justify left bottom) hide)
      )
      (property "Footprint" "kria-k26-devboard-footprints:C_0402_1005Metric" (at 20.32 -12.7 0)
        (effects (font (size 1.27 1.27) (thickness 0.15)) (justify left bottom) hide)
      )
      (property "Datasheet" "https://search.murata.co.jp/Ceramy/image/img/A01X/G101/ENG/GRM155R61H104KE14-01.pdf" (at 20.32 -15.24 0)
        (effects (font (size 1.27 1.27) (thickness 0.15)) (justify left bottom) hide)
      )
      (property "MPN" "GRM155R61H104KE14D" (at 20.32 -17.78 0)
        (effects (font (size 1.27 1.27) (thickness 0.15)) (justify left bottom) hide)
      )
      (property "Manufacturer" "Murata" (at 20.32 -20.32 0)
        (effects (font (size 1.27 1.27) (thickness 0.15)) (justify left bottom) hide)
      )
      (property "License" "Apache-2.0" (at 20.32 -22.86 0)
        (effects (font (size 1.27 1.27) (thickness 0.15)) (justify left bottom) hide)
      )
      (property "Author" "Antmicro" (at 20.32 -25.4 0)
        (effects (font (size 1.27 1.27) (thickness 0.15)) (justify left bottom) hide)
      )
      (property "Val" "100n" (at 20.32 -7.62 0)
        (effects (font (size 1.27 1.27) (thickness 0.15)) (justify left bottom))
      )
      (property "Voltage" "50V" (at 20.32 -27.94 0)
        (effects (font (size 1.27 1.27)) (justify left bottom) hide)
      )
      (property "Dielectric" "X5R" (at 20.32 -30.48 0)
        (effects (font (size 1.27 1.27)) (justify left bottom) hide)
      )
      (property "ki_description" " " (at 0 0 0)
        (effects (font (size 1.27 1.27)) hide)
      )
      (symbol "C_100n_0402_22_0_1"
        (polyline
          (pts
            (xy 2.032 -1.524)
            (xy 2.032 1.524)
          )
          (stroke (width 0.3048) (type default))
          (fill (type none))
        )
        (polyline
          (pts
            (xy 3.048 -1.524)
            (xy 3.048 1.524)
          )
          (stroke (width 0.3302) (type default))
          (fill (type none))
        )
      )
      (symbol "C_100n_0402_22_1_1"
        (pin passive line (at 0 0 0) (length 2.032)
          (name "~" (effects (font (size 1.27 1.27))))
          (number "1" (effects (font (size 1.27 1.27))))
        )
        (pin passive line (at 5.08 0 180) (length 2.032)
          (name "~" (effects (font (size 1.27 1.27))))
          (number "2" (effects (font (size 1.27 1.27))))
        )
      )
    )
	(symbol "kria-k26-devboard:C_100n_0402_23" (pin_numbers hide) (pin_names hide) (in_bom yes) (on_board yes)
      (property "Reference" "C" (at 20.32 -5.08 0)
        (effects (font (size 1.27 1.27) (thickness 0.15)) (justify left bottom))
      )
      (property "Value" "C_100n_0402_23" (at 20.32 -10.16 0)
        (effects (font (size 1.27 1.27) (thickness 0.15)) (justify left bottom) hide)
      )
      (property "Footprint" "kria-k26-devboard-footprints:C_0402_1005Metric" (at 20.32 -12.7 0)
        (effects (font (size 1.27 1.27) (thickness 0.15)) (justify left bottom) hide)
      )
      (property "Datasheet" "https://search.murata.co.jp/Ceramy/image/img/A01X/G101/ENG/GRM155R61H104KE14-01.pdf" (at 20.32 -15.24 0)
        (effects (font (size 1.27 1.27) (thickness 0.15)) (justify left bottom) hide)
      )
      (property "MPN" "GRM155R61H104KE14D" (at 20.32 -17.78 0)
        (effects (font (size 1.27 1.27) (thickness 0.15)) (justify left bottom) hide)
      )
      (property "Manufacturer" "Murata" (at 20.32 -20.32 0)
        (effects (font (size 1.27 1.27) (thickness 0.15)) (justify left bottom) hide)
      )
      (property "License" "Apache-2.0" (at 20.32 -22.86 0)
        (effects (font (size 1.27 1.27) (thickness 0.15)) (justify left bottom) hide)
      )
      (property "Author" "Antmicro" (at 20.32 -25.4 0)
        (effects (font (size 1.27 1.27) (thickness 0.15)) (justify left bottom) hide)
      )
      (property "Val" "100n" (at 20.32 -7.62 0)
        (effects (font (size 1.27 1.27) (thickness 0.15)) (justify left bottom))
      )
      (property "Voltage" "50V" (at 20.32 -27.94 0)
        (effects (font (size 1.27 1.27)) (justify left bottom) hide)
      )
      (property "Dielectric" "X5R" (at 20.32 -30.48 0)
        (effects (font (size 1.27 1.27)) (justify left bottom) hide)
      )
      (property "ki_description" " " (at 0 0 0)
        (effects (font (size 1.27 1.27)) hide)
      )
      (symbol "C_100n_0402_23_0_1"
        (polyline
          (pts
            (xy 2.032 -1.524)
            (xy 2.032 1.524)
          )
          (stroke (width 0.3048) (type default))
          (fill (type none))
        )
        (polyline
          (pts
            (xy 3.048 -1.524)
            (xy 3.048 1.524)
          )
          (stroke (width 0.3302) (type default))
          (fill (type none))
        )
      )
      (symbol "C_100n_0402_23_1_1"
        (pin passive line (at 0 0 0) (length 2.032)
          (name "~" (effects (font (size 1.27 1.27))))
          (number "1" (effects (font (size 1.27 1.27))))
        )
        (pin passive line (at 5.08 0 180) (length 2.032)
          (name "~" (effects (font (size 1.27 1.27))))
          (number "2" (effects (font (size 1.27 1.27))))
        )
      )
    )
	(symbol "kria-k26-devboard:C_100n_0402_24" (pin_numbers hide) (pin_names hide) (in_bom yes) (on_board yes)
      (property "Reference" "C" (at 20.32 -5.08 0)
        (effects (font (size 1.27 1.27) (thickness 0.15)) (justify left bottom))
      )
      (property "Value" "C_100n_0402_24" (at 20.32 -10.16 0)
        (effects (font (size 1.27 1.27) (thickness 0.15)) (justify left bottom) hide)
      )
      (property "Footprint" "kria-k26-devboard-footprints:C_0402_1005Metric" (at 20.32 -12.7 0)
        (effects (font (size 1.27 1.27) (thickness 0.15)) (justify left bottom) hide)
      )
      (property "Datasheet" "https://search.murata.co.jp/Ceramy/image/img/A01X/G101/ENG/GRM155R61H104KE14-01.pdf" (at 20.32 -15.24 0)
        (effects (font (size 1.27 1.27) (thickness 0.15)) (justify left bottom) hide)
      )
      (property "MPN" "GRM155R61H104KE14D" (at 20.32 -17.78 0)
        (effects (font (size 1.27 1.27) (thickness 0.15)) (justify left bottom) hide)
      )
      (property "Manufacturer" "Murata" (at 20.32 -20.32 0)
        (effects (font (size 1.27 1.27) (thickness 0.15)) (justify left bottom) hide)
      )
      (property "License" "Apache-2.0" (at 20.32 -22.86 0)
        (effects (font (size 1.27 1.27) (thickness 0.15)) (justify left bottom) hide)
      )
      (property "Author" "Antmicro" (at 20.32 -25.4 0)
        (effects (font (size 1.27 1.27) (thickness 0.15)) (justify left bottom) hide)
      )
      (property "Val" "100n" (at 20.32 -7.62 0)
        (effects (font (size 1.27 1.27) (thickness 0.15)) (justify left bottom))
      )
      (property "Voltage" "50V" (at 20.32 -27.94 0)
        (effects (font (size 1.27 1.27)) (justify left bottom) hide)
      )
      (property "Dielectric" "X5R" (at 20.32 -30.48 0)
        (effects (font (size 1.27 1.27)) (justify left bottom) hide)
      )
      (property "ki_description" " " (at 0 0 0)
        (effects (font (size 1.27 1.27)) hide)
      )
      (symbol "C_100n_0402_24_0_1"
        (polyline
          (pts
            (xy 2.032 -1.524)
            (xy 2.032 1.524)
          )
          (stroke (width 0.3048) (type default))
          (fill (type none))
        )
        (polyline
          (pts
            (xy 3.048 -1.524)
            (xy 3.048 1.524)
          )
          (stroke (width 0.3302) (type default))
          (fill (type none))
        )
      )
      (symbol "C_100n_0402_24_1_1"
        (pin passive line (at 0 0 0) (length 2.032)
          (name "~" (effects (font (size 1.27 1.27))))
          (number "1" (effects (font (size 1.27 1.27))))
        )
        (pin passive line (at 5.08 0 180) (length 2.032)
          (name "~" (effects (font (size 1.27 1.27))))
          (number "2" (effects (font (size 1.27 1.27))))
        )
      )
    )
	(symbol "kria-k26-devboard:C_100n_0402_25" (pin_numbers hide) (pin_names hide) (in_bom yes) (on_board yes)
      (property "Reference" "C" (at 20.32 -5.08 0)
        (effects (font (size 1.27 1.27) (thickness 0.15)) (justify left bottom))
      )
      (property "Value" "C_100n_0402_25" (at 20.32 -10.16 0)
        (effects (font (size 1.27 1.27) (thickness 0.15)) (justify left bottom) hide)
      )
      (property "Footprint" "kria-k26-devboard-footprints:C_0402_1005Metric" (at 20.32 -12.7 0)
        (effects (font (size 1.27 1.27) (thickness 0.15)) (justify left bottom) hide)
      )
      (property "Datasheet" "https://search.murata.co.jp/Ceramy/image/img/A01X/G101/ENG/GRM155R61H104KE14-01.pdf" (at 20.32 -15.24 0)
        (effects (font (size 1.27 1.27) (thickness 0.15)) (justify left bottom) hide)
      )
      (property "MPN" "GRM155R61H104KE14D" (at 20.32 -17.78 0)
        (effects (font (size 1.27 1.27) (thickness 0.15)) (justify left bottom) hide)
      )
      (property "Manufacturer" "Murata" (at 20.32 -20.32 0)
        (effects (font (size 1.27 1.27) (thickness 0.15)) (justify left bottom) hide)
      )
      (property "License" "Apache-2.0" (at 20.32 -22.86 0)
        (effects (font (size 1.27 1.27) (thickness 0.15)) (justify left bottom) hide)
      )
      (property "Author" "Antmicro" (at 20.32 -25.4 0)
        (effects (font (size 1.27 1.27) (thickness 0.15)) (justify left bottom) hide)
      )
      (property "Val" "100n" (at 20.32 -7.62 0)
        (effects (font (size 1.27 1.27) (thickness 0.15)) (justify left bottom))
      )
      (property "Voltage" "50V" (at 20.32 -27.94 0)
        (effects (font (size 1.27 1.27)) (justify left bottom) hide)
      )
      (property "Dielectric" "X5R" (at 20.32 -30.48 0)
        (effects (font (size 1.27 1.27)) (justify left bottom) hide)
      )
      (property "ki_description" " " (at 0 0 0)
        (effects (font (size 1.27 1.27)) hide)
      )
      (symbol "C_100n_0402_25_0_1"
        (polyline
          (pts
            (xy 2.032 -1.524)
            (xy 2.032 1.524)
          )
          (stroke (width 0.3048) (type default))
          (fill (type none))
        )
        (polyline
          (pts
            (xy 3.048 -1.524)
            (xy 3.048 1.524)
          )
          (stroke (width 0.3302) (type default))
          (fill (type none))
        )
      )
      (symbol "C_100n_0402_25_1_1"
        (pin passive line (at 0 0 0) (length 2.032)
          (name "~" (effects (font (size 1.27 1.27))))
          (number "1" (effects (font (size 1.27 1.27))))
        )
        (pin passive line (at 5.08 0 180) (length 2.032)
          (name "~" (effects (font (size 1.27 1.27))))
          (number "2" (effects (font (size 1.27 1.27))))
        )
      )
    )
	(symbol "kria-k26-devboard:C_100n_0402_26" (pin_numbers hide) (pin_names hide) (in_bom yes) (on_board yes)
      (property "Reference" "C" (at 20.32 -5.08 0)
        (effects (font (size 1.27 1.27) (thickness 0.15)) (justify left bottom))
      )
      (property "Value" "C_100n_0402_26" (at 20.32 -10.16 0)
        (effects (font (size 1.27 1.27) (thickness 0.15)) (justify left bottom) hide)
      )
      (property "Footprint" "kria-k26-devboard-footprints:C_0402_1005Metric" (at 20.32 -12.7 0)
        (effects (font (size 1.27 1.27) (thickness 0.15)) (justify left bottom) hide)
      )
      (property "Datasheet" "https://search.murata.co.jp/Ceramy/image/img/A01X/G101/ENG/GRM155R61H104KE14-01.pdf" (at 20.32 -15.24 0)
        (effects (font (size 1.27 1.27) (thickness 0.15)) (justify left bottom) hide)
      )
      (property "MPN" "GRM155R61H104KE14D" (at 20.32 -17.78 0)
        (effects (font (size 1.27 1.27) (thickness 0.15)) (justify left bottom) hide)
      )
      (property "Manufacturer" "Murata" (at 20.32 -20.32 0)
        (effects (font (size 1.27 1.27) (thickness 0.15)) (justify left bottom) hide)
      )
      (property "License" "Apache-2.0" (at 20.32 -22.86 0)
        (effects (font (size 1.27 1.27) (thickness 0.15)) (justify left bottom) hide)
      )
      (property "Author" "Antmicro" (at 20.32 -25.4 0)
        (effects (font (size 1.27 1.27) (thickness 0.15)) (justify left bottom) hide)
      )
      (property "Val" "100n" (at 20.32 -7.62 0)
        (effects (font (size 1.27 1.27) (thickness 0.15)) (justify left bottom))
      )
      (property "Voltage" "50V" (at 20.32 -27.94 0)
        (effects (font (size 1.27 1.27)) (justify left bottom) hide)
      )
      (property "Dielectric" "X5R" (at 20.32 -30.48 0)
        (effects (font (size 1.27 1.27)) (justify left bottom) hide)
      )
      (property "ki_description" " " (at 0 0 0)
        (effects (font (size 1.27 1.27)) hide)
      )
      (symbol "C_100n_0402_26_0_1"
        (polyline
          (pts
            (xy 2.032 -1.524)
            (xy 2.032 1.524)
          )
          (stroke (width 0.3048) (type default))
          (fill (type none))
        )
        (polyline
          (pts
            (xy 3.048 -1.524)
            (xy 3.048 1.524)
          )
          (stroke (width 0.3302) (type default))
          (fill (type none))
        )
      )
      (symbol "C_100n_0402_26_1_1"
        (pin passive line (at 0 0 0) (length 2.032)
          (name "~" (effects (font (size 1.27 1.27))))
          (number "1" (effects (font (size 1.27 1.27))))
        )
        (pin passive line (at 5.08 0 180) (length 2.032)
          (name "~" (effects (font (size 1.27 1.27))))
          (number "2" (effects (font (size 1.27 1.27))))
        )
      )
    )
	(symbol "kria-k26-devboard:C_100n_0402_27" (pin_numbers hide) (pin_names hide) (in_bom yes) (on_board yes)
      (property "Reference" "C" (at 20.32 -5.08 0)
        (effects (font (size 1.27 1.27) (thickness 0.15)) (justify left bottom))
      )
      (property "Value" "C_100n_0402_27" (at 20.32 -10.16 0)
        (effects (font (size 1.27 1.27) (thickness 0.15)) (justify left bottom) hide)
      )
      (property "Footprint" "kria-k26-devboard-footprints:C_0402_1005Metric" (at 20.32 -12.7 0)
        (effects (font (size 1.27 1.27) (thickness 0.15)) (justify left bottom) hide)
      )
      (property "Datasheet" "https://search.murata.co.jp/Ceramy/image/img/A01X/G101/ENG/GRM155R61H104KE14-01.pdf" (at 20.32 -15.24 0)
        (effects (font (size 1.27 1.27) (thickness 0.15)) (justify left bottom) hide)
      )
      (property "MPN" "GRM155R61H104KE14D" (at 20.32 -17.78 0)
        (effects (font (size 1.27 1.27) (thickness 0.15)) (justify left bottom) hide)
      )
      (property "Manufacturer" "Murata" (at 20.32 -20.32 0)
        (effects (font (size 1.27 1.27) (thickness 0.15)) (justify left bottom) hide)
      )
      (property "License" "Apache-2.0" (at 20.32 -22.86 0)
        (effects (font (size 1.27 1.27) (thickness 0.15)) (justify left bottom) hide)
      )
      (property "Author" "Antmicro" (at 20.32 -25.4 0)
        (effects (font (size 1.27 1.27) (thickness 0.15)) (justify left bottom) hide)
      )
      (property "Val" "100n" (at 20.32 -7.62 0)
        (effects (font (size 1.27 1.27) (thickness 0.15)) (justify left bottom))
      )
      (property "Voltage" "50V" (at 20.32 -27.94 0)
        (effects (font (size 1.27 1.27)) (justify left bottom) hide)
      )
      (property "Dielectric" "X5R" (at 20.32 -30.48 0)
        (effects (font (size 1.27 1.27)) (justify left bottom) hide)
      )
      (property "ki_description" " " (at 0 0 0)
        (effects (font (size 1.27 1.27)) hide)
      )
      (symbol "C_100n_0402_27_0_1"
        (polyline
          (pts
            (xy 2.032 -1.524)
            (xy 2.032 1.524)
          )
          (stroke (width 0.3048) (type default))
          (fill (type none))
        )
        (polyline
          (pts
            (xy 3.048 -1.524)
            (xy 3.048 1.524)
          )
          (stroke (width 0.3302) (type default))
          (fill (type none))
        )
      )
      (symbol "C_100n_0402_27_1_1"
        (pin passive line (at 0 0 0) (length 2.032)
          (name "~" (effects (font (size 1.27 1.27))))
          (number "1" (effects (font (size 1.27 1.27))))
        )
        (pin passive line (at 5.08 0 180) (length 2.032)
          (name "~" (effects (font (size 1.27 1.27))))
          (number "2" (effects (font (size 1.27 1.27))))
        )
      )
    )
	(symbol "kria-k26-devboard:C_100n_0402_28" (pin_numbers hide) (pin_names hide) (in_bom yes) (on_board yes)
      (property "Reference" "C" (at 20.32 -5.08 0)
        (effects (font (size 1.27 1.27) (thickness 0.15)) (justify left bottom))
      )
      (property "Value" "C_100n_0402_28" (at 20.32 -10.16 0)
        (effects (font (size 1.27 1.27) (thickness 0.15)) (justify left bottom) hide)
      )
      (property "Footprint" "kria-k26-devboard-footprints:C_0402_1005Metric" (at 20.32 -12.7 0)
        (effects (font (size 1.27 1.27) (thickness 0.15)) (justify left bottom) hide)
      )
      (property "Datasheet" "https://search.murata.co.jp/Ceramy/image/img/A01X/G101/ENG/GRM155R61H104KE14-01.pdf" (at 20.32 -15.24 0)
        (effects (font (size 1.27 1.27) (thickness 0.15)) (justify left bottom) hide)
      )
      (property "MPN" "GRM155R61H104KE14D" (at 20.32 -17.78 0)
        (effects (font (size 1.27 1.27) (thickness 0.15)) (justify left bottom) hide)
      )
      (property "Manufacturer" "Murata" (at 20.32 -20.32 0)
        (effects (font (size 1.27 1.27) (thickness 0.15)) (justify left bottom) hide)
      )
      (property "License" "Apache-2.0" (at 20.32 -22.86 0)
        (effects (font (size 1.27 1.27) (thickness 0.15)) (justify left bottom) hide)
      )
      (property "Author" "Antmicro" (at 20.32 -25.4 0)
        (effects (font (size 1.27 1.27) (thickness 0.15)) (justify left bottom) hide)
      )
      (property "Val" "100n" (at 20.32 -7.62 0)
        (effects (font (size 1.27 1.27) (thickness 0.15)) (justify left bottom))
      )
      (property "Voltage" "50V" (at 20.32 -27.94 0)
        (effects (font (size 1.27 1.27)) (justify left bottom) hide)
      )
      (property "Dielectric" "X5R" (at 20.32 -30.48 0)
        (effects (font (size 1.27 1.27)) (justify left bottom) hide)
      )
      (property "ki_description" " " (at 0 0 0)
        (effects (font (size 1.27 1.27)) hide)
      )
      (symbol "C_100n_0402_28_0_1"
        (polyline
          (pts
            (xy 2.032 -1.524)
            (xy 2.032 1.524)
          )
          (stroke (width 0.3048) (type default))
          (fill (type none))
        )
        (polyline
          (pts
            (xy 3.048 -1.524)
            (xy 3.048 1.524)
          )
          (stroke (width 0.3302) (type default))
          (fill (type none))
        )
      )
      (symbol "C_100n_0402_28_1_1"
        (pin passive line (at 0 0 0) (length 2.032)
          (name "~" (effects (font (size 1.27 1.27))))
          (number "1" (effects (font (size 1.27 1.27))))
        )
        (pin passive line (at 5.08 0 180) (length 2.032)
          (name "~" (effects (font (size 1.27 1.27))))
          (number "2" (effects (font (size 1.27 1.27))))
        )
      )
    )
	(symbol "kria-k26-devboard:C_100n_0402_29" (pin_numbers hide) (pin_names hide) (in_bom yes) (on_board yes)
      (property "Reference" "C" (at 20.32 -5.08 0)
        (effects (font (size 1.27 1.27) (thickness 0.15)) (justify left bottom))
      )
      (property "Value" "C_100n_0402_29" (at 20.32 -10.16 0)
        (effects (font (size 1.27 1.27) (thickness 0.15)) (justify left bottom) hide)
      )
      (property "Footprint" "kria-k26-devboard-footprints:C_0402_1005Metric" (at 20.32 -12.7 0)
        (effects (font (size 1.27 1.27) (thickness 0.15)) (justify left bottom) hide)
      )
      (property "Datasheet" "https://search.murata.co.jp/Ceramy/image/img/A01X/G101/ENG/GRM155R61H104KE14-01.pdf" (at 20.32 -15.24 0)
        (effects (font (size 1.27 1.27) (thickness 0.15)) (justify left bottom) hide)
      )
      (property "MPN" "GRM155R61H104KE14D" (at 20.32 -17.78 0)
        (effects (font (size 1.27 1.27) (thickness 0.15)) (justify left bottom) hide)
      )
      (property "Manufacturer" "Murata" (at 20.32 -20.32 0)
        (effects (font (size 1.27 1.27) (thickness 0.15)) (justify left bottom) hide)
      )
      (property "License" "Apache-2.0" (at 20.32 -22.86 0)
        (effects (font (size 1.27 1.27) (thickness 0.15)) (justify left bottom) hide)
      )
      (property "Author" "Antmicro" (at 20.32 -25.4 0)
        (effects (font (size 1.27 1.27) (thickness 0.15)) (justify left bottom) hide)
      )
      (property "Val" "100n" (at 20.32 -7.62 0)
        (effects (font (size 1.27 1.27) (thickness 0.15)) (justify left bottom))
      )
      (property "Voltage" "50V" (at 20.32 -27.94 0)
        (effects (font (size 1.27 1.27)) (justify left bottom) hide)
      )
      (property "Dielectric" "X5R" (at 20.32 -30.48 0)
        (effects (font (size 1.27 1.27)) (justify left bottom) hide)
      )
      (property "ki_description" " " (at 0 0 0)
        (effects (font (size 1.27 1.27)) hide)
      )
      (symbol "C_100n_0402_29_0_1"
        (polyline
          (pts
            (xy 2.032 -1.524)
            (xy 2.032 1.524)
          )
          (stroke (width 0.3048) (type default))
          (fill (type none))
        )
        (polyline
          (pts
            (xy 3.048 -1.524)
            (xy 3.048 1.524)
          )
          (stroke (width 0.3302) (type default))
          (fill (type none))
        )
      )
      (symbol "C_100n_0402_29_1_1"
        (pin passive line (at 0 0 0) (length 2.032)
          (name "~" (effects (font (size 1.27 1.27))))
          (number "1" (effects (font (size 1.27 1.27))))
        )
        (pin passive line (at 5.08 0 180) (length 2.032)
          (name "~" (effects (font (size 1.27 1.27))))
          (number "2" (effects (font (size 1.27 1.27))))
        )
      )
    )
	(symbol "kria-k26-devboard:C_100n_0402_30" (pin_numbers hide) (pin_names hide) (in_bom yes) (on_board yes)
      (property "Reference" "C" (at 20.32 -5.08 0)
        (effects (font (size 1.27 1.27) (thickness 0.15)) (justify left bottom))
      )
      (property "Value" "C_100n_0402_30" (at 20.32 -10.16 0)
        (effects (font (size 1.27 1.27) (thickness 0.15)) (justify left bottom) hide)
      )
      (property "Footprint" "kria-k26-devboard-footprints:C_0402_1005Metric" (at 20.32 -12.7 0)
        (effects (font (size 1.27 1.27) (thickness 0.15)) (justify left bottom) hide)
      )
      (property "Datasheet" "https://search.murata.co.jp/Ceramy/image/img/A01X/G101/ENG/GRM155R61H104KE14-01.pdf" (at 20.32 -15.24 0)
        (effects (font (size 1.27 1.27) (thickness 0.15)) (justify left bottom) hide)
      )
      (property "MPN" "GRM155R61H104KE14D" (at 20.32 -17.78 0)
        (effects (font (size 1.27 1.27) (thickness 0.15)) (justify left bottom) hide)
      )
      (property "Manufacturer" "Murata" (at 20.32 -20.32 0)
        (effects (font (size 1.27 1.27) (thickness 0.15)) (justify left bottom) hide)
      )
      (property "License" "Apache-2.0" (at 20.32 -22.86 0)
        (effects (font (size 1.27 1.27) (thickness 0.15)) (justify left bottom) hide)
      )
      (property "Author" "Antmicro" (at 20.32 -25.4 0)
        (effects (font (size 1.27 1.27) (thickness 0.15)) (justify left bottom) hide)
      )
      (property "Val" "100n" (at 20.32 -7.62 0)
        (effects (font (size 1.27 1.27) (thickness 0.15)) (justify left bottom))
      )
      (property "Voltage" "50V" (at 20.32 -27.94 0)
        (effects (font (size 1.27 1.27)) (justify left bottom) hide)
      )
      (property "Dielectric" "X5R" (at 20.32 -30.48 0)
        (effects (font (size 1.27 1.27)) (justify left bottom) hide)
      )
      (property "ki_description" " " (at 0 0 0)
        (effects (font (size 1.27 1.27)) hide)
      )
      (symbol "C_100n_0402_30_0_1"
        (polyline
          (pts
            (xy 2.032 -1.524)
            (xy 2.032 1.524)
          )
          (stroke (width 0.3048) (type default))
          (fill (type none))
        )
        (polyline
          (pts
            (xy 3.048 -1.524)
            (xy 3.048 1.524)
          )
          (stroke (width 0.3302) (type default))
          (fill (type none))
        )
      )
      (symbol "C_100n_0402_30_1_1"
        (pin passive line (at 0 0 0) (length 2.032)
          (name "~" (effects (font (size 1.27 1.27))))
          (number "1" (effects (font (size 1.27 1.27))))
        )
        (pin passive line (at 5.08 0 180) (length 2.032)
          (name "~" (effects (font (size 1.27 1.27))))
          (number "2" (effects (font (size 1.27 1.27))))
        )
      )
    )
	(symbol "kria-k26-devboard:C_100n_0402_31" (pin_numbers hide) (pin_names hide) (in_bom yes) (on_board yes)
      (property "Reference" "C" (at 20.32 -5.08 0)
        (effects (font (size 1.27 1.27) (thickness 0.15)) (justify left bottom))
      )
      (property "Value" "C_100n_0402_31" (at 20.32 -10.16 0)
        (effects (font (size 1.27 1.27) (thickness 0.15)) (justify left bottom) hide)
      )
      (property "Footprint" "kria-k26-devboard-footprints:C_0402_1005Metric" (at 20.32 -12.7 0)
        (effects (font (size 1.27 1.27) (thickness 0.15)) (justify left bottom) hide)
      )
      (property "Datasheet" "https://search.murata.co.jp/Ceramy/image/img/A01X/G101/ENG/GRM155R61H104KE14-01.pdf" (at 20.32 -15.24 0)
        (effects (font (size 1.27 1.27) (thickness 0.15)) (justify left bottom) hide)
      )
      (property "MPN" "GRM155R61H104KE14D" (at 20.32 -17.78 0)
        (effects (font (size 1.27 1.27) (thickness 0.15)) (justify left bottom) hide)
      )
      (property "Manufacturer" "Murata" (at 20.32 -20.32 0)
        (effects (font (size 1.27 1.27) (thickness 0.15)) (justify left bottom) hide)
      )
      (property "License" "Apache-2.0" (at 20.32 -22.86 0)
        (effects (font (size 1.27 1.27) (thickness 0.15)) (justify left bottom) hide)
      )
      (property "Author" "Antmicro" (at 20.32 -25.4 0)
        (effects (font (size 1.27 1.27) (thickness 0.15)) (justify left bottom) hide)
      )
      (property "Val" "100n" (at 20.32 -7.62 0)
        (effects (font (size 1.27 1.27) (thickness 0.15)) (justify left bottom))
      )
      (property "Voltage" "50V" (at 20.32 -27.94 0)
        (effects (font (size 1.27 1.27)) (justify left bottom) hide)
      )
      (property "Dielectric" "X5R" (at 20.32 -30.48 0)
        (effects (font (size 1.27 1.27)) (justify left bottom) hide)
      )
      (property "ki_description" " " (at 0 0 0)
        (effects (font (size 1.27 1.27)) hide)
      )
      (symbol "C_100n_0402_31_0_1"
        (polyline
          (pts
            (xy 2.032 -1.524)
            (xy 2.032 1.524)
          )
          (stroke (width 0.3048) (type default))
          (fill (type none))
        )
        (polyline
          (pts
            (xy 3.048 -1.524)
            (xy 3.048 1.524)
          )
          (stroke (width 0.3302) (type default))
          (fill (type none))
        )
      )
      (symbol "C_100n_0402_31_1_1"
        (pin passive line (at 0 0 0) (length 2.032)
          (name "~" (effects (font (size 1.27 1.27))))
          (number "1" (effects (font (size 1.27 1.27))))
        )
        (pin passive line (at 5.08 0 180) (length 2.032)
          (name "~" (effects (font (size 1.27 1.27))))
          (number "2" (effects (font (size 1.27 1.27))))
        )
      )
    )
	(symbol "kria-k26-devboard:C_100n_0402_32" (pin_numbers hide) (pin_names hide) (in_bom yes) (on_board yes)
      (property "Reference" "C" (at 20.32 -5.08 0)
        (effects (font (size 1.27 1.27) (thickness 0.15)) (justify left bottom))
      )
      (property "Value" "C_100n_0402_32" (at 20.32 -10.16 0)
        (effects (font (size 1.27 1.27) (thickness 0.15)) (justify left bottom) hide)
      )
      (property "Footprint" "kria-k26-devboard-footprints:C_0402_1005Metric" (at 20.32 -12.7 0)
        (effects (font (size 1.27 1.27) (thickness 0.15)) (justify left bottom) hide)
      )
      (property "Datasheet" "https://search.murata.co.jp/Ceramy/image/img/A01X/G101/ENG/GRM155R61H104KE14-01.pdf" (at 20.32 -15.24 0)
        (effects (font (size 1.27 1.27) (thickness 0.15)) (justify left bottom) hide)
      )
      (property "MPN" "GRM155R61H104KE14D" (at 20.32 -17.78 0)
        (effects (font (size 1.27 1.27) (thickness 0.15)) (justify left bottom) hide)
      )
      (property "Manufacturer" "Murata" (at 20.32 -20.32 0)
        (effects (font (size 1.27 1.27) (thickness 0.15)) (justify left bottom) hide)
      )
      (property "License" "Apache-2.0" (at 20.32 -22.86 0)
        (effects (font (size 1.27 1.27) (thickness 0.15)) (justify left bottom) hide)
      )
      (property "Author" "Antmicro" (at 20.32 -25.4 0)
        (effects (font (size 1.27 1.27) (thickness 0.15)) (justify left bottom) hide)
      )
      (property "Val" "100n" (at 20.32 -7.62 0)
        (effects (font (size 1.27 1.27) (thickness 0.15)) (justify left bottom))
      )
      (property "Voltage" "50V" (at 20.32 -27.94 0)
        (effects (font (size 1.27 1.27)) (justify left bottom) hide)
      )
      (property "Dielectric" "X5R" (at 20.32 -30.48 0)
        (effects (font (size 1.27 1.27)) (justify left bottom) hide)
      )
      (property "ki_description" " " (at 0 0 0)
        (effects (font (size 1.27 1.27)) hide)
      )
      (symbol "C_100n_0402_32_0_1"
        (polyline
          (pts
            (xy 2.032 -1.524)
            (xy 2.032 1.524)
          )
          (stroke (width 0.3048) (type default))
          (fill (type none))
        )
        (polyline
          (pts
            (xy 3.048 -1.524)
            (xy 3.048 1.524)
          )
          (stroke (width 0.3302) (type default))
          (fill (type none))
        )
      )
      (symbol "C_100n_0402_32_1_1"
        (pin passive line (at 0 0 0) (length 2.032)
          (name "~" (effects (font (size 1.27 1.27))))
          (number "1" (effects (font (size 1.27 1.27))))
        )
        (pin passive line (at 5.08 0 180) (length 2.032)
          (name "~" (effects (font (size 1.27 1.27))))
          (number "2" (effects (font (size 1.27 1.27))))
        )
      )
    )
	(symbol "kria-k26-devboard:C_100n_0402_33" (pin_numbers hide) (pin_names hide) (in_bom yes) (on_board yes)
      (property "Reference" "C" (at 20.32 -5.08 0)
        (effects (font (size 1.27 1.27) (thickness 0.15)) (justify left bottom))
      )
      (property "Value" "C_100n_0402_33" (at 20.32 -10.16 0)
        (effects (font (size 1.27 1.27) (thickness 0.15)) (justify left bottom) hide)
      )
      (property "Footprint" "kria-k26-devboard-footprints:C_0402_1005Metric" (at 20.32 -12.7 0)
        (effects (font (size 1.27 1.27) (thickness 0.15)) (justify left bottom) hide)
      )
      (property "Datasheet" "https://search.murata.co.jp/Ceramy/image/img/A01X/G101/ENG/GRM155R61H104KE14-01.pdf" (at 20.32 -15.24 0)
        (effects (font (size 1.27 1.27) (thickness 0.15)) (justify left bottom) hide)
      )
      (property "MPN" "GRM155R61H104KE14D" (at 20.32 -17.78 0)
        (effects (font (size 1.27 1.27) (thickness 0.15)) (justify left bottom) hide)
      )
      (property "Manufacturer" "Murata" (at 20.32 -20.32 0)
        (effects (font (size 1.27 1.27) (thickness 0.15)) (justify left bottom) hide)
      )
      (property "License" "Apache-2.0" (at 20.32 -22.86 0)
        (effects (font (size 1.27 1.27) (thickness 0.15)) (justify left bottom) hide)
      )
      (property "Author" "Antmicro" (at 20.32 -25.4 0)
        (effects (font (size 1.27 1.27) (thickness 0.15)) (justify left bottom) hide)
      )
      (property "Val" "100n" (at 20.32 -7.62 0)
        (effects (font (size 1.27 1.27) (thickness 0.15)) (justify left bottom))
      )
      (property "Voltage" "50V" (at 20.32 -27.94 0)
        (effects (font (size 1.27 1.27)) (justify left bottom) hide)
      )
      (property "Dielectric" "X5R" (at 20.32 -30.48 0)
        (effects (font (size 1.27 1.27)) (justify left bottom) hide)
      )
      (property "ki_description" " " (at 0 0 0)
        (effects (font (size 1.27 1.27)) hide)
      )
      (symbol "C_100n_0402_33_0_1"
        (polyline
          (pts
            (xy 2.032 -1.524)
            (xy 2.032 1.524)
          )
          (stroke (width 0.3048) (type default))
          (fill (type none))
        )
        (polyline
          (pts
            (xy 3.048 -1.524)
            (xy 3.048 1.524)
          )
          (stroke (width 0.3302) (type default))
          (fill (type none))
        )
      )
      (symbol "C_100n_0402_33_1_1"
        (pin passive line (at 0 0 0) (length 2.032)
          (name "~" (effects (font (size 1.27 1.27))))
          (number "1" (effects (font (size 1.27 1.27))))
        )
        (pin passive line (at 5.08 0 180) (length 2.032)
          (name "~" (effects (font (size 1.27 1.27))))
          (number "2" (effects (font (size 1.27 1.27))))
        )
      )
    )
	(symbol "kria-k26-devboard:C_100n_0402_34" (pin_numbers hide) (pin_names hide) (in_bom yes) (on_board yes)
      (property "Reference" "C" (at 20.32 -5.08 0)
        (effects (font (size 1.27 1.27) (thickness 0.15)) (justify left bottom))
      )
      (property "Value" "C_100n_0402_34" (at 20.32 -10.16 0)
        (effects (font (size 1.27 1.27) (thickness 0.15)) (justify left bottom) hide)
      )
      (property "Footprint" "kria-k26-devboard-footprints:C_0402_1005Metric" (at 20.32 -12.7 0)
        (effects (font (size 1.27 1.27) (thickness 0.15)) (justify left bottom) hide)
      )
      (property "Datasheet" "https://search.murata.co.jp/Ceramy/image/img/A01X/G101/ENG/GRM155R61H104KE14-01.pdf" (at 20.32 -15.24 0)
        (effects (font (size 1.27 1.27) (thickness 0.15)) (justify left bottom) hide)
      )
      (property "MPN" "GRM155R61H104KE14D" (at 20.32 -17.78 0)
        (effects (font (size 1.27 1.27) (thickness 0.15)) (justify left bottom) hide)
      )
      (property "Manufacturer" "Murata" (at 20.32 -20.32 0)
        (effects (font (size 1.27 1.27) (thickness 0.15)) (justify left bottom) hide)
      )
      (property "License" "Apache-2.0" (at 20.32 -22.86 0)
        (effects (font (size 1.27 1.27) (thickness 0.15)) (justify left bottom) hide)
      )
      (property "Author" "Antmicro" (at 20.32 -25.4 0)
        (effects (font (size 1.27 1.27) (thickness 0.15)) (justify left bottom) hide)
      )
      (property "Val" "100n" (at 20.32 -7.62 0)
        (effects (font (size 1.27 1.27) (thickness 0.15)) (justify left bottom))
      )
      (property "Voltage" "50V" (at 20.32 -27.94 0)
        (effects (font (size 1.27 1.27)) (justify left bottom) hide)
      )
      (property "Dielectric" "X5R" (at 20.32 -30.48 0)
        (effects (font (size 1.27 1.27)) (justify left bottom) hide)
      )
      (property "ki_description" " " (at 0 0 0)
        (effects (font (size 1.27 1.27)) hide)
      )
      (symbol "C_100n_0402_34_0_1"
        (polyline
          (pts
            (xy 2.032 -1.524)
            (xy 2.032 1.524)
          )
          (stroke (width 0.3048) (type default))
          (fill (type none))
        )
        (polyline
          (pts
            (xy 3.048 -1.524)
            (xy 3.048 1.524)
          )
          (stroke (width 0.3302) (type default))
          (fill (type none))
        )
      )
      (symbol "C_100n_0402_34_1_1"
        (pin passive line (at 0 0 0) (length 2.032)
          (name "~" (effects (font (size 1.27 1.27))))
          (number "1" (effects (font (size 1.27 1.27))))
        )
        (pin passive line (at 5.08 0 180) (length 2.032)
          (name "~" (effects (font (size 1.27 1.27))))
          (number "2" (effects (font (size 1.27 1.27))))
        )
      )
    )
	(symbol "kria-k26-devboard:C_100n_0402_35" (pin_numbers hide) (pin_names hide) (in_bom yes) (on_board yes)
      (property "Reference" "C" (at 20.32 -5.08 0)
        (effects (font (size 1.27 1.27) (thickness 0.15)) (justify left bottom))
      )
      (property "Value" "C_100n_0402_35" (at 20.32 -10.16 0)
        (effects (font (size 1.27 1.27) (thickness 0.15)) (justify left bottom) hide)
      )
      (property "Footprint" "kria-k26-devboard-footprints:C_0402_1005Metric" (at 20.32 -12.7 0)
        (effects (font (size 1.27 1.27) (thickness 0.15)) (justify left bottom) hide)
      )
      (property "Datasheet" "https://search.murata.co.jp/Ceramy/image/img/A01X/G101/ENG/GRM155R61H104KE14-01.pdf" (at 20.32 -15.24 0)
        (effects (font (size 1.27 1.27) (thickness 0.15)) (justify left bottom) hide)
      )
      (property "MPN" "GRM155R61H104KE14D" (at 20.32 -17.78 0)
        (effects (font (size 1.27 1.27) (thickness 0.15)) (justify left bottom) hide)
      )
      (property "Manufacturer" "Murata" (at 20.32 -20.32 0)
        (effects (font (size 1.27 1.27) (thickness 0.15)) (justify left bottom) hide)
      )
      (property "License" "Apache-2.0" (at 20.32 -22.86 0)
        (effects (font (size 1.27 1.27) (thickness 0.15)) (justify left bottom) hide)
      )
      (property "Author" "Antmicro" (at 20.32 -25.4 0)
        (effects (font (size 1.27 1.27) (thickness 0.15)) (justify left bottom) hide)
      )
      (property "Val" "100n" (at 20.32 -7.62 0)
        (effects (font (size 1.27 1.27) (thickness 0.15)) (justify left bottom))
      )
      (property "Voltage" "50V" (at 20.32 -27.94 0)
        (effects (font (size 1.27 1.27)) (justify left bottom) hide)
      )
      (property "Dielectric" "X5R" (at 20.32 -30.48 0)
        (effects (font (size 1.27 1.27)) (justify left bottom) hide)
      )
      (property "ki_description" " " (at 0 0 0)
        (effects (font (size 1.27 1.27)) hide)
      )
      (symbol "C_100n_0402_35_0_1"
        (polyline
          (pts
            (xy 2.032 -1.524)
            (xy 2.032 1.524)
          )
          (stroke (width 0.3048) (type default))
          (fill (type none))
        )
        (polyline
          (pts
            (xy 3.048 -1.524)
            (xy 3.048 1.524)
          )
          (stroke (width 0.3302) (type default))
          (fill (type none))
        )
      )
      (symbol "C_100n_0402_35_1_1"
        (pin passive line (at 0 0 0) (length 2.032)
          (name "~" (effects (font (size 1.27 1.27))))
          (number "1" (effects (font (size 1.27 1.27))))
        )
        (pin passive line (at 5.08 0 180) (length 2.032)
          (name "~" (effects (font (size 1.27 1.27))))
          (number "2" (effects (font (size 1.27 1.27))))
        )
      )
    )
	(symbol "kria-k26-devboard:C_100n_0402_36" (pin_numbers hide) (pin_names hide) (in_bom yes) (on_board yes)
      (property "Reference" "C" (at 20.32 -5.08 0)
        (effects (font (size 1.27 1.27) (thickness 0.15)) (justify left bottom))
      )
      (property "Value" "C_100n_0402_36" (at 20.32 -10.16 0)
        (effects (font (size 1.27 1.27) (thickness 0.15)) (justify left bottom) hide)
      )
      (property "Footprint" "kria-k26-devboard-footprints:C_0402_1005Metric" (at 20.32 -12.7 0)
        (effects (font (size 1.27 1.27) (thickness 0.15)) (justify left bottom) hide)
      )
      (property "Datasheet" "https://search.murata.co.jp/Ceramy/image/img/A01X/G101/ENG/GRM155R61H104KE14-01.pdf" (at 20.32 -15.24 0)
        (effects (font (size 1.27 1.27) (thickness 0.15)) (justify left bottom) hide)
      )
      (property "MPN" "GRM155R61H104KE14D" (at 20.32 -17.78 0)
        (effects (font (size 1.27 1.27) (thickness 0.15)) (justify left bottom) hide)
      )
      (property "Manufacturer" "Murata" (at 20.32 -20.32 0)
        (effects (font (size 1.27 1.27) (thickness 0.15)) (justify left bottom) hide)
      )
      (property "License" "Apache-2.0" (at 20.32 -22.86 0)
        (effects (font (size 1.27 1.27) (thickness 0.15)) (justify left bottom) hide)
      )
      (property "Author" "Antmicro" (at 20.32 -25.4 0)
        (effects (font (size 1.27 1.27) (thickness 0.15)) (justify left bottom) hide)
      )
      (property "Val" "100n" (at 20.32 -7.62 0)
        (effects (font (size 1.27 1.27) (thickness 0.15)) (justify left bottom))
      )
      (property "Voltage" "50V" (at 20.32 -27.94 0)
        (effects (font (size 1.27 1.27)) (justify left bottom) hide)
      )
      (property "Dielectric" "X5R" (at 20.32 -30.48 0)
        (effects (font (size 1.27 1.27)) (justify left bottom) hide)
      )
      (property "ki_description" " " (at 0 0 0)
        (effects (font (size 1.27 1.27)) hide)
      )
      (symbol "C_100n_0402_36_0_1"
        (polyline
          (pts
            (xy 2.032 -1.524)
            (xy 2.032 1.524)
          )
          (stroke (width 0.3048) (type default))
          (fill (type none))
        )
        (polyline
          (pts
            (xy 3.048 -1.524)
            (xy 3.048 1.524)
          )
          (stroke (width 0.3302) (type default))
          (fill (type none))
        )
      )
      (symbol "C_100n_0402_36_1_1"
        (pin passive line (at 0 0 0) (length 2.032)
          (name "~" (effects (font (size 1.27 1.27))))
          (number "1" (effects (font (size 1.27 1.27))))
        )
        (pin passive line (at 5.08 0 180) (length 2.032)
          (name "~" (effects (font (size 1.27 1.27))))
          (number "2" (effects (font (size 1.27 1.27))))
        )
      )
    )
	(symbol "kria-k26-devboard:C_100n_0402_37" (pin_numbers hide) (pin_names hide) (in_bom yes) (on_board yes)
      (property "Reference" "C" (at 20.32 -5.08 0)
        (effects (font (size 1.27 1.27) (thickness 0.15)) (justify left bottom))
      )
      (property "Value" "C_100n_0402_37" (at 20.32 -10.16 0)
        (effects (font (size 1.27 1.27) (thickness 0.15)) (justify left bottom) hide)
      )
      (property "Footprint" "kria-k26-devboard-footprints:C_0402_1005Metric" (at 20.32 -12.7 0)
        (effects (font (size 1.27 1.27) (thickness 0.15)) (justify left bottom) hide)
      )
      (property "Datasheet" "https://search.murata.co.jp/Ceramy/image/img/A01X/G101/ENG/GRM155R61H104KE14-01.pdf" (at 20.32 -15.24 0)
        (effects (font (size 1.27 1.27) (thickness 0.15)) (justify left bottom) hide)
      )
      (property "MPN" "GRM155R61H104KE14D" (at 20.32 -17.78 0)
        (effects (font (size 1.27 1.27) (thickness 0.15)) (justify left bottom) hide)
      )
      (property "Manufacturer" "Murata" (at 20.32 -20.32 0)
        (effects (font (size 1.27 1.27) (thickness 0.15)) (justify left bottom) hide)
      )
      (property "License" "Apache-2.0" (at 20.32 -22.86 0)
        (effects (font (size 1.27 1.27) (thickness 0.15)) (justify left bottom) hide)
      )
      (property "Author" "Antmicro" (at 20.32 -25.4 0)
        (effects (font (size 1.27 1.27) (thickness 0.15)) (justify left bottom) hide)
      )
      (property "Val" "100n" (at 20.32 -7.62 0)
        (effects (font (size 1.27 1.27) (thickness 0.15)) (justify left bottom))
      )
      (property "Voltage" "50V" (at 20.32 -27.94 0)
        (effects (font (size 1.27 1.27)) (justify left bottom) hide)
      )
      (property "Dielectric" "X5R" (at 20.32 -30.48 0)
        (effects (font (size 1.27 1.27)) (justify left bottom) hide)
      )
      (property "ki_description" " " (at 0 0 0)
        (effects (font (size 1.27 1.27)) hide)
      )
      (symbol "C_100n_0402_37_0_1"
        (polyline
          (pts
            (xy 2.032 -1.524)
            (xy 2.032 1.524)
          )
          (stroke (width 0.3048) (type default))
          (fill (type none))
        )
        (polyline
          (pts
            (xy 3.048 -1.524)
            (xy 3.048 1.524)
          )
          (stroke (width 0.3302) (type default))
          (fill (type none))
        )
      )
      (symbol "C_100n_0402_37_1_1"
        (pin passive line (at 0 0 0) (length 2.032)
          (name "~" (effects (font (size 1.27 1.27))))
          (number "1" (effects (font (size 1.27 1.27))))
        )
        (pin passive line (at 5.08 0 180) (length 2.032)
          (name "~" (effects (font (size 1.27 1.27))))
          (number "2" (effects (font (size 1.27 1.27))))
        )
      )
    )
	(symbol "kria-k26-devboard:C_100n_0402_38" (pin_numbers hide) (pin_names hide) (in_bom yes) (on_board yes)
      (property "Reference" "C" (at 20.32 -5.08 0)
        (effects (font (size 1.27 1.27) (thickness 0.15)) (justify left bottom))
      )
      (property "Value" "C_100n_0402_38" (at 20.32 -10.16 0)
        (effects (font (size 1.27 1.27) (thickness 0.15)) (justify left bottom) hide)
      )
      (property "Footprint" "kria-k26-devboard-footprints:C_0402_1005Metric" (at 20.32 -12.7 0)
        (effects (font (size 1.27 1.27) (thickness 0.15)) (justify left bottom) hide)
      )
      (property "Datasheet" "https://search.murata.co.jp/Ceramy/image/img/A01X/G101/ENG/GRM155R61H104KE14-01.pdf" (at 20.32 -15.24 0)
        (effects (font (size 1.27 1.27) (thickness 0.15)) (justify left bottom) hide)
      )
      (property "MPN" "GRM155R61H104KE14D" (at 20.32 -17.78 0)
        (effects (font (size 1.27 1.27) (thickness 0.15)) (justify left bottom) hide)
      )
      (property "Manufacturer" "Murata" (at 20.32 -20.32 0)
        (effects (font (size 1.27 1.27) (thickness 0.15)) (justify left bottom) hide)
      )
      (property "License" "Apache-2.0" (at 20.32 -22.86 0)
        (effects (font (size 1.27 1.27) (thickness 0.15)) (justify left bottom) hide)
      )
      (property "Author" "Antmicro" (at 20.32 -25.4 0)
        (effects (font (size 1.27 1.27) (thickness 0.15)) (justify left bottom) hide)
      )
      (property "Val" "100n" (at 20.32 -7.62 0)
        (effects (font (size 1.27 1.27) (thickness 0.15)) (justify left bottom))
      )
      (property "Voltage" "50V" (at 20.32 -27.94 0)
        (effects (font (size 1.27 1.27)) (justify left bottom) hide)
      )
      (property "Dielectric" "X5R" (at 20.32 -30.48 0)
        (effects (font (size 1.27 1.27)) (justify left bottom) hide)
      )
      (property "ki_description" " " (at 0 0 0)
        (effects (font (size 1.27 1.27)) hide)
      )
      (symbol "C_100n_0402_38_0_1"
        (polyline
          (pts
            (xy 2.032 -1.524)
            (xy 2.032 1.524)
          )
          (stroke (width 0.3048) (type default))
          (fill (type none))
        )
        (polyline
          (pts
            (xy 3.048 -1.524)
            (xy 3.048 1.524)
          )
          (stroke (width 0.3302) (type default))
          (fill (type none))
        )
      )
      (symbol "C_100n_0402_38_1_1"
        (pin passive line (at 0 0 0) (length 2.032)
          (name "~" (effects (font (size 1.27 1.27))))
          (number "1" (effects (font (size 1.27 1.27))))
        )
        (pin passive line (at 5.08 0 180) (length 2.032)
          (name "~" (effects (font (size 1.27 1.27))))
          (number "2" (effects (font (size 1.27 1.27))))
        )
      )
    )
	(symbol "kria-k26-devboard:C_100n_0402_39" (pin_numbers hide) (pin_names hide) (in_bom yes) (on_board yes)
      (property "Reference" "C" (at 20.32 -5.08 0)
        (effects (font (size 1.27 1.27) (thickness 0.15)) (justify left bottom))
      )
      (property "Value" "C_100n_0402_39" (at 20.32 -10.16 0)
        (effects (font (size 1.27 1.27) (thickness 0.15)) (justify left bottom) hide)
      )
      (property "Footprint" "kria-k26-devboard-footprints:C_0402_1005Metric" (at 20.32 -12.7 0)
        (effects (font (size 1.27 1.27) (thickness 0.15)) (justify left bottom) hide)
      )
      (property "Datasheet" "https://search.murata.co.jp/Ceramy/image/img/A01X/G101/ENG/GRM155R61H104KE14-01.pdf" (at 20.32 -15.24 0)
        (effects (font (size 1.27 1.27) (thickness 0.15)) (justify left bottom) hide)
      )
      (property "MPN" "GRM155R61H104KE14D" (at 20.32 -17.78 0)
        (effects (font (size 1.27 1.27) (thickness 0.15)) (justify left bottom) hide)
      )
      (property "Manufacturer" "Murata" (at 20.32 -20.32 0)
        (effects (font (size 1.27 1.27) (thickness 0.15)) (justify left bottom) hide)
      )
      (property "License" "Apache-2.0" (at 20.32 -22.86 0)
        (effects (font (size 1.27 1.27) (thickness 0.15)) (justify left bottom) hide)
      )
      (property "Author" "Antmicro" (at 20.32 -25.4 0)
        (effects (font (size 1.27 1.27) (thickness 0.15)) (justify left bottom) hide)
      )
      (property "Val" "100n" (at 20.32 -7.62 0)
        (effects (font (size 1.27 1.27) (thickness 0.15)) (justify left bottom))
      )
      (property "Voltage" "50V" (at 20.32 -27.94 0)
        (effects (font (size 1.27 1.27)) (justify left bottom) hide)
      )
      (property "Dielectric" "X5R" (at 20.32 -30.48 0)
        (effects (font (size 1.27 1.27)) (justify left bottom) hide)
      )
      (property "ki_description" " " (at 0 0 0)
        (effects (font (size 1.27 1.27)) hide)
      )
      (symbol "C_100n_0402_39_0_1"
        (polyline
          (pts
            (xy 2.032 -1.524)
            (xy 2.032 1.524)
          )
          (stroke (width 0.3048) (type default))
          (fill (type none))
        )
        (polyline
          (pts
            (xy 3.048 -1.524)
            (xy 3.048 1.524)
          )
          (stroke (width 0.3302) (type default))
          (fill (type none))
        )
      )
      (symbol "C_100n_0402_39_1_1"
        (pin passive line (at 0 0 0) (length 2.032)
          (name "~" (effects (font (size 1.27 1.27))))
          (number "1" (effects (font (size 1.27 1.27))))
        )
        (pin passive line (at 5.08 0 180) (length 2.032)
          (name "~" (effects (font (size 1.27 1.27))))
          (number "2" (effects (font (size 1.27 1.27))))
        )
      )
    )
	(symbol "kria-k26-devboard:C_100n_100V_0805" (pin_numbers hide) (pin_names hide) (in_bom yes) (on_board yes)
      (property "Reference" "C" (at 20.32 -5.08 0)
        (effects (font (size 1.27 1.27) (thickness 0.15)) (justify left bottom))
      )
      (property "Value" "C_100n_0805_100V" (at 20.32 -10.16 0)
        (effects (font (size 1.27 1.27) (thickness 0.15)) (justify left bottom) hide)
      )
      (property "Footprint" "kria-k26-devboard-footprints:C_0805_2012Metric" (at 20.32 -12.7 0)
        (effects (font (size 1.27 1.27) (thickness 0.15)) (justify left bottom) hide)
      )
      (property "Datasheet" "https://www.mouser.pl/datasheet/2/585/MLCC-1837944.pdf" (at 20.32 -15.24 0)
        (effects (font (size 1.27 1.27) (thickness 0.15)) (justify left bottom) hide)
      )
      (property "MPN" "CL21B104KCFNNNE" (at 20.32 -17.78 0)
        (effects (font (size 1.27 1.27) (thickness 0.15)) (justify left bottom) hide)
      )
      (property "Manufacturer" "SAMSUNG" (at 20.32 -20.32 0)
        (effects (font (size 1.27 1.27) (thickness 0.15)) (justify left bottom) hide)
      )
      (property "License" "Apache-2.0" (at 20.32 -22.86 0)
        (effects (font (size 1.27 1.27) (thickness 0.15)) (justify left bottom) hide)
      )
      (property "Author" "Antmicro" (at 20.32 -25.4 0)
        (effects (font (size 1.27 1.27) (thickness 0.15)) (justify left bottom) hide)
      )
      (property "Val" "100n/100V" (at 20.32 -7.62 0)
        (effects (font (size 1.27 1.27) (thickness 0.15)) (justify left bottom))
      )
      (property "Voltage" "100V" (at 20.32 -27.94 0)
        (effects (font (size 1.27 1.27)) (justify left bottom) hide)
      )
      (property "Dielectric" "X7R" (at 20.32 -30.48 0)
        (effects (font (size 1.27 1.27)) (justify left bottom) hide)
      )
      (property "ki_description" " " (at 0 0 0)
        (effects (font (size 1.27 1.27)) hide)
      )
      (symbol "C_100n_100V_0805_0_1"
        (polyline
          (pts
            (xy 2.032 -1.524)
            (xy 2.032 1.524)
          )
          (stroke (width 0.3048) (type default))
          (fill (type none))
        )
        (polyline
          (pts
            (xy 3.048 -1.524)
            (xy 3.048 1.524)
          )
          (stroke (width 0.3302) (type default))
          (fill (type none))
        )
      )
      (symbol "C_100n_100V_0805_1_1"
        (pin passive line (at 0 0 0) (length 2.032)
          (name "~" (effects (font (size 1.27 1.27))))
          (number "1" (effects (font (size 1.27 1.27))))
        )
        (pin passive line (at 5.08 0 180) (length 2.032)
          (name "~" (effects (font (size 1.27 1.27))))
          (number "2" (effects (font (size 1.27 1.27))))
        )
      )
    )
	(symbol "kria-k26-devboard:C_100n_50V_0402" (pin_numbers hide) (pin_names hide) (in_bom yes) (on_board yes)
      (property "Reference" "C" (at 20.32 -5.08 0)
        (effects (font (size 1.27 1.27) (thickness 0.15)) (justify left bottom))
      )
      (property "Value" "C_100n_50V_0402" (at 20.32 -10.16 0)
        (effects (font (size 1.27 1.27) (thickness 0.15)) (justify left bottom) hide)
      )
      (property "Footprint" "kria-k26-devboard-footprints:C_0402_1005Metric" (at 20.32 -12.7 0)
        (effects (font (size 1.27 1.27) (thickness 0.15)) (justify left bottom) hide)
      )
      (property "Datasheet" " " (at 20.32 -15.24 0)
        (effects (font (size 1.27 1.27) (thickness 0.15)) (justify left bottom) hide)
      )
      (property "MPN" "GRM155R71H104KE14D" (at 20.32 -17.78 0)
        (effects (font (size 1.27 1.27) (thickness 0.15)) (justify left bottom) hide)
      )
      (property "Manufacturer" "Murata" (at 20.32 -20.32 0)
        (effects (font (size 1.27 1.27) (thickness 0.15)) (justify left bottom) hide)
      )
      (property "License" "Apache-2.0" (at 20.32 -22.86 0)
        (effects (font (size 1.27 1.27) (thickness 0.15)) (justify left bottom) hide)
      )
      (property "Author" "Antmicro" (at 20.32 -25.4 0)
        (effects (font (size 1.27 1.27) (thickness 0.15)) (justify left bottom) hide)
      )
      (property "Val" "100n/50V" (at 20.32 -7.62 0)
        (effects (font (size 1.27 1.27) (thickness 0.15)) (justify left bottom))
      )
      (property "Voltage" "" (at 20.32 -27.94 0)
        (effects (font (size 1.27 1.27)) (justify left bottom) hide)
      )
      (property "Dielectric" "" (at 20.32 -30.48 0)
        (effects (font (size 1.27 1.27)) (justify left bottom) hide)
      )
      (property "ki_description" " " (at 0 0 0)
        (effects (font (size 1.27 1.27)) hide)
      )
      (symbol "C_100n_50V_0402_0_1"
        (polyline
          (pts
            (xy 2.032 -1.524)
            (xy 2.032 1.524)
          )
          (stroke (width 0.3048) (type default))
          (fill (type none))
        )
        (polyline
          (pts
            (xy 3.048 -1.524)
            (xy 3.048 1.524)
          )
          (stroke (width 0.3302) (type default))
          (fill (type none))
        )
      )
      (symbol "C_100n_50V_0402_1_1"
        (pin passive line (at 0 0 0) (length 2.032)
          (name "~" (effects (font (size 1.27 1.27))))
          (number "1" (effects (font (size 1.27 1.27))))
        )
        (pin passive line (at 5.08 0 180) (length 2.032)
          (name "~" (effects (font (size 1.27 1.27))))
          (number "2" (effects (font (size 1.27 1.27))))
        )
      )
    )
	(symbol "kria-k26-devboard:C_100p_0402" (pin_numbers hide) (pin_names hide) (in_bom yes) (on_board yes)
      (property "Reference" "C" (at 20.32 -5.08 0)
        (effects (font (size 1.27 1.27) (thickness 0.15)) (justify left bottom))
      )
      (property "Value" "C_100p_0402" (at 20.32 -10.16 0)
        (effects (font (size 1.27 1.27) (thickness 0.15)) (justify left bottom) hide)
      )
      (property "Footprint" "kria-k26-devboard-footprints:C_0402_1005Metric" (at 20.32 -12.7 0)
        (effects (font (size 1.27 1.27) (thickness 0.15)) (justify left bottom) hide)
      )
      (property "Datasheet" "https://www.murata.com/-/media/webrenewal/support/library/catalog/products/k35e.ashx?la=en-us&cvid=20200508021757000000" (at 20.32 -15.24 0)
        (effects (font (size 1.27 1.27) (thickness 0.15)) (justify left bottom) hide)
      )
      (property "MPN" "GCM1555C1H101JA16D" (at 20.32 -17.78 0)
        (effects (font (size 1.27 1.27) (thickness 0.15)) (justify left bottom) hide)
      )
      (property "Manufacturer" "Murata" (at 20.32 -20.32 0)
        (effects (font (size 1.27 1.27) (thickness 0.15)) (justify left bottom) hide)
      )
      (property "License" "Apache-2.0" (at 20.32 -22.86 0)
        (effects (font (size 1.27 1.27) (thickness 0.15)) (justify left bottom) hide)
      )
      (property "Author" "Antmicro" (at 20.32 -25.4 0)
        (effects (font (size 1.27 1.27) (thickness 0.15)) (justify left bottom) hide)
      )
      (property "Val" "100p" (at 20.32 -7.62 0)
        (effects (font (size 1.27 1.27) (thickness 0.15)) (justify left bottom))
      )
      (property "Voltage" "50V" (at 20.32 -27.94 0)
        (effects (font (size 1.27 1.27)) (justify left bottom) hide)
      )
      (property "Dielectric" "C0G" (at 20.32 -30.48 0)
        (effects (font (size 1.27 1.27)) (justify left bottom) hide)
      )
      (property "ki_description" " " (at 0 0 0)
        (effects (font (size 1.27 1.27)) hide)
      )
      (symbol "C_100p_0402_0_1"
        (polyline
          (pts
            (xy 2.032 -1.524)
            (xy 2.032 1.524)
          )
          (stroke (width 0.3048) (type default))
          (fill (type none))
        )
        (polyline
          (pts
            (xy 3.048 -1.524)
            (xy 3.048 1.524)
          )
          (stroke (width 0.3302) (type default))
          (fill (type none))
        )
      )
      (symbol "C_100p_0402_1_1"
        (pin passive line (at 0 0 0) (length 2.032)
          (name "~" (effects (font (size 1.27 1.27))))
          (number "1" (effects (font (size 1.27 1.27))))
        )
        (pin passive line (at 5.08 0 180) (length 2.032)
          (name "~" (effects (font (size 1.27 1.27))))
          (number "2" (effects (font (size 1.27 1.27))))
        )
      )
    )
	(symbol "kria-k26-devboard:C_10n_0402" (pin_numbers hide) (pin_names hide) (in_bom yes) (on_board yes)
      (property "Reference" "C" (at 20.32 -5.08 0)
        (effects (font (size 1.27 1.27) (thickness 0.15)) (justify left bottom))
      )
      (property "Value" "C_10n_0402" (at 20.32 -10.16 0)
        (effects (font (size 1.27 1.27) (thickness 0.15)) (justify left bottom) hide)
      )
      (property "Footprint" "kria-k26-devboard-footprints:C_0402_1005Metric" (at 20.32 -12.7 0)
        (effects (font (size 1.27 1.27) (thickness 0.15)) (justify left bottom) hide)
      )
      (property "Datasheet" "https://search.murata.co.jp/Ceramy/image/img/A01X/G101/ENG/GRM155R71H103KA88-01.pdf" (at 20.32 -15.24 0)
        (effects (font (size 1.27 1.27) (thickness 0.15)) (justify left bottom) hide)
      )
      (property "MPN" "GRM155R71H103KA88D" (at 20.32 -17.78 0)
        (effects (font (size 1.27 1.27) (thickness 0.15)) (justify left bottom) hide)
      )
      (property "Manufacturer" "Murata" (at 20.32 -20.32 0)
        (effects (font (size 1.27 1.27) (thickness 0.15)) (justify left bottom) hide)
      )
      (property "License" "Apache-2.0" (at 20.32 -22.86 0)
        (effects (font (size 1.27 1.27) (thickness 0.15)) (justify left bottom) hide)
      )
      (property "Author" "Antmicro" (at 20.32 -25.4 0)
        (effects (font (size 1.27 1.27) (thickness 0.15)) (justify left bottom) hide)
      )
      (property "Val" "10n" (at 20.32 -7.62 0)
        (effects (font (size 1.27 1.27) (thickness 0.15)) (justify left bottom))
      )
      (property "Voltage" "50V" (at 20.32 -27.94 0)
        (effects (font (size 1.27 1.27)) (justify left bottom) hide)
      )
      (property "Dielectric" "X7R" (at 20.32 -30.48 0)
        (effects (font (size 1.27 1.27)) (justify left bottom) hide)
      )
      (property "ki_description" " " (at 0 0 0)
        (effects (font (size 1.27 1.27)) hide)
      )
      (symbol "C_10n_0402_0_1"
        (polyline
          (pts
            (xy 2.032 -1.524)
            (xy 2.032 1.524)
          )
          (stroke (width 0.3048) (type default))
          (fill (type none))
        )
        (polyline
          (pts
            (xy 3.048 -1.524)
            (xy 3.048 1.524)
          )
          (stroke (width 0.3302) (type default))
          (fill (type none))
        )
      )
      (symbol "C_10n_0402_1_1"
        (pin passive line (at 0 0 0) (length 2.032)
          (name "~" (effects (font (size 1.27 1.27))))
          (number "1" (effects (font (size 1.27 1.27))))
        )
        (pin passive line (at 5.08 0 180) (length 2.032)
          (name "~" (effects (font (size 1.27 1.27))))
          (number "2" (effects (font (size 1.27 1.27))))
        )
      )
    )
	(symbol "kria-k26-devboard:C_10u_0402" (pin_numbers hide) (pin_names hide) (in_bom yes) (on_board yes)
      (property "Reference" "C" (at 20.32 -5.08 0)
        (effects (font (size 1.27 1.27) (thickness 0.15)) (justify left bottom))
      )
      (property "Value" "C_10u_0402" (at 20.32 -10.16 0)
        (effects (font (size 1.27 1.27) (thickness 0.15)) (justify left bottom) hide)
      )
      (property "Footprint" "kria-k26-devboard-footprints:C_0402_1005Metric" (at 20.32 -12.7 0)
        (effects (font (size 1.27 1.27) (thickness 0.15)) (justify left bottom) hide)
      )
      (property "Datasheet" " " (at 20.32 -15.24 0)
        (effects (font (size 1.27 1.27) (thickness 0.15)) (justify left bottom) hide)
      )
      (property "MPN" "CC0402MRX5R5BB106" (at 20.32 -17.78 0)
        (effects (font (size 1.27 1.27) (thickness 0.15)) (justify left bottom) hide)
      )
      (property "Manufacturer" "Yaego" (at 20.32 -20.32 0)
        (effects (font (size 1.27 1.27) (thickness 0.15)) (justify left bottom) hide)
      )
      (property "License" "Apache-2.0" (at 20.32 -22.86 0)
        (effects (font (size 1.27 1.27) (thickness 0.15)) (justify left bottom) hide)
      )
      (property "Author" "Antmicro" (at 20.32 -25.4 0)
        (effects (font (size 1.27 1.27) (thickness 0.15)) (justify left bottom) hide)
      )
      (property "Val" "10u" (at 20.32 -7.62 0)
        (effects (font (size 1.27 1.27) (thickness 0.15)) (justify left bottom))
      )
      (property "Voltage" "" (at 20.32 -27.94 0)
        (effects (font (size 1.27 1.27)) (justify left bottom) hide)
      )
      (property "Dielectric" "" (at 20.32 -30.48 0)
        (effects (font (size 1.27 1.27)) (justify left bottom) hide)
      )
      (property "ki_description" " " (at 0 0 0)
        (effects (font (size 1.27 1.27)) hide)
      )
      (symbol "C_10u_0402_0_1"
        (polyline
          (pts
            (xy 2.032 -1.524)
            (xy 2.032 1.524)
          )
          (stroke (width 0.3048) (type default))
          (fill (type none))
        )
        (polyline
          (pts
            (xy 3.048 -1.524)
            (xy 3.048 1.524)
          )
          (stroke (width 0.3302) (type default))
          (fill (type none))
        )
      )
      (symbol "C_10u_0402_1_1"
        (pin passive line (at 0 0 0) (length 2.032)
          (name "~" (effects (font (size 1.27 1.27))))
          (number "1" (effects (font (size 1.27 1.27))))
        )
        (pin passive line (at 5.08 0 180) (length 2.032)
          (name "~" (effects (font (size 1.27 1.27))))
          (number "2" (effects (font (size 1.27 1.27))))
        )
      )
    )
	(symbol "kria-k26-devboard:C_10u_0603" (pin_numbers hide) (pin_names hide) (in_bom yes) (on_board yes)
      (property "Reference" "C" (at 20.32 -5.08 0)
        (effects (font (size 1.27 1.27) (thickness 0.15)) (justify left bottom))
      )
      (property "Value" "C_10u_0603" (at 20.32 -10.16 0)
        (effects (font (size 1.27 1.27) (thickness 0.15)) (justify left bottom) hide)
      )
      (property "Footprint" "kria-k26-devboard-footprints:C_0603_1608Metric" (at 20.32 -12.7 0)
        (effects (font (size 1.27 1.27) (thickness 0.15)) (justify left bottom) hide)
      )
      (property "Datasheet" " " (at 20.32 -15.24 0)
        (effects (font (size 1.27 1.27) (thickness 0.15)) (justify left bottom) hide)
      )
      (property "MPN" "GRM188R61A106KE69D" (at 20.32 -17.78 0)
        (effects (font (size 1.27 1.27) (thickness 0.15)) (justify left bottom) hide)
      )
      (property "Manufacturer" "Murata" (at 20.32 -20.32 0)
        (effects (font (size 1.27 1.27) (thickness 0.15)) (justify left bottom) hide)
      )
      (property "License" "Apache-2.0" (at 20.32 -22.86 0)
        (effects (font (size 1.27 1.27) (thickness 0.15)) (justify left bottom) hide)
      )
      (property "Author" "Antmicro" (at 20.32 -25.4 0)
        (effects (font (size 1.27 1.27) (thickness 0.15)) (justify left bottom) hide)
      )
      (property "Val" "10u" (at 20.32 -7.62 0)
        (effects (font (size 1.27 1.27) (thickness 0.15)) (justify left bottom))
      )
      (property "Voltage" "" (at 20.32 -27.94 0)
        (effects (font (size 1.27 1.27)) (justify left bottom) hide)
      )
      (property "Dielectric" "template_dielectric" (at 20.32 -30.48 0)
        (effects (font (size 1.27 1.27)) (justify left bottom) hide)
      )
      (property "ki_description" " " (at 0 0 0)
        (effects (font (size 1.27 1.27)) hide)
      )
      (symbol "C_10u_0603_0_1"
        (polyline
          (pts
            (xy 2.032 -1.524)
            (xy 2.032 1.524)
          )
          (stroke (width 0.3048) (type default))
          (fill (type none))
        )
        (polyline
          (pts
            (xy 3.048 -1.524)
            (xy 3.048 1.524)
          )
          (stroke (width 0.3302) (type default))
          (fill (type none))
        )
      )
      (symbol "C_10u_0603_1_1"
        (pin passive line (at 0 0 0) (length 2.032)
          (name "~" (effects (font (size 1.27 1.27))))
          (number "1" (effects (font (size 1.27 1.27))))
        )
        (pin passive line (at 5.08 0 180) (length 2.032)
          (name "~" (effects (font (size 1.27 1.27))))
          (number "2" (effects (font (size 1.27 1.27))))
        )
      )
    )
	(symbol "kria-k26-devboard:C_10u_25V_0603" (pin_numbers hide) (pin_names hide) (in_bom yes) (on_board yes)
      (property "Reference" "C" (at 20.32 -5.08 0)
        (effects (font (size 1.27 1.27) (thickness 0.15)) (justify left bottom))
      )
      (property "Value" "C_10u_25V_0603" (at 20.32 -10.16 0)
        (effects (font (size 1.27 1.27) (thickness 0.15)) (justify left bottom) hide)
      )
      (property "Footprint" "kria-k26-devboard-footprints:C_0603_1608Metric" (at 20.32 -12.7 0)
        (effects (font (size 1.27 1.27) (thickness 0.15)) (justify left bottom) hide)
      )
      (property "Datasheet" " " (at 20.32 -15.24 0)
        (effects (font (size 1.27 1.27) (thickness 0.15)) (justify left bottom) hide)
      )
      (property "MPN" "C1608X5R1E106M080AC" (at 20.32 -17.78 0)
        (effects (font (size 1.27 1.27) (thickness 0.15)) (justify left bottom) hide)
      )
      (property "Manufacturer" "TDK" (at 20.32 -20.32 0)
        (effects (font (size 1.27 1.27) (thickness 0.15)) (justify left bottom) hide)
      )
      (property "License" "Apache-2.0" (at 20.32 -22.86 0)
        (effects (font (size 1.27 1.27) (thickness 0.15)) (justify left bottom) hide)
      )
      (property "Author" "Antmicro" (at 20.32 -25.4 0)
        (effects (font (size 1.27 1.27) (thickness 0.15)) (justify left bottom) hide)
      )
      (property "Val" "10u/25V" (at 20.32 -7.62 0)
        (effects (font (size 1.27 1.27) (thickness 0.15)) (justify left bottom))
      )
      (property "Voltage" "" (at 20.32 -27.94 0)
        (effects (font (size 1.27 1.27)) (justify left bottom) hide)
      )
      (property "Dielectric" "" (at 20.32 -30.48 0)
        (effects (font (size 1.27 1.27)) (justify left bottom) hide)
      )
      (property "ki_description" " " (at 0 0 0)
        (effects (font (size 1.27 1.27)) hide)
      )
      (symbol "C_10u_25V_0603_0_1"
        (polyline
          (pts
            (xy 2.032 -1.524)
            (xy 2.032 1.524)
          )
          (stroke (width 0.3048) (type default))
          (fill (type none))
        )
        (polyline
          (pts
            (xy 3.048 -1.524)
            (xy 3.048 1.524)
          )
          (stroke (width 0.3302) (type default))
          (fill (type none))
        )
      )
      (symbol "C_10u_25V_0603_1_1"
        (pin passive line (at 0 0 0) (length 2.032)
          (name "~" (effects (font (size 1.27 1.27))))
          (number "1" (effects (font (size 1.27 1.27))))
        )
        (pin passive line (at 5.08 0 180) (length 2.032)
          (name "~" (effects (font (size 1.27 1.27))))
          (number "2" (effects (font (size 1.27 1.27))))
        )
      )
    )
	(symbol "kria-k26-devboard:C_10u_25V_0603_10" (pin_numbers hide) (pin_names hide) (in_bom yes) (on_board yes)
      (property "Reference" "C" (at 20.32 -5.08 0)
        (effects (font (size 1.27 1.27) (thickness 0.15)) (justify left bottom))
      )
      (property "Value" "C_10u_25V_0603_10" (at 20.32 -10.16 0)
        (effects (font (size 1.27 1.27) (thickness 0.15)) (justify left bottom) hide)
      )
      (property "Footprint" "kria-k26-devboard-footprints:C_0603_1608Metric" (at 20.32 -12.7 0)
        (effects (font (size 1.27 1.27) (thickness 0.15)) (justify left bottom) hide)
      )
      (property "Datasheet" " " (at 20.32 -15.24 0)
        (effects (font (size 1.27 1.27) (thickness 0.15)) (justify left bottom) hide)
      )
      (property "MPN" "C1608X5R1E106M080AC" (at 20.32 -17.78 0)
        (effects (font (size 1.27 1.27) (thickness 0.15)) (justify left bottom) hide)
      )
      (property "Manufacturer" "TDK" (at 20.32 -20.32 0)
        (effects (font (size 1.27 1.27) (thickness 0.15)) (justify left bottom) hide)
      )
      (property "License" "Apache-2.0" (at 20.32 -22.86 0)
        (effects (font (size 1.27 1.27) (thickness 0.15)) (justify left bottom) hide)
      )
      (property "Author" "Antmicro" (at 20.32 -25.4 0)
        (effects (font (size 1.27 1.27) (thickness 0.15)) (justify left bottom) hide)
      )
      (property "Val" "10u/25V" (at 20.32 -7.62 0)
        (effects (font (size 1.27 1.27) (thickness 0.15)) (justify left bottom))
      )
      (property "Voltage" "" (at 20.32 -27.94 0)
        (effects (font (size 1.27 1.27)) (justify left bottom) hide)
      )
      (property "Dielectric" "" (at 20.32 -30.48 0)
        (effects (font (size 1.27 1.27)) (justify left bottom) hide)
      )
      (property "ki_description" " " (at 0 0 0)
        (effects (font (size 1.27 1.27)) hide)
      )
      (symbol "C_10u_25V_0603_10_0_1"
        (polyline
          (pts
            (xy 2.032 -1.524)
            (xy 2.032 1.524)
          )
          (stroke (width 0.3048) (type default))
          (fill (type none))
        )
        (polyline
          (pts
            (xy 3.048 -1.524)
            (xy 3.048 1.524)
          )
          (stroke (width 0.3302) (type default))
          (fill (type none))
        )
      )
      (symbol "C_10u_25V_0603_10_1_1"
        (pin passive line (at 0 0 0) (length 2.032)
          (name "~" (effects (font (size 1.27 1.27))))
          (number "1" (effects (font (size 1.27 1.27))))
        )
        (pin passive line (at 5.08 0 180) (length 2.032)
          (name "~" (effects (font (size 1.27 1.27))))
          (number "2" (effects (font (size 1.27 1.27))))
        )
      )
    )
	(symbol "kria-k26-devboard:C_18p_0402" (pin_numbers hide) (pin_names hide) (in_bom yes) (on_board yes)
      (property "Reference" "C" (at 20.32 -5.08 0)
        (effects (font (size 1.27 1.27) (thickness 0.15)) (justify left bottom))
      )
      (property "Value" "C_18p_0402" (at 20.32 -10.16 0)
        (effects (font (size 1.27 1.27) (thickness 0.15)) (justify left bottom) hide)
      )
      (property "Footprint" "kria-k26-devboard-footprints:C_0402_1005Metric" (at 20.32 -12.7 0)
        (effects (font (size 1.27 1.27) (thickness 0.15)) (justify left bottom) hide)
      )
      (property "Datasheet" " " (at 20.32 -15.24 0)
        (effects (font (size 1.27 1.27) (thickness 0.15)) (justify left bottom) hide)
      )
      (property "MPN" "MC0402N180J500CT" (at 20.32 -17.78 0)
        (effects (font (size 1.27 1.27) (thickness 0.15)) (justify left bottom) hide)
      )
      (property "Manufacturer" "Multicomp" (at 20.32 -20.32 0)
        (effects (font (size 1.27 1.27) (thickness 0.15)) (justify left bottom) hide)
      )
      (property "License" "Apache-2.0" (at 20.32 -22.86 0)
        (effects (font (size 1.27 1.27) (thickness 0.15)) (justify left bottom) hide)
      )
      (property "Author" "Antmicro" (at 20.32 -25.4 0)
        (effects (font (size 1.27 1.27) (thickness 0.15)) (justify left bottom) hide)
      )
      (property "Val" "18p" (at 20.32 -7.62 0)
        (effects (font (size 1.27 1.27) (thickness 0.15)) (justify left bottom))
      )
      (property "Voltage" "" (at 20.32 -27.94 0)
        (effects (font (size 1.27 1.27)) (justify left bottom) hide)
      )
      (property "Dielectric" "" (at 20.32 -30.48 0)
        (effects (font (size 1.27 1.27)) (justify left bottom) hide)
      )
      (property "ki_description" " " (at 0 0 0)
        (effects (font (size 1.27 1.27)) hide)
      )
      (symbol "C_18p_0402_0_1"
        (polyline
          (pts
            (xy 2.032 -1.524)
            (xy 2.032 1.524)
          )
          (stroke (width 0.3048) (type default))
          (fill (type none))
        )
        (polyline
          (pts
            (xy 3.048 -1.524)
            (xy 3.048 1.524)
          )
          (stroke (width 0.3302) (type default))
          (fill (type none))
        )
      )
      (symbol "C_18p_0402_1_1"
        (pin passive line (at 0 0 0) (length 2.032)
          (name "~" (effects (font (size 1.27 1.27))))
          (number "1" (effects (font (size 1.27 1.27))))
        )
        (pin passive line (at 5.08 0 180) (length 2.032)
          (name "~" (effects (font (size 1.27 1.27))))
          (number "2" (effects (font (size 1.27 1.27))))
        )
      )
    )
	(symbol "kria-k26-devboard:C_1u_0402" (pin_numbers hide) (pin_names hide) (in_bom yes) (on_board yes)
      (property "Reference" "C" (at 20.32 -5.08 0)
        (effects (font (size 1.27 1.27) (thickness 0.15)) (justify left bottom))
      )
      (property "Value" "C_1u_0402" (at 20.32 -10.16 0)
        (effects (font (size 1.27 1.27) (thickness 0.15)) (justify left bottom) hide)
      )
      (property "Footprint" "kria-k26-devboard-footprints:C_0402_1005Metric" (at 20.32 -12.7 0)
        (effects (font (size 1.27 1.27) (thickness 0.15)) (justify left bottom) hide)
      )
      (property "Datasheet" " " (at 20.32 -15.24 0)
        (effects (font (size 1.27 1.27) (thickness 0.15)) (justify left bottom) hide)
      )
      (property "MPN" "C1005X6S1A105K050BC" (at 20.32 -17.78 0)
        (effects (font (size 1.27 1.27) (thickness 0.15)) (justify left bottom) hide)
      )
      (property "Manufacturer" "TDK" (at 20.32 -20.32 0)
        (effects (font (size 1.27 1.27) (thickness 0.15)) (justify left bottom) hide)
      )
      (property "License" "Apache-2.0" (at 20.32 -22.86 0)
        (effects (font (size 1.27 1.27) (thickness 0.15)) (justify left bottom) hide)
      )
      (property "Author" "Antmicro" (at 20.32 -25.4 0)
        (effects (font (size 1.27 1.27) (thickness 0.15)) (justify left bottom) hide)
      )
      (property "Val" "1u" (at 20.32 -7.62 0)
        (effects (font (size 1.27 1.27) (thickness 0.15)) (justify left bottom))
      )
      (property "Voltage" "" (at 20.32 -27.94 0)
        (effects (font (size 1.27 1.27)) (justify left bottom) hide)
      )
      (property "Dielectric" "" (at 20.32 -30.48 0)
        (effects (font (size 1.27 1.27)) (justify left bottom) hide)
      )
      (property "ki_description" " " (at 0 0 0)
        (effects (font (size 1.27 1.27)) hide)
      )
      (symbol "C_1u_0402_0_1"
        (polyline
          (pts
            (xy 2.032 -1.524)
            (xy 2.032 1.524)
          )
          (stroke (width 0.3048) (type default))
          (fill (type none))
        )
        (polyline
          (pts
            (xy 3.048 -1.524)
            (xy 3.048 1.524)
          )
          (stroke (width 0.3302) (type default))
          (fill (type none))
        )
      )
      (symbol "C_1u_0402_1_1"
        (pin passive line (at 0 0 0) (length 2.032)
          (name "~" (effects (font (size 1.27 1.27))))
          (number "1" (effects (font (size 1.27 1.27))))
        )
        (pin passive line (at 5.08 0 180) (length 2.032)
          (name "~" (effects (font (size 1.27 1.27))))
          (number "2" (effects (font (size 1.27 1.27))))
        )
      )
    )
	(symbol "kria-k26-devboard:C_1u_25V_0603" (pin_numbers hide) (pin_names hide) (in_bom yes) (on_board yes)
      (property "Reference" "C" (at 20.32 -5.08 0)
        (effects (font (size 1.27 1.27) (thickness 0.15)) (justify left bottom))
      )
      (property "Value" "C_1u_25V_0603" (at 20.32 -10.16 0)
        (effects (font (size 1.27 1.27) (thickness 0.15)) (justify left bottom) hide)
      )
      (property "Footprint" "kria-k26-devboard-footprints:C_0603_1608Metric" (at 20.32 -12.7 0)
        (effects (font (size 1.27 1.27) (thickness 0.15)) (justify left bottom) hide)
      )
      (property "Datasheet" " " (at 20.32 -15.24 0)
        (effects (font (size 1.27 1.27) (thickness 0.15)) (justify left bottom) hide)
      )
      (property "MPN" "CL10A105KA8NNNC" (at 20.32 -17.78 0)
        (effects (font (size 1.27 1.27) (thickness 0.15)) (justify left bottom) hide)
      )
      (property "Manufacturer" "Samsung" (at 20.32 -20.32 0)
        (effects (font (size 1.27 1.27) (thickness 0.15)) (justify left bottom) hide)
      )
      (property "License" "Apache-2.0" (at 20.32 -22.86 0)
        (effects (font (size 1.27 1.27) (thickness 0.15)) (justify left bottom) hide)
      )
      (property "Author" "Antmicro" (at 20.32 -25.4 0)
        (effects (font (size 1.27 1.27) (thickness 0.15)) (justify left bottom) hide)
      )
      (property "Val" "1u/25V" (at 20.32 -7.62 0)
        (effects (font (size 1.27 1.27) (thickness 0.15)) (justify left bottom))
      )
      (property "Voltage" "" (at 20.32 -27.94 0)
        (effects (font (size 1.27 1.27)) (justify left bottom) hide)
      )
      (property "Dielectric" "" (at 20.32 -30.48 0)
        (effects (font (size 1.27 1.27)) (justify left bottom) hide)
      )
      (property "ki_description" " " (at 0 0 0)
        (effects (font (size 1.27 1.27)) hide)
      )
      (symbol "C_1u_25V_0603_0_1"
        (polyline
          (pts
            (xy 2.032 -1.524)
            (xy 2.032 1.524)
          )
          (stroke (width 0.3048) (type default))
          (fill (type none))
        )
        (polyline
          (pts
            (xy 3.048 -1.524)
            (xy 3.048 1.524)
          )
          (stroke (width 0.3302) (type default))
          (fill (type none))
        )
      )
      (symbol "C_1u_25V_0603_1_1"
        (pin passive line (at 0 0 0) (length 2.032)
          (name "~" (effects (font (size 1.27 1.27))))
          (number "1" (effects (font (size 1.27 1.27))))
        )
        (pin passive line (at 5.08 0 180) (length 2.032)
          (name "~" (effects (font (size 1.27 1.27))))
          (number "2" (effects (font (size 1.27 1.27))))
        )
      )
    )
	(symbol "kria-k26-devboard:C_22p_0402" (pin_numbers hide) (pin_names hide) (in_bom yes) (on_board yes)
      (property "Reference" "C" (at 20.32 -5.08 0)
        (effects (font (size 1.27 1.27) (thickness 0.15)) (justify left bottom))
      )
      (property "Value" "C_22p_0402" (at 20.32 -10.16 0)
        (effects (font (size 1.27 1.27) (thickness 0.15)) (justify left bottom) hide)
      )
      (property "Footprint" "kria-k26-devboard-footprints:C_0402_1005Metric" (at 20.32 -12.7 0)
        (effects (font (size 1.27 1.27) (thickness 0.15)) (justify left bottom) hide)
      )
      (property "Datasheet" " " (at 20.32 -15.24 0)
        (effects (font (size 1.27 1.27) (thickness 0.15)) (justify left bottom) hide)
      )
      (property "MPN" "CC0402JRNPO9BN220" (at 20.32 -17.78 0)
        (effects (font (size 1.27 1.27) (thickness 0.15)) (justify left bottom) hide)
      )
      (property "Manufacturer" "Yaego" (at 20.32 -20.32 0)
        (effects (font (size 1.27 1.27) (thickness 0.15)) (justify left bottom) hide)
      )
      (property "License" "Apache-2.0" (at 20.32 -22.86 0)
        (effects (font (size 1.27 1.27) (thickness 0.15)) (justify left bottom) hide)
      )
      (property "Author" "Antmicro" (at 20.32 -25.4 0)
        (effects (font (size 1.27 1.27) (thickness 0.15)) (justify left bottom) hide)
      )
      (property "Val" "22p" (at 20.32 -7.62 0)
        (effects (font (size 1.27 1.27) (thickness 0.15)) (justify left bottom))
      )
      (property "Voltage" "" (at 20.32 -27.94 0)
        (effects (font (size 1.27 1.27)) (justify left bottom) hide)
      )
      (property "Dielectric" "" (at 20.32 -30.48 0)
        (effects (font (size 1.27 1.27)) (justify left bottom) hide)
      )
      (property "ki_description" " " (at 0 0 0)
        (effects (font (size 1.27 1.27)) hide)
      )
      (symbol "C_22p_0402_0_1"
        (polyline
          (pts
            (xy 2.032 -1.524)
            (xy 2.032 1.524)
          )
          (stroke (width 0.3048) (type default))
          (fill (type none))
        )
        (polyline
          (pts
            (xy 3.048 -1.524)
            (xy 3.048 1.524)
          )
          (stroke (width 0.3302) (type default))
          (fill (type none))
        )
      )
      (symbol "C_22p_0402_1_1"
        (pin passive line (at 0 0 0) (length 2.032)
          (name "~" (effects (font (size 1.27 1.27))))
          (number "1" (effects (font (size 1.27 1.27))))
        )
        (pin passive line (at 5.08 0 180) (length 2.032)
          (name "~" (effects (font (size 1.27 1.27))))
          (number "2" (effects (font (size 1.27 1.27))))
        )
      )
    )
	(symbol "kria-k26-devboard:C_22u_0603" (pin_numbers hide) (pin_names hide) (in_bom yes) (on_board yes)
      (property "Reference" "C" (at 20.32 -5.08 0)
        (effects (font (size 1.27 1.27) (thickness 0.15)) (justify left bottom))
      )
      (property "Value" "C_22u_0603" (at 20.32 -10.16 0)
        (effects (font (size 1.27 1.27) (thickness 0.15)) (justify left bottom) hide)
      )
      (property "Footprint" "kria-k26-devboard-footprints:C_0603_1608Metric" (at 20.32 -12.7 0)
        (effects (font (size 1.27 1.27) (thickness 0.15)) (justify left bottom) hide)
      )
      (property "Datasheet" " " (at 20.32 -15.24 0)
        (effects (font (size 1.27 1.27) (thickness 0.15)) (justify left bottom) hide)
      )
      (property "MPN" "GRM188R60J226MEA0D" (at 20.32 -17.78 0)
        (effects (font (size 1.27 1.27) (thickness 0.15)) (justify left bottom) hide)
      )
      (property "Manufacturer" "Murata" (at 20.32 -20.32 0)
        (effects (font (size 1.27 1.27) (thickness 0.15)) (justify left bottom) hide)
      )
      (property "License" "Apache-2.0" (at 20.32 -22.86 0)
        (effects (font (size 1.27 1.27) (thickness 0.15)) (justify left bottom) hide)
      )
      (property "Author" "Antmicro" (at 20.32 -25.4 0)
        (effects (font (size 1.27 1.27) (thickness 0.15)) (justify left bottom) hide)
      )
      (property "Val" "22u" (at 20.32 -7.62 0)
        (effects (font (size 1.27 1.27) (thickness 0.15)) (justify left bottom))
      )
      (property "Voltage" "" (at 20.32 -27.94 0)
        (effects (font (size 1.27 1.27)) (justify left bottom) hide)
      )
      (property "Dielectric" "" (at 20.32 -30.48 0)
        (effects (font (size 1.27 1.27)) (justify left bottom) hide)
      )
      (property "ki_description" " " (at 0 0 0)
        (effects (font (size 1.27 1.27)) hide)
      )
      (symbol "C_22u_0603_0_1"
        (polyline
          (pts
            (xy 2.032 -1.524)
            (xy 2.032 1.524)
          )
          (stroke (width 0.3048) (type default))
          (fill (type none))
        )
        (polyline
          (pts
            (xy 3.048 -1.524)
            (xy 3.048 1.524)
          )
          (stroke (width 0.3302) (type default))
          (fill (type none))
        )
      )
      (symbol "C_22u_0603_1_1"
        (pin passive line (at 0 0 0) (length 2.032)
          (name "~" (effects (font (size 1.27 1.27))))
          (number "1" (effects (font (size 1.27 1.27))))
        )
        (pin passive line (at 5.08 0 180) (length 2.032)
          (name "~" (effects (font (size 1.27 1.27))))
          (number "2" (effects (font (size 1.27 1.27))))
        )
      )
    )
	(symbol "kria-k26-devboard:C_22u_0603_10" (pin_numbers hide) (pin_names hide) (in_bom yes) (on_board yes)
      (property "Reference" "C" (at 20.32 -5.08 0)
        (effects (font (size 1.27 1.27) (thickness 0.15)) (justify left bottom))
      )
      (property "Value" "C_22u_0603_10" (at 20.32 -10.16 0)
        (effects (font (size 1.27 1.27) (thickness 0.15)) (justify left bottom) hide)
      )
      (property "Footprint" "kria-k26-devboard-footprints:C_0603_1608Metric" (at 20.32 -12.7 0)
        (effects (font (size 1.27 1.27) (thickness 0.15)) (justify left bottom) hide)
      )
      (property "Datasheet" " " (at 20.32 -15.24 0)
        (effects (font (size 1.27 1.27) (thickness 0.15)) (justify left bottom) hide)
      )
      (property "MPN" "GRM188R60J226MEA0D" (at 20.32 -17.78 0)
        (effects (font (size 1.27 1.27) (thickness 0.15)) (justify left bottom) hide)
      )
      (property "Manufacturer" "Murata" (at 20.32 -20.32 0)
        (effects (font (size 1.27 1.27) (thickness 0.15)) (justify left bottom) hide)
      )
      (property "License" "Apache-2.0" (at 20.32 -22.86 0)
        (effects (font (size 1.27 1.27) (thickness 0.15)) (justify left bottom) hide)
      )
      (property "Author" "Antmicro" (at 20.32 -25.4 0)
        (effects (font (size 1.27 1.27) (thickness 0.15)) (justify left bottom) hide)
      )
      (property "Val" "22u" (at 20.32 -7.62 0)
        (effects (font (size 1.27 1.27) (thickness 0.15)) (justify left bottom))
      )
      (property "Voltage" "" (at 20.32 -27.94 0)
        (effects (font (size 1.27 1.27)) (justify left bottom) hide)
      )
      (property "Dielectric" "" (at 20.32 -30.48 0)
        (effects (font (size 1.27 1.27)) (justify left bottom) hide)
      )
      (property "ki_description" " " (at 0 0 0)
        (effects (font (size 1.27 1.27)) hide)
      )
      (symbol "C_22u_0603_10_0_1"
        (polyline
          (pts
            (xy 2.032 -1.524)
            (xy 2.032 1.524)
          )
          (stroke (width 0.3048) (type default))
          (fill (type none))
        )
        (polyline
          (pts
            (xy 3.048 -1.524)
            (xy 3.048 1.524)
          )
          (stroke (width 0.3302) (type default))
          (fill (type none))
        )
      )
      (symbol "C_22u_0603_10_1_1"
        (pin passive line (at 0 0 0) (length 2.032)
          (name "~" (effects (font (size 1.27 1.27))))
          (number "1" (effects (font (size 1.27 1.27))))
        )
        (pin passive line (at 5.08 0 180) (length 2.032)
          (name "~" (effects (font (size 1.27 1.27))))
          (number "2" (effects (font (size 1.27 1.27))))
        )
      )
    )
	(symbol "kria-k26-devboard:C_22u_0603_11" (pin_numbers hide) (pin_names hide) (in_bom yes) (on_board yes)
      (property "Reference" "C" (at 20.32 -5.08 0)
        (effects (font (size 1.27 1.27) (thickness 0.15)) (justify left bottom))
      )
      (property "Value" "C_22u_0603_11" (at 20.32 -10.16 0)
        (effects (font (size 1.27 1.27) (thickness 0.15)) (justify left bottom) hide)
      )
      (property "Footprint" "kria-k26-devboard-footprints:C_0603_1608Metric" (at 20.32 -12.7 0)
        (effects (font (size 1.27 1.27) (thickness 0.15)) (justify left bottom) hide)
      )
      (property "Datasheet" " " (at 20.32 -15.24 0)
        (effects (font (size 1.27 1.27) (thickness 0.15)) (justify left bottom) hide)
      )
      (property "MPN" "GRM188R60J226MEA0D" (at 20.32 -17.78 0)
        (effects (font (size 1.27 1.27) (thickness 0.15)) (justify left bottom) hide)
      )
      (property "Manufacturer" "Murata" (at 20.32 -20.32 0)
        (effects (font (size 1.27 1.27) (thickness 0.15)) (justify left bottom) hide)
      )
      (property "License" "Apache-2.0" (at 20.32 -22.86 0)
        (effects (font (size 1.27 1.27) (thickness 0.15)) (justify left bottom) hide)
      )
      (property "Author" "Antmicro" (at 20.32 -25.4 0)
        (effects (font (size 1.27 1.27) (thickness 0.15)) (justify left bottom) hide)
      )
      (property "Val" "22u" (at 20.32 -7.62 0)
        (effects (font (size 1.27 1.27) (thickness 0.15)) (justify left bottom))
      )
      (property "Voltage" "" (at 20.32 -27.94 0)
        (effects (font (size 1.27 1.27)) (justify left bottom) hide)
      )
      (property "Dielectric" "" (at 20.32 -30.48 0)
        (effects (font (size 1.27 1.27)) (justify left bottom) hide)
      )
      (property "ki_description" " " (at 0 0 0)
        (effects (font (size 1.27 1.27)) hide)
      )
      (symbol "C_22u_0603_11_0_1"
        (polyline
          (pts
            (xy 2.032 -1.524)
            (xy 2.032 1.524)
          )
          (stroke (width 0.3048) (type default))
          (fill (type none))
        )
        (polyline
          (pts
            (xy 3.048 -1.524)
            (xy 3.048 1.524)
          )
          (stroke (width 0.3302) (type default))
          (fill (type none))
        )
      )
      (symbol "C_22u_0603_11_1_1"
        (pin passive line (at 0 0 0) (length 2.032)
          (name "~" (effects (font (size 1.27 1.27))))
          (number "1" (effects (font (size 1.27 1.27))))
        )
        (pin passive line (at 5.08 0 180) (length 2.032)
          (name "~" (effects (font (size 1.27 1.27))))
          (number "2" (effects (font (size 1.27 1.27))))
        )
      )
    )
	(symbol "kria-k26-devboard:C_22u_100V_2220" (pin_numbers hide) (pin_names hide) (in_bom yes) (on_board yes)
      (property "Reference" "C" (at 20.32 -5.08 0)
        (effects (font (size 1.27 1.27) (thickness 0.15)) (justify left bottom))
      )
      (property "Value" "C_22u_100V_2220" (at 20.32 -10.16 0)
        (effects (font (size 1.27 1.27) (thickness 0.15)) (justify left bottom) hide)
      )
      (property "Footprint" "kria-k26-devboard-footprints:C_2220_5650Metric" (at 20.32 -12.7 0)
        (effects (font (size 1.27 1.27) (thickness 0.15)) (justify left bottom) hide)
      )
      (property "Datasheet" " " (at 20.32 -15.24 0)
        (effects (font (size 1.27 1.27) (thickness 0.15)) (justify left bottom) hide)
      )
      (property "MPN" "C5750X7S2A226M280KB" (at 20.32 -17.78 0)
        (effects (font (size 1.27 1.27) (thickness 0.15)) (justify left bottom) hide)
      )
      (property "Manufacturer" "TDK" (at 20.32 -20.32 0)
        (effects (font (size 1.27 1.27) (thickness 0.15)) (justify left bottom) hide)
      )
      (property "License" "Apache-2.0" (at 20.32 -22.86 0)
        (effects (font (size 1.27 1.27) (thickness 0.15)) (justify left bottom) hide)
      )
      (property "Author" "Antmicro" (at 20.32 -25.4 0)
        (effects (font (size 1.27 1.27) (thickness 0.15)) (justify left bottom) hide)
      )
      (property "Val" "22u/100V" (at 20.32 -7.62 0)
        (effects (font (size 1.27 1.27) (thickness 0.15)) (justify left bottom))
      )
      (property "Voltage" "" (at 20.32 -27.94 0)
        (effects (font (size 1.27 1.27)) (justify left bottom) hide)
      )
      (property "Dielectric" "" (at 20.32 -30.48 0)
        (effects (font (size 1.27 1.27)) (justify left bottom) hide)
      )
      (property "ki_description" " " (at 0 0 0)
        (effects (font (size 1.27 1.27)) hide)
      )
      (symbol "C_22u_100V_2220_0_1"
        (polyline
          (pts
            (xy 2.032 -1.524)
            (xy 2.032 1.524)
          )
          (stroke (width 0.3048) (type default))
          (fill (type none))
        )
        (polyline
          (pts
            (xy 3.048 -1.524)
            (xy 3.048 1.524)
          )
          (stroke (width 0.3302) (type default))
          (fill (type none))
        )
      )
      (symbol "C_22u_100V_2220_1_1"
        (pin passive line (at 0 0 0) (length 2.032)
          (name "~" (effects (font (size 1.27 1.27))))
          (number "1" (effects (font (size 1.27 1.27))))
        )
        (pin passive line (at 5.08 0 180) (length 2.032)
          (name "~" (effects (font (size 1.27 1.27))))
          (number "2" (effects (font (size 1.27 1.27))))
        )
      )
    )
	(symbol "kria-k26-devboard:C_22u_16V_0603" (pin_numbers hide) (pin_names hide) (in_bom yes) (on_board yes)
      (property "Reference" "C" (at 20.32 -5.08 0)
        (effects (font (size 1.27 1.27) (thickness 0.15)) (justify left bottom))
      )
      (property "Value" "C_22u_16V_0603" (at 20.32 -10.16 0)
        (effects (font (size 1.27 1.27) (thickness 0.15)) (justify left bottom) hide)
      )
      (property "Footprint" "kria-k26-devboard-footprints:C_0603_1608Metric" (at 20.32 -12.7 0)
        (effects (font (size 1.27 1.27) (thickness 0.15)) (justify left bottom) hide)
      )
      (property "Datasheet" "https://www.mouser.pl/datasheet/2/585/MLCC-1837944.pdf" (at 20.32 -15.24 0)
        (effects (font (size 1.27 1.27) (thickness 0.15)) (justify left bottom) hide)
      )
      (property "MPN" "CL10A226MO7JZNC" (at 20.32 -17.78 0)
        (effects (font (size 1.27 1.27) (thickness 0.15)) (justify left bottom) hide)
      )
      (property "Manufacturer" "Samsung" (at 20.32 -20.32 0)
        (effects (font (size 1.27 1.27) (thickness 0.15)) (justify left bottom) hide)
      )
      (property "License" "Apache-2.0" (at 20.32 -22.86 0)
        (effects (font (size 1.27 1.27) (thickness 0.15)) (justify left bottom) hide)
      )
      (property "Author" "Antmicro" (at 20.32 -25.4 0)
        (effects (font (size 1.27 1.27) (thickness 0.15)) (justify left bottom) hide)
      )
      (property "Val" "22u/16V" (at 20.32 -7.62 0)
        (effects (font (size 1.27 1.27) (thickness 0.15)) (justify left bottom))
      )
      (property "Voltage" "" (at 20.32 -27.94 0)
        (effects (font (size 1.27 1.27)) (justify left bottom) hide)
      )
      (property "Dielectric" "" (at 20.32 -30.48 0)
        (effects (font (size 1.27 1.27)) (justify left bottom) hide)
      )
      (property "ki_description" " " (at 0 0 0)
        (effects (font (size 1.27 1.27)) hide)
      )
      (symbol "C_22u_16V_0603_0_1"
        (polyline
          (pts
            (xy 2.032 -1.524)
            (xy 2.032 1.524)
          )
          (stroke (width 0.3048) (type default))
          (fill (type none))
        )
        (polyline
          (pts
            (xy 3.048 -1.524)
            (xy 3.048 1.524)
          )
          (stroke (width 0.3302) (type default))
          (fill (type none))
        )
      )
      (symbol "C_22u_16V_0603_1_1"
        (pin passive line (at 0 0 0) (length 2.032)
          (name "~" (effects (font (size 1.27 1.27))))
          (number "1" (effects (font (size 1.27 1.27))))
        )
        (pin passive line (at 5.08 0 180) (length 2.032)
          (name "~" (effects (font (size 1.27 1.27))))
          (number "2" (effects (font (size 1.27 1.27))))
        )
      )
    )
	(symbol "kria-k26-devboard:C_3n9_0402" (pin_numbers hide) (pin_names hide) (in_bom yes) (on_board yes)
      (property "Reference" "C" (at 20.32 -5.08 0)
        (effects (font (size 1.27 1.27) (thickness 0.15)) (justify left bottom))
      )
      (property "Value" "C_3n9_0402" (at 20.32 -10.16 0)
        (effects (font (size 1.27 1.27) (thickness 0.15)) (justify left bottom) hide)
      )
      (property "Footprint" "kria-k26-devboard-footprints:C_0402_1005Metric" (at 20.32 -12.7 0)
        (effects (font (size 1.27 1.27) (thickness 0.15)) (justify left bottom) hide)
      )
      (property "Datasheet" " " (at 20.32 -15.24 0)
        (effects (font (size 1.27 1.27) (thickness 0.15)) (justify left bottom) hide)
      )
      (property "MPN" "GRM155R71H392KA01D" (at 20.32 -17.78 0)
        (effects (font (size 1.27 1.27) (thickness 0.15)) (justify left bottom) hide)
      )
      (property "Manufacturer" "Murata" (at 20.32 -20.32 0)
        (effects (font (size 1.27 1.27) (thickness 0.15)) (justify left bottom) hide)
      )
      (property "License" "Apache-2.0" (at 20.32 -22.86 0)
        (effects (font (size 1.27 1.27) (thickness 0.15)) (justify left bottom) hide)
      )
      (property "Author" "Antmicro" (at 20.32 -25.4 0)
        (effects (font (size 1.27 1.27) (thickness 0.15)) (justify left bottom) hide)
      )
      (property "Val" "3n9" (at 20.32 -7.62 0)
        (effects (font (size 1.27 1.27) (thickness 0.15)) (justify left bottom))
      )
      (property "Voltage" "" (at 20.32 -27.94 0)
        (effects (font (size 1.27 1.27)) (justify left bottom) hide)
      )
      (property "Dielectric" "" (at 20.32 -30.48 0)
        (effects (font (size 1.27 1.27)) (justify left bottom) hide)
      )
      (property "ki_description" " " (at 0 0 0)
        (effects (font (size 1.27 1.27)) hide)
      )
      (symbol "C_3n9_0402_0_1"
        (polyline
          (pts
            (xy 2.032 -1.524)
            (xy 2.032 1.524)
          )
          (stroke (width 0.3048) (type default))
          (fill (type none))
        )
        (polyline
          (pts
            (xy 3.048 -1.524)
            (xy 3.048 1.524)
          )
          (stroke (width 0.3302) (type default))
          (fill (type none))
        )
      )
      (symbol "C_3n9_0402_1_1"
        (pin passive line (at 0 0 0) (length 2.032)
          (name "~" (effects (font (size 1.27 1.27))))
          (number "1" (effects (font (size 1.27 1.27))))
        )
        (pin passive line (at 5.08 0 180) (length 2.032)
          (name "~" (effects (font (size 1.27 1.27))))
          (number "2" (effects (font (size 1.27 1.27))))
        )
      )
    )
	(symbol "kria-k26-devboard:C_470n_0402" (pin_numbers hide) (pin_names hide) (in_bom yes) (on_board yes)
      (property "Reference" "C" (at 20.32 -5.08 0)
        (effects (font (size 1.27 1.27) (thickness 0.15)) (justify left bottom))
      )
      (property "Value" "C_470n_0402" (at 20.32 -10.16 0)
        (effects (font (size 1.27 1.27) (thickness 0.15)) (justify left bottom) hide)
      )
      (property "Footprint" "kria-k26-devboard-footprints:C_0402_1005Metric" (at 20.32 -12.7 0)
        (effects (font (size 1.27 1.27) (thickness 0.15)) (justify left bottom) hide)
      )
      (property "Datasheet" " " (at 20.32 -15.24 0)
        (effects (font (size 1.27 1.27) (thickness 0.15)) (justify left bottom) hide)
      )
      (property "MPN" "C1005X5R1E474M050BB" (at 20.32 -17.78 0)
        (effects (font (size 1.27 1.27) (thickness 0.15)) (justify left bottom) hide)
      )
      (property "Manufacturer" "TDK" (at 20.32 -20.32 0)
        (effects (font (size 1.27 1.27) (thickness 0.15)) (justify left bottom) hide)
      )
      (property "License" "Apache-2.0" (at 20.32 -22.86 0)
        (effects (font (size 1.27 1.27) (thickness 0.15)) (justify left bottom) hide)
      )
      (property "Author" "Antmicro" (at 20.32 -25.4 0)
        (effects (font (size 1.27 1.27) (thickness 0.15)) (justify left bottom) hide)
      )
      (property "Val" "470n" (at 20.32 -7.62 0)
        (effects (font (size 1.27 1.27) (thickness 0.15)) (justify left bottom))
      )
      (property "Voltage" "" (at 20.32 -27.94 0)
        (effects (font (size 1.27 1.27)) (justify left bottom) hide)
      )
      (property "Dielectric" "" (at 20.32 -30.48 0)
        (effects (font (size 1.27 1.27)) (justify left bottom) hide)
      )
      (property "ki_description" " " (at 0 0 0)
        (effects (font (size 1.27 1.27)) hide)
      )
      (symbol "C_470n_0402_0_1"
        (polyline
          (pts
            (xy 2.032 -1.524)
            (xy 2.032 1.524)
          )
          (stroke (width 0.3048) (type default))
          (fill (type none))
        )
        (polyline
          (pts
            (xy 3.048 -1.524)
            (xy 3.048 1.524)
          )
          (stroke (width 0.3302) (type default))
          (fill (type none))
        )
      )
      (symbol "C_470n_0402_1_1"
        (pin passive line (at 0 0 0) (length 2.032)
          (name "~" (effects (font (size 1.27 1.27))))
          (number "1" (effects (font (size 1.27 1.27))))
        )
        (pin passive line (at 5.08 0 180) (length 2.032)
          (name "~" (effects (font (size 1.27 1.27))))
          (number "2" (effects (font (size 1.27 1.27))))
        )
      )
    )
	(symbol "kria-k26-devboard:C_47n_0402" (pin_numbers hide) (pin_names hide) (in_bom yes) (on_board yes)
      (property "Reference" "C" (at 20.32 -5.08 0)
        (effects (font (size 1.27 1.27) (thickness 0.15)) (justify left bottom))
      )
      (property "Value" "C_47n_0402" (at 20.32 -10.16 0)
        (effects (font (size 1.27 1.27) (thickness 0.15)) (justify left bottom) hide)
      )
      (property "Footprint" "kria-k26-devboard-footprints:C_0402_1005Metric" (at 20.32 -12.7 0)
        (effects (font (size 1.27 1.27) (thickness 0.15)) (justify left bottom) hide)
      )
      (property "Datasheet" " " (at 20.32 -15.24 0)
        (effects (font (size 1.27 1.27) (thickness 0.15)) (justify left bottom) hide)
      )
      (property "MPN" "MC0402X473K160CT" (at 20.32 -17.78 0)
        (effects (font (size 1.27 1.27) (thickness 0.15)) (justify left bottom) hide)
      )
      (property "Manufacturer" "Multicomp" (at 20.32 -20.32 0)
        (effects (font (size 1.27 1.27) (thickness 0.15)) (justify left bottom) hide)
      )
      (property "License" "Apache-2.0" (at 20.32 -22.86 0)
        (effects (font (size 1.27 1.27) (thickness 0.15)) (justify left bottom) hide)
      )
      (property "Author" "Antmicro" (at 20.32 -25.4 0)
        (effects (font (size 1.27 1.27) (thickness 0.15)) (justify left bottom) hide)
      )
      (property "Val" "47n" (at 20.32 -7.62 0)
        (effects (font (size 1.27 1.27) (thickness 0.15)) (justify left bottom))
      )
      (property "Voltage" "" (at 20.32 -27.94 0)
        (effects (font (size 1.27 1.27)) (justify left bottom) hide)
      )
      (property "Dielectric" "" (at 20.32 -30.48 0)
        (effects (font (size 1.27 1.27)) (justify left bottom) hide)
      )
      (property "ki_description" " " (at 0 0 0)
        (effects (font (size 1.27 1.27)) hide)
      )
      (symbol "C_47n_0402_0_1"
        (polyline
          (pts
            (xy 2.032 -1.524)
            (xy 2.032 1.524)
          )
          (stroke (width 0.3048) (type default))
          (fill (type none))
        )
        (polyline
          (pts
            (xy 3.048 -1.524)
            (xy 3.048 1.524)
          )
          (stroke (width 0.3302) (type default))
          (fill (type none))
        )
      )
      (symbol "C_47n_0402_1_1"
        (pin passive line (at 0 0 0) (length 2.032)
          (name "~" (effects (font (size 1.27 1.27))))
          (number "1" (effects (font (size 1.27 1.27))))
        )
        (pin passive line (at 5.08 0 180) (length 2.032)
          (name "~" (effects (font (size 1.27 1.27))))
          (number "2" (effects (font (size 1.27 1.27))))
        )
      )
    )
	(symbol "kria-k26-devboard:C_47u_0805" (pin_numbers hide) (pin_names hide) (in_bom yes) (on_board yes)
      (property "Reference" "C" (at 20.32 -5.08 0)
        (effects (font (size 1.27 1.27) (thickness 0.15)) (justify left bottom))
      )
      (property "Value" "C_47u_0805" (at 20.32 -10.16 0)
        (effects (font (size 1.27 1.27) (thickness 0.15)) (justify left bottom) hide)
      )
      (property "Footprint" "kria-k26-devboard-footprints:C_0805_2012Metric" (at 20.32 -12.7 0)
        (effects (font (size 1.27 1.27) (thickness 0.15)) (justify left bottom) hide)
      )
      (property "Datasheet" " " (at 20.32 -15.24 0)
        (effects (font (size 1.27 1.27) (thickness 0.15)) (justify left bottom) hide)
      )
      (property "MPN" "C0805C476M9PACTU" (at 20.32 -17.78 0)
        (effects (font (size 1.27 1.27) (thickness 0.15)) (justify left bottom) hide)
      )
      (property "Manufacturer" "KEMET" (at 20.32 -20.32 0)
        (effects (font (size 1.27 1.27) (thickness 0.15)) (justify left bottom) hide)
      )
      (property "License" "Apache-2.0" (at 20.32 -22.86 0)
        (effects (font (size 1.27 1.27) (thickness 0.15)) (justify left bottom) hide)
      )
      (property "Author" "Antmicro" (at 20.32 -25.4 0)
        (effects (font (size 1.27 1.27) (thickness 0.15)) (justify left bottom) hide)
      )
      (property "Val" "47u" (at 20.32 -7.62 0)
        (effects (font (size 1.27 1.27) (thickness 0.15)) (justify left bottom))
      )
      (property "Voltage" "" (at 20.32 -27.94 0)
        (effects (font (size 1.27 1.27)) (justify left bottom) hide)
      )
      (property "Dielectric" "" (at 20.32 -30.48 0)
        (effects (font (size 1.27 1.27)) (justify left bottom) hide)
      )
      (property "ki_description" " " (at 0 0 0)
        (effects (font (size 1.27 1.27)) hide)
      )
      (symbol "C_47u_0805_0_1"
        (polyline
          (pts
            (xy 2.032 -1.524)
            (xy 2.032 1.524)
          )
          (stroke (width 0.3048) (type default))
          (fill (type none))
        )
        (polyline
          (pts
            (xy 3.048 -1.524)
            (xy 3.048 1.524)
          )
          (stroke (width 0.3302) (type default))
          (fill (type none))
        )
      )
      (symbol "C_47u_0805_1_1"
        (pin passive line (at 0 0 0) (length 2.032)
          (name "~" (effects (font (size 1.27 1.27))))
          (number "1" (effects (font (size 1.27 1.27))))
        )
        (pin passive line (at 5.08 0 180) (length 2.032)
          (name "~" (effects (font (size 1.27 1.27))))
          (number "2" (effects (font (size 1.27 1.27))))
        )
      )
    )
	(symbol "kria-k26-devboard:C_47u_16V_1206" (pin_numbers hide) (pin_names hide) (in_bom yes) (on_board yes)
      (property "Reference" "C" (at 20.32 -5.08 0)
        (effects (font (size 1.27 1.27) (thickness 0.15)) (justify left bottom))
      )
      (property "Value" "C_47u_16V_1206" (at 20.32 -10.16 0)
        (effects (font (size 1.27 1.27) (thickness 0.15)) (justify left bottom) hide)
      )
      (property "Footprint" "kria-k26-devboard-footprints:C_1206_3216Metric" (at 20.32 -12.7 0)
        (effects (font (size 1.27 1.27) (thickness 0.15)) (justify left bottom) hide)
      )
      (property "Datasheet" " " (at 20.32 -15.24 0)
        (effects (font (size 1.27 1.27) (thickness 0.15)) (justify left bottom) hide)
      )
      (property "MPN" "C3216X5R1C476M160AB" (at 20.32 -17.78 0)
        (effects (font (size 1.27 1.27) (thickness 0.15)) (justify left bottom) hide)
      )
      (property "Manufacturer" "TDK" (at 20.32 -20.32 0)
        (effects (font (size 1.27 1.27) (thickness 0.15)) (justify left bottom) hide)
      )
      (property "License" "Apache-2.0" (at 20.32 -22.86 0)
        (effects (font (size 1.27 1.27) (thickness 0.15)) (justify left bottom) hide)
      )
      (property "Author" "Antmicro" (at 20.32 -25.4 0)
        (effects (font (size 1.27 1.27) (thickness 0.15)) (justify left bottom) hide)
      )
      (property "Val" "47u/16V" (at 20.32 -7.62 0)
        (effects (font (size 1.27 1.27) (thickness 0.15)) (justify left bottom))
      )
      (property "Voltage" "" (at 20.32 -27.94 0)
        (effects (font (size 1.27 1.27)) (justify left bottom) hide)
      )
      (property "Dielectric" "" (at 20.32 -30.48 0)
        (effects (font (size 1.27 1.27)) (justify left bottom) hide)
      )
      (property "ki_description" " " (at 0 0 0)
        (effects (font (size 1.27 1.27)) hide)
      )
      (symbol "C_47u_16V_1206_0_1"
        (polyline
          (pts
            (xy 2.032 -1.524)
            (xy 2.032 1.524)
          )
          (stroke (width 0.3048) (type default))
          (fill (type none))
        )
        (polyline
          (pts
            (xy 3.048 -1.524)
            (xy 3.048 1.524)
          )
          (stroke (width 0.3302) (type default))
          (fill (type none))
        )
      )
      (symbol "C_47u_16V_1206_1_1"
        (pin passive line (at 0 0 0) (length 2.032)
          (name "~" (effects (font (size 1.27 1.27))))
          (number "1" (effects (font (size 1.27 1.27))))
        )
        (pin passive line (at 5.08 0 180) (length 2.032)
          (name "~" (effects (font (size 1.27 1.27))))
          (number "2" (effects (font (size 1.27 1.27))))
        )
      )
    )
	(symbol "kria-k26-devboard:C_4u7_0402" (pin_numbers hide) (pin_names hide) (in_bom yes) (on_board yes)
      (property "Reference" "C" (at 20.32 -5.08 0)
        (effects (font (size 1.27 1.27) (thickness 0.15)) (justify left bottom))
      )
      (property "Value" "C_4u7_0402" (at 20.32 -10.16 0)
        (effects (font (size 1.27 1.27) (thickness 0.15)) (justify left bottom) hide)
      )
      (property "Footprint" "kria-k26-devboard-footprints:C_0402_1005Metric" (at 20.32 -12.7 0)
        (effects (font (size 1.27 1.27) (thickness 0.15)) (justify left bottom) hide)
      )
      (property "Datasheet" " " (at 20.32 -15.24 0)
        (effects (font (size 1.27 1.27) (thickness 0.15)) (justify left bottom) hide)
      )
      (property "MPN" "GRM155R61A475MEAAD" (at 20.32 -17.78 0)
        (effects (font (size 1.27 1.27) (thickness 0.15)) (justify left bottom) hide)
      )
      (property "Manufacturer" "Murata" (at 20.32 -20.32 0)
        (effects (font (size 1.27 1.27) (thickness 0.15)) (justify left bottom) hide)
      )
      (property "License" "Apache-2.0" (at 20.32 -22.86 0)
        (effects (font (size 1.27 1.27) (thickness 0.15)) (justify left bottom) hide)
      )
      (property "Author" "Antmicro" (at 20.32 -25.4 0)
        (effects (font (size 1.27 1.27) (thickness 0.15)) (justify left bottom) hide)
      )
      (property "Val" "4u7" (at 20.32 -7.62 0)
        (effects (font (size 1.27 1.27) (thickness 0.15)) (justify left bottom))
      )
      (property "Voltage" "" (at 20.32 -27.94 0)
        (effects (font (size 1.27 1.27)) (justify left bottom) hide)
      )
      (property "Dielectric" "" (at 20.32 -30.48 0)
        (effects (font (size 1.27 1.27)) (justify left bottom) hide)
      )
      (property "ki_description" " " (at 0 0 0)
        (effects (font (size 1.27 1.27)) hide)
      )
      (symbol "C_4u7_0402_0_1"
        (polyline
          (pts
            (xy 2.032 -1.524)
            (xy 2.032 1.524)
          )
          (stroke (width 0.3048) (type default))
          (fill (type none))
        )
        (polyline
          (pts
            (xy 3.048 -1.524)
            (xy 3.048 1.524)
          )
          (stroke (width 0.3302) (type default))
          (fill (type none))
        )
      )
      (symbol "C_4u7_0402_1_1"
        (pin passive line (at 0 0 0) (length 2.032)
          (name "~" (effects (font (size 1.27 1.27))))
          (number "1" (effects (font (size 1.27 1.27))))
        )
        (pin passive line (at 5.08 0 180) (length 2.032)
          (name "~" (effects (font (size 1.27 1.27))))
          (number "2" (effects (font (size 1.27 1.27))))
        )
      )
    )
	(symbol "kria-k26-devboard:Conn_FFC_WE_68715014522_CUSTOM_TWO-SIDES" (in_bom yes) (on_board yes)
      (property "Reference" "J" (at 19.05 -2.54 0)
        (effects (font (size 1.27 1.27) (thickness 0.15)) (justify left bottom))
      )
      (property "Value" "Conn_FFC_WE_68715014522_CUSTOM_TWO-SIDES" (at 19.05 -5.08 0)
        (effects (font (size 1.27 1.27) (thickness 0.15)) (justify left bottom))
      )
      (property "Footprint" "kria-k26-devboard-footprints:Conn_FFC_WE_68715014x22_ALT" (at 19.05 -7.62 0)
        (effects (font (size 1.27 1.27) (thickness 0.15)) (justify left bottom) hide)
      )
      (property "Datasheet" "https://www.we-online.com/components/products/datasheet/68715014522.pdf" (at 19.05 -10.16 0)
        (effects (font (size 1.27 1.27) (thickness 0.15)) (justify left bottom) hide)
      )
      (property "MPN" "68715014522" (at 19.05 -12.7 0)
        (effects (font (size 1.27 1.27) (thickness 0.15)) (justify left bottom) hide)
      )
      (property "Manufacturer" "Würth Elektronik" (at 19.05 -15.24 0)
        (effects (font (size 1.27 1.27) (thickness 0.15)) (justify left bottom) hide)
      )
      (property "Author" "Antmicro" (at 19.05 -17.78 0)
        (effects (font (size 1.27 1.27) (thickness 0.15)) (justify left bottom) hide)
      )
      (property "License" "Apache-2.0" (at 19.05 -20.32 0)
        (effects (font (size 1.27 1.27) (thickness 0.15)) (justify left bottom) hide)
      )
      (property "VSD_Class" "Antmicro Dual Camera interface" (at 19.05 -22.86 0)
        (effects (font (size 1.27 1.27)) (justify left bottom) hide)
      )
      (property "ki_keywords" "CONNECTOR" (at 0 0 0)
        (effects (font (size 1.27 1.27)) hide)
      )
      (property "ki_description" "FFC connector" (at 0 0 0)
        (effects (font (size 1.27 1.27)) hide)
      )
      (symbol "Conn_FFC_WE_68715014522_CUSTOM_TWO-SIDES_1_1"
        (rectangle (start 3.81 -124.333) (end 5.08 -124.587)
          (stroke (width 0.254) (type default))
          (fill (type background))
        )
        (rectangle (start 3.81 -121.793) (end 5.08 -122.047)
          (stroke (width 0.254) (type default))
          (fill (type background))
        )
        (rectangle (start 3.81 -119.253) (end 5.08 -119.507)
          (stroke (width 0.254) (type default))
          (fill (type background))
        )
        (rectangle (start 3.81 -116.713) (end 5.08 -116.967)
          (stroke (width 0.254) (type default))
          (fill (type background))
        )
        (rectangle (start 3.81 -114.173) (end 5.08 -114.427)
          (stroke (width 0.254) (type default))
          (fill (type background))
        )
        (rectangle (start 3.81 -111.633) (end 5.08 -111.887)
          (stroke (width 0.254) (type default))
          (fill (type background))
        )
        (rectangle (start 3.81 -109.093) (end 5.08 -109.347)
          (stroke (width 0.254) (type default))
          (fill (type background))
        )
        (rectangle (start 3.81 -106.553) (end 5.08 -106.807)
          (stroke (width 0.254) (type default))
          (fill (type background))
        )
        (rectangle (start 3.81 -104.013) (end 5.08 -104.267)
          (stroke (width 0.254) (type default))
          (fill (type background))
        )
        (rectangle (start 3.81 -101.473) (end 5.08 -101.727)
          (stroke (width 0.254) (type default))
          (fill (type background))
        )
        (rectangle (start 3.81 -98.933) (end 5.08 -99.187)
          (stroke (width 0.254) (type default))
          (fill (type background))
        )
        (rectangle (start 3.81 -96.393) (end 5.08 -96.647)
          (stroke (width 0.254) (type default))
          (fill (type background))
        )
        (rectangle (start 3.81 -93.853) (end 5.08 -94.107)
          (stroke (width 0.254) (type default))
          (fill (type background))
        )
        (rectangle (start 3.81 -91.313) (end 5.08 -91.567)
          (stroke (width 0.254) (type default))
          (fill (type background))
        )
        (rectangle (start 3.81 -88.773) (end 5.08 -89.027)
          (stroke (width 0.254) (type default))
          (fill (type background))
        )
        (rectangle (start 3.81 -86.233) (end 5.08 -86.487)
          (stroke (width 0.254) (type default))
          (fill (type background))
        )
        (rectangle (start 3.81 -83.693) (end 5.08 -83.947)
          (stroke (width 0.254) (type default))
          (fill (type background))
        )
        (rectangle (start 3.81 -81.153) (end 5.08 -81.407)
          (stroke (width 0.254) (type default))
          (fill (type background))
        )
        (rectangle (start 3.81 -78.613) (end 5.08 -78.867)
          (stroke (width 0.254) (type default))
          (fill (type background))
        )
        (rectangle (start 3.81 -76.073) (end 5.08 -76.327)
          (stroke (width 0.254) (type default))
          (fill (type background))
        )
        (rectangle (start 3.81 -73.533) (end 5.08 -73.787)
          (stroke (width 0.254) (type default))
          (fill (type background))
        )
        (rectangle (start 3.81 -70.993) (end 5.08 -71.247)
          (stroke (width 0.254) (type default))
          (fill (type background))
        )
        (rectangle (start 3.81 -68.453) (end 5.08 -68.707)
          (stroke (width 0.254) (type default))
          (fill (type background))
        )
        (rectangle (start 3.81 -65.913) (end 5.08 -66.167)
          (stroke (width 0.254) (type default))
          (fill (type background))
        )
        (rectangle (start 3.81 -63.373) (end 5.08 -63.627)
          (stroke (width 0.254) (type default))
          (fill (type background))
        )
        (rectangle (start 3.81 -60.833) (end 5.08 -61.087)
          (stroke (width 0.254) (type default))
          (fill (type background))
        )
        (rectangle (start 3.81 -58.293) (end 5.08 -58.547)
          (stroke (width 0.254) (type default))
          (fill (type background))
        )
        (rectangle (start 3.81 -55.753) (end 5.08 -56.007)
          (stroke (width 0.254) (type default))
          (fill (type background))
        )
        (rectangle (start 3.81 -53.213) (end 5.08 -53.467)
          (stroke (width 0.254) (type default))
          (fill (type background))
        )
        (rectangle (start 3.81 -50.673) (end 5.08 -50.927)
          (stroke (width 0.254) (type default))
          (fill (type background))
        )
        (rectangle (start 3.81 -48.133) (end 5.08 -48.387)
          (stroke (width 0.254) (type default))
          (fill (type background))
        )
        (rectangle (start 3.81 -45.593) (end 5.08 -45.847)
          (stroke (width 0.254) (type default))
          (fill (type background))
        )
        (rectangle (start 3.81 -43.053) (end 5.08 -43.307)
          (stroke (width 0.254) (type default))
          (fill (type background))
        )
        (rectangle (start 3.81 -40.513) (end 5.08 -40.767)
          (stroke (width 0.254) (type default))
          (fill (type background))
        )
        (rectangle (start 3.81 -37.973) (end 5.08 -38.227)
          (stroke (width 0.254) (type default))
          (fill (type background))
        )
        (rectangle (start 3.81 -35.433) (end 5.08 -35.687)
          (stroke (width 0.254) (type default))
          (fill (type background))
        )
        (rectangle (start 3.81 -32.893) (end 5.08 -33.147)
          (stroke (width 0.254) (type default))
          (fill (type background))
        )
        (rectangle (start 3.81 -30.353) (end 5.08 -30.607)
          (stroke (width 0.254) (type default))
          (fill (type background))
        )
        (rectangle (start 3.81 -27.813) (end 5.08 -28.067)
          (stroke (width 0.254) (type default))
          (fill (type background))
        )
        (rectangle (start 3.81 -25.273) (end 5.08 -25.527)
          (stroke (width 0.254) (type default))
          (fill (type background))
        )
        (rectangle (start 3.81 -22.733) (end 5.08 -22.987)
          (stroke (width 0.254) (type default))
          (fill (type background))
        )
        (rectangle (start 3.81 -20.193) (end 5.08 -20.447)
          (stroke (width 0.254) (type default))
          (fill (type background))
        )
        (rectangle (start 3.81 -17.653) (end 5.08 -17.907)
          (stroke (width 0.254) (type default))
          (fill (type background))
        )
        (rectangle (start 3.81 -15.113) (end 5.08 -15.367)
          (stroke (width 0.254) (type default))
          (fill (type background))
        )
        (rectangle (start 3.81 -12.573) (end 5.08 -12.827)
          (stroke (width 0.254) (type default))
          (fill (type background))
        )
        (rectangle (start 3.81 -10.033) (end 5.08 -10.287)
          (stroke (width 0.254) (type default))
          (fill (type background))
        )
        (rectangle (start 3.81 -7.493) (end 5.08 -7.747)
          (stroke (width 0.254) (type default))
          (fill (type background))
        )
        (rectangle (start 3.81 -4.953) (end 5.08 -5.207)
          (stroke (width 0.254) (type default))
          (fill (type background))
        )
        (rectangle (start 3.81 -2.413) (end 5.08 -2.667)
          (stroke (width 0.254) (type default))
          (fill (type background))
        )
        (rectangle (start 3.81 0.127) (end 5.08 -0.127)
          (stroke (width 0.254) (type default))
          (fill (type background))
        )
        (rectangle (start 3.81 1.27) (end 7.62 -132.08)
          (stroke (width 0.254) (type default))
          (fill (type background))
        )
        (pin passive line (at 0 0 0) (length 3.81)
          (name "~" (effects (font (size 1.27 1.27))))
          (number "1" (effects (font (size 1.27 1.27))))
        )
        (pin passive line (at 0 -22.86 0) (length 3.81)
          (name "~" (effects (font (size 1.27 1.27))))
          (number "10" (effects (font (size 1.27 1.27))))
        )
        (pin passive line (at 0 -25.4 0) (length 3.81)
          (name "~" (effects (font (size 1.27 1.27))))
          (number "11" (effects (font (size 1.27 1.27))))
        )
        (pin passive line (at 0 -27.94 0) (length 3.81)
          (name "~" (effects (font (size 1.27 1.27))))
          (number "12" (effects (font (size 1.27 1.27))))
        )
        (pin passive line (at 0 -30.48 0) (length 3.81)
          (name "~" (effects (font (size 1.27 1.27))))
          (number "13" (effects (font (size 1.27 1.27))))
        )
        (pin passive line (at 0 -33.02 0) (length 3.81)
          (name "~" (effects (font (size 1.27 1.27))))
          (number "14" (effects (font (size 1.27 1.27))))
        )
        (pin passive line (at 0 -35.56 0) (length 3.81)
          (name "~" (effects (font (size 1.27 1.27))))
          (number "15" (effects (font (size 1.27 1.27))))
        )
        (pin passive line (at 0 -38.1 0) (length 3.81)
          (name "~" (effects (font (size 1.27 1.27))))
          (number "16" (effects (font (size 1.27 1.27))))
        )
        (pin passive line (at 0 -40.64 0) (length 3.81)
          (name "~" (effects (font (size 1.27 1.27))))
          (number "17" (effects (font (size 1.27 1.27))))
        )
        (pin passive line (at 0 -43.18 0) (length 3.81)
          (name "~" (effects (font (size 1.27 1.27))))
          (number "18" (effects (font (size 1.27 1.27))))
        )
        (pin passive line (at 0 -45.72 0) (length 3.81)
          (name "~" (effects (font (size 1.27 1.27))))
          (number "19" (effects (font (size 1.27 1.27))))
        )
        (pin passive line (at 0 -2.54 0) (length 3.81)
          (name "~" (effects (font (size 1.27 1.27))))
          (number "2" (effects (font (size 1.27 1.27))))
        )
        (pin passive line (at 0 -48.26 0) (length 3.81)
          (name "~" (effects (font (size 1.27 1.27))))
          (number "20" (effects (font (size 1.27 1.27))))
        )
        (pin passive line (at 0 -50.8 0) (length 3.81)
          (name "~" (effects (font (size 1.27 1.27))))
          (number "21" (effects (font (size 1.27 1.27))))
        )
        (pin passive line (at 0 -53.34 0) (length 3.81)
          (name "~" (effects (font (size 1.27 1.27))))
          (number "22" (effects (font (size 1.27 1.27))))
        )
        (pin passive line (at 0 -55.88 0) (length 3.81)
          (name "~" (effects (font (size 1.27 1.27))))
          (number "23" (effects (font (size 1.27 1.27))))
        )
        (pin passive line (at 0 -58.42 0) (length 3.81)
          (name "~" (effects (font (size 1.27 1.27))))
          (number "24" (effects (font (size 1.27 1.27))))
        )
        (pin passive line (at 0 -60.96 0) (length 3.81)
          (name "~" (effects (font (size 1.27 1.27))))
          (number "25" (effects (font (size 1.27 1.27))))
        )
        (pin passive line (at 0 -63.5 0) (length 3.81)
          (name "~" (effects (font (size 1.27 1.27))))
          (number "26" (effects (font (size 1.27 1.27))))
        )
        (pin passive line (at 0 -66.04 0) (length 3.81)
          (name "~" (effects (font (size 1.27 1.27))))
          (number "27" (effects (font (size 1.27 1.27))))
        )
        (pin passive line (at 0 -68.58 0) (length 3.81)
          (name "~" (effects (font (size 1.27 1.27))))
          (number "28" (effects (font (size 1.27 1.27))))
        )
        (pin passive line (at 0 -71.12 0) (length 3.81)
          (name "~" (effects (font (size 1.27 1.27))))
          (number "29" (effects (font (size 1.27 1.27))))
        )
        (pin passive line (at 0 -5.08 0) (length 3.81)
          (name "~" (effects (font (size 1.27 1.27))))
          (number "3" (effects (font (size 1.27 1.27))))
        )
        (pin passive line (at 0 -73.66 0) (length 3.81)
          (name "~" (effects (font (size 1.27 1.27))))
          (number "30" (effects (font (size 1.27 1.27))))
        )
        (pin passive line (at 0 -76.2 0) (length 3.81)
          (name "~" (effects (font (size 1.27 1.27))))
          (number "31" (effects (font (size 1.27 1.27))))
        )
        (pin passive line (at 0 -78.74 0) (length 3.81)
          (name "~" (effects (font (size 1.27 1.27))))
          (number "32" (effects (font (size 1.27 1.27))))
        )
        (pin passive line (at 0 -81.28 0) (length 3.81)
          (name "~" (effects (font (size 1.27 1.27))))
          (number "33" (effects (font (size 1.27 1.27))))
        )
        (pin passive line (at 0 -83.82 0) (length 3.81)
          (name "~" (effects (font (size 1.27 1.27))))
          (number "34" (effects (font (size 1.27 1.27))))
        )
        (pin passive line (at 0 -86.36 0) (length 3.81)
          (name "~" (effects (font (size 1.27 1.27))))
          (number "35" (effects (font (size 1.27 1.27))))
        )
        (pin passive line (at 0 -88.9 0) (length 3.81)
          (name "~" (effects (font (size 1.27 1.27))))
          (number "36" (effects (font (size 1.27 1.27))))
        )
        (pin passive line (at 0 -91.44 0) (length 3.81)
          (name "~" (effects (font (size 1.27 1.27))))
          (number "37" (effects (font (size 1.27 1.27))))
        )
        (pin passive line (at 0 -93.98 0) (length 3.81)
          (name "~" (effects (font (size 1.27 1.27))))
          (number "38" (effects (font (size 1.27 1.27))))
        )
        (pin passive line (at 0 -96.52 0) (length 3.81)
          (name "~" (effects (font (size 1.27 1.27))))
          (number "39" (effects (font (size 1.27 1.27))))
        )
        (pin passive line (at 0 -7.62 0) (length 3.81)
          (name "~" (effects (font (size 1.27 1.27))))
          (number "4" (effects (font (size 1.27 1.27))))
        )
        (pin passive line (at 0 -99.06 0) (length 3.81)
          (name "~" (effects (font (size 1.27 1.27))))
          (number "40" (effects (font (size 1.27 1.27))))
        )
        (pin passive line (at 0 -101.6 0) (length 3.81)
          (name "~" (effects (font (size 1.27 1.27))))
          (number "41" (effects (font (size 1.27 1.27))))
        )
        (pin passive line (at 0 -104.14 0) (length 3.81)
          (name "~" (effects (font (size 1.27 1.27))))
          (number "42" (effects (font (size 1.27 1.27))))
        )
        (pin passive line (at 0 -106.68 0) (length 3.81)
          (name "~" (effects (font (size 1.27 1.27))))
          (number "43" (effects (font (size 1.27 1.27))))
        )
        (pin passive line (at 0 -109.22 0) (length 3.81)
          (name "~" (effects (font (size 1.27 1.27))))
          (number "44" (effects (font (size 1.27 1.27))))
        )
        (pin passive line (at 0 -111.76 0) (length 3.81)
          (name "~" (effects (font (size 1.27 1.27))))
          (number "45" (effects (font (size 1.27 1.27))))
        )
        (pin passive line (at 0 -114.3 0) (length 3.81)
          (name "~" (effects (font (size 1.27 1.27))))
          (number "46" (effects (font (size 1.27 1.27))))
        )
        (pin passive line (at 0 -116.84 0) (length 3.81)
          (name "~" (effects (font (size 1.27 1.27))))
          (number "47" (effects (font (size 1.27 1.27))))
        )
        (pin passive line (at 0 -119.38 0) (length 3.81)
          (name "~" (effects (font (size 1.27 1.27))))
          (number "48" (effects (font (size 1.27 1.27))))
        )
        (pin passive line (at 0 -121.92 0) (length 3.81)
          (name "~" (effects (font (size 1.27 1.27))))
          (number "49" (effects (font (size 1.27 1.27))))
        )
        (pin passive line (at 0 -10.16 0) (length 3.81)
          (name "~" (effects (font (size 1.27 1.27))))
          (number "5" (effects (font (size 1.27 1.27))))
        )
        (pin passive line (at 0 -124.46 0) (length 3.81)
          (name "~" (effects (font (size 1.27 1.27))))
          (number "50" (effects (font (size 1.27 1.27))))
        )
        (pin passive line (at 0 -12.7 0) (length 3.81)
          (name "~" (effects (font (size 1.27 1.27))))
          (number "6" (effects (font (size 1.27 1.27))))
        )
        (pin passive line (at 0 -15.24 0) (length 3.81)
          (name "~" (effects (font (size 1.27 1.27))))
          (number "7" (effects (font (size 1.27 1.27))))
        )
        (pin passive line (at 0 -17.78 0) (length 3.81)
          (name "~" (effects (font (size 1.27 1.27))))
          (number "8" (effects (font (size 1.27 1.27))))
        )
        (pin passive line (at 0 -20.32 0) (length 3.81)
          (name "~" (effects (font (size 1.27 1.27))))
          (number "9" (effects (font (size 1.27 1.27))))
        )
        (pin passive line (at 0 -127 0) (length 3.81)
          (name "MP" (effects (font (size 1.27 1.27))))
          (number "MP1" (effects (font (size 1.27 1.27))))
        )
        (pin passive line (at 0 -129.54 0) (length 3.81)
          (name "MP" (effects (font (size 1.27 1.27))))
          (number "MP2" (effects (font (size 1.27 1.27))))
        )
      )
    )
	(symbol "kria-k26-devboard:DP83867CR_VQFN" (in_bom yes) (on_board yes)
      (property "Reference" "U" (at 71.12 -3.81 0)
        (effects (font (size 1.27 1.27) (thickness 0.15)) (justify left bottom))
      )
      (property "Value" "DP83867CR_VQFN" (at 71.12 -6.35 0)
        (effects (font (size 1.27 1.27) (thickness 0.15)) (justify left bottom))
      )
      (property "Footprint" "kria-k26-devboard-footprints:QFN-48-1EP_7x7mm" (at 71.12 -8.89 0)
        (effects (font (size 1.27 1.27) (thickness 0.15)) (justify left bottom) hide)
      )
      (property "Datasheet" "https://www.ti.com/lit/ds/symlink/dp83867ir.pdf?ts=1647232328899&ref_url=https%253A%252F%252Fwww.ti.com%252Fproduct%252FDP83867IR" (at 71.12 -11.43 0)
        (effects (font (size 1.27 1.27) (thickness 0.15)) (justify left bottom) hide)
      )
      (property "Manufacturer" "Texas Instruments" (at 71.12 -13.97 0)
        (effects (font (size 1.27 1.27) (thickness 0.15)) (justify left bottom) hide)
      )
      (property "MPN" "DP83867CRRGZR" (at 71.12 -16.51 0)
        (effects (font (size 1.27 1.27) (thickness 0.15)) (justify left bottom) hide)
      )
      (property "Author" "Antmicro" (at 71.12 -19.05 0)
        (effects (font (size 1.27 1.27) (thickness 0.15)) (justify left bottom) hide)
      )
      (property "License" "Apache-2.0" (at 71.12 -21.59 0)
        (effects (font (size 1.27 1.27) (thickness 0.15)) (justify left bottom) hide)
      )
      (property "ki_keywords" "SMT, ETHERNET, IC, TRANSCEIVER" (at 0 0 0)
        (effects (font (size 1.27 1.27)) hide)
      )
      (property "ki_description" "Robust, High Immunity 10/100/1000 Ethernet Physical Layer Transceiver" (at 0 0 0)
        (effects (font (size 1.27 1.27)) hide)
      )
      (property "ki_fp_filters" "RGZ0048B RGZ0048B_NV" (at 0 0 0)
        (effects (font (size 1.27 1.27)) hide)
      )
      (symbol "DP83867CR_VQFN_1_1"
        (rectangle (start 2.54 2.54) (end 41.91 -74.93)
          (stroke (width 0.254) (type default))
          (fill (type background))
        )
        (text "10/100/1000" (at 21.59 0 0)
          (effects (font (size 1.27 1.27)))
        )
        (text "Ethernet PHY" (at 21.59 -2.54 0)
          (effects (font (size 1.27 1.27)))
        )
        (pin bidirectional line (at 44.45 -10.16 180) (length 2.54)
          (name "TD_P_A" (effects (font (size 1.27 1.27))))
          (number "1" (effects (font (size 1.27 1.27))))
        )
        (pin bidirectional line (at 44.45 -33.02 180) (length 2.54)
          (name "TD_P_D" (effects (font (size 1.27 1.27))))
          (number "10" (effects (font (size 1.27 1.27))))
        )
        (pin bidirectional line (at 44.45 -35.56 180) (length 2.54)
          (name "TD_M_D" (effects (font (size 1.27 1.27))))
          (number "11" (effects (font (size 1.27 1.27))))
        )
        (pin passive line (at 44.45 -59.69 180) (length 2.54)
          (name "RBIAS" (effects (font (size 1.27 1.27))))
          (number "12" (effects (font (size 1.27 1.27))))
        )
        (pin power_in line (at 44.45 -2.54 180) (length 2.54)
          (name "VDDA1P8" (effects (font (size 1.27 1.27))))
          (number "13" (effects (font (size 1.27 1.27))))
        )
        (pin bidirectional line (at 0 -72.39 0) (length 2.54)
          (name "X_O" (effects (font (size 1.27 1.27))))
          (number "14" (effects (font (size 1.27 1.27))))
        )
        (pin bidirectional line (at 0 -69.85 0) (length 2.54)
          (name "X_I" (effects (font (size 1.27 1.27))))
          (number "15" (effects (font (size 1.27 1.27))))
        )
        (pin input line (at 0 -10.16 0) (length 2.54)
          (name "MDC" (effects (font (size 1.27 1.27))))
          (number "16" (effects (font (size 1.27 1.27))))
        )
        (pin bidirectional line (at 0 -12.7 0) (length 2.54)
          (name "MDIO" (effects (font (size 1.27 1.27))))
          (number "17" (effects (font (size 1.27 1.27))))
        )
        (pin output line (at 0 -50.8 0) (length 2.54)
          (name "CLK_OUT" (effects (font (size 1.27 1.27))))
          (number "18" (effects (font (size 1.27 1.27))))
        )
        (pin power_in line (at 0 0 0) (length 2.54)
          (name "VDDIO" (effects (font (size 1.27 1.27))))
          (number "19" (effects (font (size 1.27 1.27))))
        )
        (pin bidirectional line (at 44.45 -12.7 180) (length 2.54)
          (name "TD_M_A" (effects (font (size 1.27 1.27))))
          (number "2" (effects (font (size 1.27 1.27))))
        )
        (pin input line (at 0 -59.69 0) (length 2.54)
          (name "JTAG_CLK" (effects (font (size 1.27 1.27))))
          (number "20" (effects (font (size 1.27 1.27))))
        )
        (pin output line (at 0 -57.15 0) (length 2.54)
          (name "JTAG_TDO" (effects (font (size 1.27 1.27))))
          (number "21" (effects (font (size 1.27 1.27))))
        )
        (pin input line (at 0 -62.23 0) (length 2.54)
          (name "JTAG_TMS" (effects (font (size 1.27 1.27))))
          (number "22" (effects (font (size 1.27 1.27))))
        )
        (pin input line (at 0 -54.61 0) (length 2.54)
          (name "JTAG_TDI" (effects (font (size 1.27 1.27))))
          (number "23" (effects (font (size 1.27 1.27))))
        )
        (pin power_in line (at 44.45 0 180) (length 2.54)
          (name "VDD1P0" (effects (font (size 1.27 1.27))))
          (number "24" (effects (font (size 1.27 1.27))))
        )
        (pin input line (at 0 -27.94 0) (length 2.54)
          (name "TX_D3" (effects (font (size 1.27 1.27))))
          (number "25" (effects (font (size 1.27 1.27))))
        )
        (pin input line (at 0 -25.4 0) (length 2.54)
          (name "TX_D2" (effects (font (size 1.27 1.27))))
          (number "26" (effects (font (size 1.27 1.27))))
        )
        (pin input line (at 0 -22.86 0) (length 2.54)
          (name "TX_D1" (effects (font (size 1.27 1.27))))
          (number "27" (effects (font (size 1.27 1.27))))
        )
        (pin input line (at 0 -20.32 0) (length 2.54)
          (name "TX_D0" (effects (font (size 1.27 1.27))))
          (number "28" (effects (font (size 1.27 1.27))))
        )
        (pin input line (at 0 -30.48 0) (length 2.54)
          (name "GTX_CLK" (effects (font (size 1.27 1.27))))
          (number "29" (effects (font (size 1.27 1.27))))
        )
        (pin power_in line (at 0 -2.54 0) (length 2.54)
          (name "VDDA2P5" (effects (font (size 1.27 1.27))))
          (number "3" (effects (font (size 1.27 1.27))))
        )
        (pin passive line (at 0 0 0) (length 2.54) hide
          (name "VDDIO" (effects (font (size 1.27 1.27))))
          (number "30" (effects (font (size 1.27 1.27))))
        )
        (pin passive line (at 44.45 0 180) (length 2.54) hide
          (name "VDD1P0" (effects (font (size 1.27 1.27))))
          (number "31" (effects (font (size 1.27 1.27))))
        )
        (pin output line (at 0 -46.99 0) (length 2.54)
          (name "RX_CLK" (effects (font (size 1.27 1.27))))
          (number "32" (effects (font (size 1.27 1.27))))
        )
        (pin output line (at 0 -36.83 0) (length 2.54)
          (name "RX_D0" (effects (font (size 1.27 1.27))))
          (number "33" (effects (font (size 1.27 1.27))))
        )
        (pin output line (at 0 -39.37 0) (length 2.54)
          (name "RX_D1" (effects (font (size 1.27 1.27))))
          (number "34" (effects (font (size 1.27 1.27))))
        )
        (pin output line (at 0 -41.91 0) (length 2.54)
          (name "RX_D2" (effects (font (size 1.27 1.27))))
          (number "35" (effects (font (size 1.27 1.27))))
        )
        (pin output line (at 0 -44.45 0) (length 2.54)
          (name "RX_D3" (effects (font (size 1.27 1.27))))
          (number "36" (effects (font (size 1.27 1.27))))
        )
        (pin input line (at 0 -17.78 0) (length 2.54)
          (name "TX_EN_TX_CTRL" (effects (font (size 1.27 1.27))))
          (number "37" (effects (font (size 1.27 1.27))))
        )
        (pin output line (at 0 -34.29 0) (length 2.54)
          (name "RX_DV_RX_CTRL" (effects (font (size 1.27 1.27))))
          (number "38" (effects (font (size 1.27 1.27))))
        )
        (pin output line (at 44.45 -52.07 180) (length 2.54)
          (name "GPIO_0" (effects (font (size 1.27 1.27))))
          (number "39" (effects (font (size 1.27 1.27))))
        )
        (pin bidirectional line (at 44.45 -17.78 180) (length 2.54)
          (name "TD_P_B" (effects (font (size 1.27 1.27))))
          (number "4" (effects (font (size 1.27 1.27))))
        )
        (pin output line (at 44.45 -54.61 180) (length 2.54)
          (name "GPIO_1" (effects (font (size 1.27 1.27))))
          (number "40" (effects (font (size 1.27 1.27))))
        )
        (pin passive line (at 0 0 0) (length 2.54) hide
          (name "VDDIO" (effects (font (size 1.27 1.27))))
          (number "41" (effects (font (size 1.27 1.27))))
        )
        (pin passive line (at 44.45 0 180) (length 2.54) hide
          (name "VDD1P0" (effects (font (size 1.27 1.27))))
          (number "42" (effects (font (size 1.27 1.27))))
        )
        (pin input line (at 0 -6.35 0) (length 2.54)
          (name "RESET_N" (effects (font (size 1.27 1.27))))
          (number "43" (effects (font (size 1.27 1.27))))
        )
        (pin bidirectional line (at 0 -66.04 0) (length 2.54)
          (name "INT_PWDN" (effects (font (size 1.27 1.27))))
          (number "44" (effects (font (size 1.27 1.27))))
        )
        (pin bidirectional line (at 44.45 -46.99 180) (length 2.54)
          (name "LED_2" (effects (font (size 1.27 1.27))))
          (number "45" (effects (font (size 1.27 1.27))))
        )
        (pin bidirectional line (at 44.45 -44.45 180) (length 2.54)
          (name "LED_1" (effects (font (size 1.27 1.27))))
          (number "46" (effects (font (size 1.27 1.27))))
        )
        (pin bidirectional line (at 44.45 -41.91 180) (length 2.54)
          (name "LED_0" (effects (font (size 1.27 1.27))))
          (number "47" (effects (font (size 1.27 1.27))))
        )
        (pin power_in line (at 44.45 -5.08 180) (length 2.54)
          (name "VDDA1P8" (effects (font (size 1.27 1.27))))
          (number "48" (effects (font (size 1.27 1.27))))
        )
        (pin power_in line (at 44.45 -72.39 180) (length 2.54)
          (name "PAD" (effects (font (size 1.27 1.27))))
          (number "49" (effects (font (size 1.27 1.27))))
        )
        (pin bidirectional line (at 44.45 -20.32 180) (length 2.54)
          (name "TD_M_B" (effects (font (size 1.27 1.27))))
          (number "5" (effects (font (size 1.27 1.27))))
        )
        (pin passive line (at 44.45 0 180) (length 2.54) hide
          (name "VDD1P0" (effects (font (size 1.27 1.27))))
          (number "6" (effects (font (size 1.27 1.27))))
        )
        (pin bidirectional line (at 44.45 -25.4 180) (length 2.54)
          (name "TD_P_C" (effects (font (size 1.27 1.27))))
          (number "7" (effects (font (size 1.27 1.27))))
        )
        (pin bidirectional line (at 44.45 -27.94 180) (length 2.54)
          (name "TD_M_C" (effects (font (size 1.27 1.27))))
          (number "8" (effects (font (size 1.27 1.27))))
        )
        (pin passive line (at 0 -2.54 0) (length 2.54) hide
          (name "VDDA2P5" (effects (font (size 1.27 1.27))))
          (number "9" (effects (font (size 1.27 1.27))))
        )
      )
    )
	(symbol "kria-k26-devboard:DTC014T_SOT-416" (pin_names (offset 0)) (in_bom yes) (on_board yes)
      (property "Reference" "Q" (at 25.4 -5.08 0)
        (effects (font (size 1.27 1.27) (thickness 0.15)) (justify left bottom))
      )
      (property "Value" "DTC014T_SOT-416" (at 25.4 -7.62 0)
        (effects (font (size 1.27 1.27) (thickness 0.15)) (justify left bottom))
      )
      (property "Footprint" "kria-k26-devboard-footprints:SOT-416" (at 25.4 -10.16 0)
        (effects (font (size 1.27 1.27) (thickness 0.15)) (justify left bottom) hide)
      )
      (property "Datasheet" "https://www.rohm.com/datasheet?p=DTC014TEB&dist=Mouser&media=referral&source=mouser.com&campaign=Mouser" (at 25.4 -12.7 0)
        (effects (font (size 1.27 1.27) (thickness 0.15)) (justify left bottom) hide)
      )
      (property "Manufacturer" "ROHM Semiconductor" (at 25.4 -15.24 0)
        (effects (font (size 1.27 1.27) (thickness 0.15)) (justify left bottom) hide)
      )
      (property "MPN" "DTC014TEBTL" (at 25.4 -17.78 0)
        (effects (font (size 1.27 1.27) (thickness 0.15)) (justify left bottom) hide)
      )
      (property "Author" "Antmicro" (at 25.4 -20.32 0)
        (effects (font (size 1.27 1.27) (thickness 0.15)) (justify left bottom) hide)
      )
      (property "License" "Apache-2.0" (at 25.4 -22.86 0)
        (effects (font (size 1.27 1.27) (thickness 0.15)) (justify left bottom) hide)
      )
      (property "ki_description" "Digital NPN Transistor, 10k/NONE, EMT-3" (at 0 0 0)
        (effects (font (size 1.27 1.27)) hide)
      )
      (property "ki_fp_filters" "SOT?23* SC?59*" (at 0 0 0)
        (effects (font (size 1.27 1.27)) hide)
      )
      (symbol "DTC014T_SOT-416_0_1"
        (polyline
          (pts
            (xy 2.54 0)
            (xy 3.175 0)
          )
          (stroke (width 0.254) (type default))
          (fill (type none))
        )
        (polyline
          (pts
            (xy 5.08 0)
            (xy 5.588 0)
          )
          (stroke (width 0.254) (type default))
          (fill (type none))
        )
        (polyline
          (pts
            (xy 5.715 0.635)
            (xy 7.62 2.54)
          )
          (stroke (width 0.254) (type default))
          (fill (type none))
        )
        (polyline
          (pts
            (xy 5.715 -0.635)
            (xy 7.62 -2.54)
            (xy 7.62 -2.54)
          )
          (stroke (width 0.254) (type default))
          (fill (type none))
        )
        (polyline
          (pts
            (xy 5.715 1.905)
            (xy 5.715 -1.905)
            (xy 5.715 -1.905)
          )
          (stroke (width 0.508) (type default))
          (fill (type none))
        )
        (polyline
          (pts
            (xy 6.35 -1.778)
            (xy 6.858 -1.27)
            (xy 7.366 -2.286)
            (xy 6.35 -1.778)
            (xy 6.35 -1.778)
          )
          (stroke (width 0) (type default))
          (fill (type outline))
        )
        (circle (center 5.588 0) (radius 3.2528)
          (stroke (width 0.254) (type default))
          (fill (type background))
        )
      )
      (symbol "DTC014T_SOT-416_1_1"
        (rectangle (start 3.302 0.381) (end 4.953 -0.381)
          (stroke (width 0.254) (type default))
          (fill (type none))
        )
        (text "10k" (at 3.302 0.508 0)
          (effects (font (size 0.635 0.635) (thickness 0.15)) (justify left bottom))
        )
        (pin input line (at 0 0 0) (length 2.54)
          (name "B" (effects (font (size 1.27 1.27))))
          (number "1" (effects (font (size 1.27 1.27))))
        )
        (pin passive line (at 7.62 -5.08 90) (length 2.54)
          (name "E" (effects (font (size 1.27 1.27))))
          (number "2" (effects (font (size 1.27 1.27))))
        )
        (pin passive line (at 7.62 5.08 270) (length 2.54)
          (name "C" (effects (font (size 1.27 1.27))))
          (number "3" (effects (font (size 1.27 1.27))))
        )
      )
    )
	(symbol "kria-k26-devboard:DisplayPort_Molex_472720001" (in_bom yes) (on_board yes)
      (property "Reference" "J" (at 40.64 -2.54 0)
        (effects (font (size 1.27 1.27) (thickness 0.15)) (justify left bottom))
      )
      (property "Value" "DisplayPort_Molex_472720001" (at 40.64 -5.08 0)
        (effects (font (size 1.27 1.27) (thickness 0.15)) (justify left bottom))
      )
      (property "Footprint" "kria-k26-devboard-footprints:DisplayPort_Receptacle_Molex_472720001" (at 40.64 -7.62 0)
        (effects (font (size 1.27 1.27) (thickness 0.15)) (justify left bottom) hide)
      )
      (property "Datasheet" "https://www.molex.com/en-us/products/part-detail/472720001" (at 40.64 -10.16 0)
        (effects (font (size 1.27 1.27) (thickness 0.15)) (justify left bottom) hide)
      )
      (property "MPN" "472720001" (at 40.64 -12.7 0)
        (effects (font (size 1.27 1.27) (thickness 0.15)) (justify left bottom) hide)
      )
      (property "Manufacturer" "Molex" (at 40.64 -15.24 0)
        (effects (font (size 1.27 1.27) (thickness 0.15)) (justify left bottom) hide)
      )
      (property "Author" "Antmicro" (at 40.64 -17.78 0)
        (effects (font (size 1.27 1.27) (thickness 0.15)) (justify left bottom) hide)
      )
      (property "License" "Apache-2.0" (at 40.64 -20.32 0)
        (effects (font (size 1.27 1.27) (thickness 0.15)) (justify left bottom) hide)
      )
      (property "ki_keywords" "DISPLAYPORT, CONNECTOR, SMT, THT, HORIZONTAL" (at 0 0 0)
        (effects (font (size 1.27 1.27)) hide)
      )
      (property "ki_description" "DisplayPort Receptacle Connector 20 Position Surface Mount, Right Angle; Through Hole" (at 0 0 0)
        (effects (font (size 1.27 1.27)) hide)
      )
      (symbol "DisplayPort_Molex_472720001_1_1"
        (polyline
          (pts
            (xy 12.827 -2.54)
            (xy 15.367 -2.54)
          )
          (stroke (width 0.254) (type default))
          (fill (type background))
        )
        (polyline
          (pts
            (xy 14.097 -3.81)
            (xy 14.097 -10.16)
          )
          (stroke (width 0.254) (type default))
          (fill (type background))
        )
        (polyline
          (pts
            (xy 15.367 -8.89)
            (xy 14.097 -8.89)
          )
          (stroke (width 0.254) (type default))
          (fill (type background))
        )
        (polyline
          (pts
            (xy 15.367 -3.81)
            (xy 14.097 -3.81)
          )
          (stroke (width 0.254) (type default))
          (fill (type background))
        )
        (polyline
          (pts
            (xy 12.827 -2.54)
            (xy 12.827 -10.16)
            (xy 15.367 -10.16)
          )
          (stroke (width 0.254) (type default))
          (fill (type background))
        )
        (polyline
          (pts
            (xy 14.732 -26.035)
            (xy 15.367 -26.035)
            (xy 15.367 -17.78)
            (xy 14.732 -17.78)
          )
          (stroke (width 0.254) (type default))
          (fill (type background))
        )
        (polyline
          (pts
            (xy 13.462 -17.78)
            (xy 14.732 -16.51)
            (xy 16.637 -16.51)
            (xy 16.637 -26.67)
            (xy 13.462 -26.67)
            (xy 13.462 -17.78)
          )
          (stroke (width 0.254) (type default))
          (fill (type background))
        )
        (rectangle (start 2.667 2.54) (end 22.86 -45.72)
          (stroke (width 0.254) (type default))
          (fill (type background))
        )
        (arc (start 15.367 -10.16) (mid 18.061 -9.0441) (end 19.177 -6.35)
          (stroke (width 0.254) (type default))
          (fill (type background))
        )
        (arc (start 15.367 -8.89) (mid 17.1631 -8.1461) (end 17.907 -6.35)
          (stroke (width 0.254) (type default))
          (fill (type background))
        )
        (arc (start 17.907 -6.35) (mid 17.1631 -4.5539) (end 15.367 -3.81)
          (stroke (width 0.254) (type default))
          (fill (type background))
        )
        (arc (start 19.177 -6.35) (mid 18.0611 -3.656) (end 15.367 -2.54)
          (stroke (width 0.254) (type default))
          (fill (type background))
        )
        (pin bidirectional line (at 0 0 0) (length 2.54)
          (name "TXD0+" (effects (font (size 1.27 1.27))))
          (number "1" (effects (font (size 1.27 1.27))))
        )
        (pin bidirectional line (at 0 -22.86 0) (length 2.54)
          (name "TXD3+" (effects (font (size 1.27 1.27))))
          (number "10" (effects (font (size 1.27 1.27))))
        )
        (pin power_in line (at 25.4 -40.64 180) (length 2.54)
          (name "GND" (effects (font (size 1.27 1.27))))
          (number "11" (effects (font (size 1.27 1.27))))
        )
        (pin bidirectional line (at 0 -25.4 0) (length 2.54)
          (name "TXD3-" (effects (font (size 1.27 1.27))))
          (number "12" (effects (font (size 1.27 1.27))))
        )
        (pin passive line (at 25.4 -35.56 180) (length 2.54)
          (name "CFG1" (effects (font (size 1.27 1.27))))
          (number "13" (effects (font (size 1.27 1.27))))
        )
        (pin passive line (at 25.4 -33.02 180) (length 2.54)
          (name "CFG2" (effects (font (size 1.27 1.27))))
          (number "14" (effects (font (size 1.27 1.27))))
        )
        (pin bidirectional line (at 0 -30.48 0) (length 2.54)
          (name "AUX+" (effects (font (size 1.27 1.27))))
          (number "15" (effects (font (size 1.27 1.27))))
        )
        (pin passive line (at 25.4 -40.64 180) (length 2.54) hide
          (name "GND" (effects (font (size 1.27 1.27))))
          (number "16" (effects (font (size 1.27 1.27))))
        )
        (pin bidirectional line (at 0 -33.02 0) (length 2.54)
          (name "AUX-" (effects (font (size 1.27 1.27))))
          (number "17" (effects (font (size 1.27 1.27))))
        )
        (pin passive line (at 0 -38.1 0) (length 2.54)
          (name "HPD" (effects (font (size 1.27 1.27))))
          (number "18" (effects (font (size 1.27 1.27))))
        )
        (pin power_in line (at 25.4 -38.1 180) (length 2.54)
          (name "RTN" (effects (font (size 1.27 1.27))))
          (number "19" (effects (font (size 1.27 1.27))))
        )
        (pin passive line (at 25.4 -40.64 180) (length 2.54) hide
          (name "GND" (effects (font (size 1.27 1.27))))
          (number "2" (effects (font (size 1.27 1.27))))
        )
        (pin power_in line (at 0 -43.18 0) (length 2.54)
          (name "DP_PWR" (effects (font (size 1.27 1.27))))
          (number "20" (effects (font (size 1.27 1.27))))
        )
        (pin bidirectional line (at 0 -2.54 0) (length 2.54)
          (name "TXD0-" (effects (font (size 1.27 1.27))))
          (number "3" (effects (font (size 1.27 1.27))))
        )
        (pin bidirectional line (at 0 -7.62 0) (length 2.54)
          (name "TXD1+" (effects (font (size 1.27 1.27))))
          (number "4" (effects (font (size 1.27 1.27))))
        )
        (pin passive line (at 25.4 -40.64 180) (length 2.54) hide
          (name "GND" (effects (font (size 1.27 1.27))))
          (number "5" (effects (font (size 1.27 1.27))))
        )
        (pin bidirectional line (at 0 -10.16 0) (length 2.54)
          (name "TXD1-" (effects (font (size 1.27 1.27))))
          (number "6" (effects (font (size 1.27 1.27))))
        )
        (pin bidirectional line (at 0 -15.24 0) (length 2.54)
          (name "TXD2+" (effects (font (size 1.27 1.27))))
          (number "7" (effects (font (size 1.27 1.27))))
        )
        (pin passive line (at 25.4 -40.64 180) (length 2.54) hide
          (name "GND" (effects (font (size 1.27 1.27))))
          (number "8" (effects (font (size 1.27 1.27))))
        )
        (pin bidirectional line (at 0 -17.78 0) (length 2.54)
          (name "TXD2-" (effects (font (size 1.27 1.27))))
          (number "9" (effects (font (size 1.27 1.27))))
        )
        (pin passive line (at 25.4 -43.18 180) (length 2.54)
          (name "SH" (effects (font (size 1.27 1.27))))
          (number "SH" (effects (font (size 1.27 1.27))))
        )
      )
    )
	(symbol "kria-k26-devboard:FB_120Z_1.3A_Murata-BLM15PD_0402" (pin_numbers hide) (pin_names hide) (in_bom yes) (on_board yes)
      (property "Reference" "FB" (at 13.97 0 0)
        (effects (font (size 1.27 1.27) (thickness 0.15)) (justify left bottom))
      )
      (property "Value" "FB_120Z_1.3A_0402" (at 13.97 -2.54 0)
        (effects (font (size 1.27 1.27) (thickness 0.15)) (justify left bottom))
      )
      (property "Footprint" "kria-k26-devboard-footprints:FB_0402_1005Metric" (at 13.97 -5.08 0)
        (effects (font (size 1.27 1.27) (thickness 0.15)) (justify left bottom) hide)
      )
      (property "Datasheet" "https://www.murata.com/en-us/products/productdata/8796740059166/ENFA0018.pdf" (at 13.97 -7.62 0)
        (effects (font (size 1.27 1.27) (thickness 0.15)) (justify left bottom) hide)
      )
      (property "MPN" "BLM15PD121SN1D" (at 13.97 -10.16 0)
        (effects (font (size 1.27 1.27) (thickness 0.15)) (justify left bottom) hide)
      )
      (property "Manufacturer" "Murata" (at 13.97 -12.7 0)
        (effects (font (size 1.27 1.27) (thickness 0.15)) (justify left bottom) hide)
      )
      (property "Author" "Antmicro" (at 13.97 -15.24 0)
        (effects (font (size 1.27 1.27) (thickness 0.15)) (justify left bottom) hide)
      )
      (property "License" "Apache-2.0" (at 13.97 -17.78 0)
        (effects (font (size 1.27 1.27) (thickness 0.15)) (justify left bottom) hide)
      )
      (symbol "FB_120Z_1.3A_Murata-BLM15PD_0402_0_1"
        (polyline
          (pts
            (xy 1.651 0)
            (xy 1.2446 0)
          )
          (stroke (width 0) (type default))
          (fill (type none))
        )
        (polyline
          (pts
            (xy 3.81 0)
            (xy 3.3274 0)
          )
          (stroke (width 0) (type default))
          (fill (type none))
        )
        (polyline
          (pts
            (xy 2.2606 -1.8288)
            (xy 1.0414 -1.1176)
            (xy 2.7432 1.8288)
            (xy 3.9624 1.1176)
            (xy 2.2606 -1.8288)
          )
          (stroke (width 0) (type default))
          (fill (type none))
        )
      )
      (symbol "FB_120Z_1.3A_Murata-BLM15PD_0402_1_1"
        (pin passive line (at 0 0 0) (length 1.27)
          (name "~" (effects (font (size 1.27 1.27))))
          (number "1" (effects (font (size 1.27 1.27))))
        )
        (pin passive line (at 5.08 0 180) (length 1.27)
          (name "~" (effects (font (size 1.27 1.27))))
          (number "2" (effects (font (size 1.27 1.27))))
        )
      )
    )
	(symbol "kria-k26-devboard:FIN1019MTC" (in_bom yes) (on_board yes)
      (property "Reference" "U" (at 55.88 -10.16 0)
        (effects (font (size 1.27 1.27) (thickness 0.15)) (justify left bottom))
      )
      (property "Value" "FIN1019MTC" (at 55.88 -12.7 0)
        (effects (font (size 1.27 1.27) (thickness 0.15)) (justify left bottom))
      )
      (property "Footprint" "kria-k26-devboard-footprints:TSSOP-14_4.4x5mm_P0.65mm" (at 55.88 -15.24 0)
        (effects (font (size 1.27 1.27) (thickness 0.15)) (justify left bottom) hide)
      )
      (property "Datasheet" "http://www.onsemi.com/pub/Collateral/FIN1019-D.pdf" (at 55.88 -17.78 0)
        (effects (font (size 1.27 1.27) (thickness 0.15)) (justify left bottom) hide)
      )
      (property "Manufacturer" "ON Semiconductor" (at 55.88 -20.32 0)
        (effects (font (size 1.27 1.27) (thickness 0.15)) (justify left bottom) hide)
      )
      (property "MPN" "FIN1019MTCX" (at 55.88 -22.86 0)
        (effects (font (size 1.27 1.27) (thickness 0.15)) (justify left bottom) hide)
      )
      (property "Author" "Antmicro" (at 55.88 -25.4 0)
        (effects (font (size 1.27 1.27) (thickness 0.15)) (justify left bottom) hide)
      )
      (property "License" "Apache-2.0" (at 55.88 -27.94 0)
        (effects (font (size 1.27 1.27) (thickness 0.15)) (justify left bottom) hide)
      )
      (property "ki_keywords" "lvds driver reciever" (at 0 0 0)
        (effects (font (size 1.27 1.27)) hide)
      )
      (property "ki_description" "3.3V LVDS High Speed Differential Driver/Receiver, 400Mbps, TSSOP-14" (at 0 0 0)
        (effects (font (size 1.27 1.27)) hide)
      )
      (property "ki_fp_filters" "TSSOP*4.4x5mm*P0.65mm*" (at 0 0 0)
        (effects (font (size 1.27 1.27)) hide)
      )
      (symbol "FIN1019MTC_1_1"
        (polyline
          (pts
            (xy 7.62 -10.16)
            (xy 6.35 -10.16)
          )
          (stroke (width 0.254) (type default))
          (fill (type background))
        )
        (polyline
          (pts
            (xy 7.62 -3.81)
            (xy 5.715 -3.81)
          )
          (stroke (width 0.254) (type default))
          (fill (type background))
        )
        (polyline
          (pts
            (xy 10.16 -5.08)
            (xy 12.7 -5.08)
          )
          (stroke (width 0.254) (type default))
          (fill (type background))
        )
        (polyline
          (pts
            (xy 10.922 -2.54)
            (xy 12.7 -2.54)
          )
          (stroke (width 0.254) (type default))
          (fill (type background))
        )
        (polyline
          (pts
            (xy 12.7 -8.89)
            (xy 13.208 -8.89)
          )
          (stroke (width 0.254) (type default))
          (fill (type background))
        )
        (polyline
          (pts
            (xy 7.62 -1.27)
            (xy 12.7 -3.81)
            (xy 7.62 -6.35)
            (xy 7.62 -1.27)
          )
          (stroke (width 0.254) (type default))
          (fill (type background))
        )
        (polyline
          (pts
            (xy 12.7 -12.7)
            (xy 7.62 -10.16)
            (xy 12.7 -7.62)
            (xy 12.7 -12.7)
          )
          (stroke (width 0.254) (type default))
          (fill (type background))
        )
        (rectangle (start 2.54 2.54) (end 17.78 -19.05)
          (stroke (width 0.254) (type default))
          (fill (type background))
        )
        (circle (center 10.668 -2.54) (radius 0.254)
          (stroke (width 0.254) (type default))
          (fill (type background))
        )
        (circle (center 12.954 -11.43) (radius 0.254)
          (stroke (width 0.254) (type default))
          (fill (type background))
        )
        (text "D" (at 8.89 -3.81 0)
          (effects (font (size 1.27 1.27) (thickness 0.15)))
        )
        (text "R" (at 11.43 -10.16 0)
          (effects (font (size 1.27 1.27) (thickness 0.15)))
        )
        (pin input line (at 0 -6.35 0) (length 2.54)
          (name "DE" (effects (font (size 1.27 1.27))))
          (number "1" (effects (font (size 1.27 1.27))))
        )
        (pin input line (at 20.32 -8.89 180) (length 2.54)
          (name "RI+" (effects (font (size 1.27 1.27))))
          (number "10" (effects (font (size 1.27 1.27))))
        )
        (pin output line (at 20.32 -5.08 180) (length 2.54)
          (name "DO-" (effects (font (size 1.27 1.27))))
          (number "11" (effects (font (size 1.27 1.27))))
        )
        (pin output line (at 20.32 -2.54 180) (length 2.54)
          (name "DO+" (effects (font (size 1.27 1.27))))
          (number "12" (effects (font (size 1.27 1.27))))
        )
        (pin no_connect line (at 17.78 -15.875 180) (length 2.54) hide
          (name "NC" (effects (font (size 1.27 1.27))))
          (number "13" (effects (font (size 1.27 1.27))))
        )
        (pin power_in line (at 0 0 0) (length 2.54)
          (name "VCC" (effects (font (size 1.27 1.27))))
          (number "14" (effects (font (size 1.27 1.27))))
        )
        (pin input line (at 0 -3.81 0) (length 2.54)
          (name "DI" (effects (font (size 1.27 1.27))))
          (number "2" (effects (font (size 1.27 1.27))))
        )
        (pin no_connect line (at 17.78 -15.875 180) (length 2.54) hide
          (name "NC" (effects (font (size 1.27 1.27))))
          (number "3" (effects (font (size 1.27 1.27))))
        )
        (pin output line (at 0 -10.16 0) (length 2.54)
          (name "RO" (effects (font (size 1.27 1.27))))
          (number "4" (effects (font (size 1.27 1.27))))
        )
        (pin no_connect line (at 17.78 -15.875 180) (length 2.54) hide
          (name "NC" (effects (font (size 1.27 1.27))))
          (number "5" (effects (font (size 1.27 1.27))))
        )
        (pin no_connect line (at 17.78 -15.875 180) (length 2.54) hide
          (name "NC" (effects (font (size 1.27 1.27))))
          (number "6" (effects (font (size 1.27 1.27))))
        )
        (pin power_in line (at 0 -16.51 0) (length 2.54)
          (name "GND" (effects (font (size 1.27 1.27))))
          (number "7" (effects (font (size 1.27 1.27))))
        )
        (pin input line (at 0 -12.7 0) (length 2.54)
          (name "~{RE}" (effects (font (size 1.27 1.27))))
          (number "8" (effects (font (size 1.27 1.27))))
        )
        (pin input line (at 20.32 -11.43 180) (length 2.54)
          (name "RI-" (effects (font (size 1.27 1.27))))
          (number "9" (effects (font (size 1.27 1.27))))
        )
      )
    )
	(symbol "kria-k26-devboard:FT4232HP_QFN" (in_bom yes) (on_board yes)
      (property "Reference" "U" (at 55.88 -2.54 0)
        (effects (font (size 1.27 1.27) (thickness 0.15)) (justify left bottom))
      )
      (property "Value" "FT4232HP_QFN" (at 55.88 -5.08 0)
        (effects (font (size 1.27 1.27) (thickness 0.15)) (justify left bottom))
      )
      (property "Footprint" "kria-k26-devboard-footprints:QFN-68-1EP_8x8mm_P0.4mm" (at 55.88 -7.62 0)
        (effects (font (size 1.27 1.27) (thickness 0.15)) (justify left bottom) hide)
      )
      (property "Datasheet" "https://ftdichip.com/wp-content/uploads/2021/11/DS_FT4233HP.pdf" (at 55.88 -10.16 0)
        (effects (font (size 1.27 1.27) (thickness 0.15)) (justify left bottom) hide)
      )
      (property "Manufacturer" "FTDI Chip" (at 55.88 -12.7 0)
        (effects (font (size 1.27 1.27) (thickness 0.15)) (justify left bottom) hide)
      )
      (property "MPN" "FT4232HPQ-TRAY" (at 55.88 -15.24 0)
        (effects (font (size 1.27 1.27) (thickness 0.15)) (justify left bottom) hide)
      )
      (property "Author" "Antmicro" (at 55.88 -17.78 0)
        (effects (font (size 1.27 1.27) (thickness 0.15)) (justify left bottom) hide)
      )
      (property "License" "Apache-2.0" (at 55.88 -20.32 0)
        (effects (font (size 1.27 1.27) (thickness 0.15)) (justify left bottom) hide)
      )
      (property "ki_keywords" "SMT, INTERFACE, IC, CONTROLLER, USB, UART, I2C, SPI" (at 0 0 0)
        (effects (font (size 1.27 1.27)) hide)
      )
      (property "ki_description" "Interface Bridges, USB to UART, MPSSE, 1.62 V, 1.98 V, LQFP, 64 Pins, -40 °C" (at 0 0 0)
        (effects (font (size 1.27 1.27)) hide)
      )
      (symbol "FT4232HP_QFN_1_1"
        (rectangle (start 2.54 2.54) (end 38.1 -104.14)
          (stroke (width 0.254) (type default))
          (fill (type background))
        )
        (pin output line (at 0 -53.34 0) (length 2.54)
          (name "EECLK" (effects (font (size 1.27 1.27))))
          (number "1" (effects (font (size 1.27 1.27))))
        )
        (pin power_in line (at 0 -2.54 0) (length 2.54)
          (name "V_{CCIO}" (effects (font (size 1.27 1.27))))
          (number "10" (effects (font (size 1.27 1.27))))
        )
        (pin bidirectional line (at 40.64 -5.08 180) (length 2.54)
          (name "ADBUS2" (effects (font (size 1.27 1.27))))
          (number "11" (effects (font (size 1.27 1.27))))
        )
        (pin bidirectional line (at 40.64 -7.62 180) (length 2.54)
          (name "ADBUS3" (effects (font (size 1.27 1.27))))
          (number "12" (effects (font (size 1.27 1.27))))
        )
        (pin bidirectional line (at 40.64 -10.16 180) (length 2.54)
          (name "ADBUS4" (effects (font (size 1.27 1.27))))
          (number "13" (effects (font (size 1.27 1.27))))
        )
        (pin bidirectional line (at 40.64 -12.7 180) (length 2.54)
          (name "ADBUS5" (effects (font (size 1.27 1.27))))
          (number "14" (effects (font (size 1.27 1.27))))
        )
        (pin bidirectional line (at 40.64 -15.24 180) (length 2.54)
          (name "ADBUS6" (effects (font (size 1.27 1.27))))
          (number "15" (effects (font (size 1.27 1.27))))
        )
        (pin bidirectional line (at 40.64 -17.78 180) (length 2.54)
          (name "ADBUS7" (effects (font (size 1.27 1.27))))
          (number "16" (effects (font (size 1.27 1.27))))
        )
        (pin bidirectional line (at 40.64 -21.59 180) (length 2.54)
          (name "BDBUS0" (effects (font (size 1.27 1.27))))
          (number "17" (effects (font (size 1.27 1.27))))
        )
        (pin bidirectional line (at 40.64 -24.13 180) (length 2.54)
          (name "BDBUS1" (effects (font (size 1.27 1.27))))
          (number "18" (effects (font (size 1.27 1.27))))
        )
        (pin bidirectional line (at 40.64 -26.67 180) (length 2.54)
          (name "BDBUS2" (effects (font (size 1.27 1.27))))
          (number "19" (effects (font (size 1.27 1.27))))
        )
        (pin bidirectional line (at 0 -55.88 0) (length 2.54)
          (name "EEDATA" (effects (font (size 1.27 1.27))))
          (number "2" (effects (font (size 1.27 1.27))))
        )
        (pin bidirectional line (at 40.64 -29.21 180) (length 2.54)
          (name "BDBUS3" (effects (font (size 1.27 1.27))))
          (number "20" (effects (font (size 1.27 1.27))))
        )
        (pin bidirectional line (at 40.64 -31.75 180) (length 2.54)
          (name "BDBUS4" (effects (font (size 1.27 1.27))))
          (number "21" (effects (font (size 1.27 1.27))))
        )
        (pin bidirectional line (at 40.64 -34.29 180) (length 2.54)
          (name "BDBUS5" (effects (font (size 1.27 1.27))))
          (number "22" (effects (font (size 1.27 1.27))))
        )
        (pin bidirectional line (at 40.64 -36.83 180) (length 2.54)
          (name "BDBUS6" (effects (font (size 1.27 1.27))))
          (number "23" (effects (font (size 1.27 1.27))))
        )
        (pin bidirectional line (at 40.64 -39.37 180) (length 2.54)
          (name "BDBUS7" (effects (font (size 1.27 1.27))))
          (number "24" (effects (font (size 1.27 1.27))))
        )
        (pin power_in line (at 0 -15.24 0) (length 2.54)
          (name "V_{CORE}" (effects (font (size 1.27 1.27))))
          (number "25" (effects (font (size 1.27 1.27))))
        )
        (pin passive line (at 0 -2.54 0) (length 2.54) hide
          (name "V_{CCIO}" (effects (font (size 1.27 1.27))))
          (number "26" (effects (font (size 1.27 1.27))))
        )
        (pin input line (at 0 -62.23 0) (length 2.54)
          (name "OSCI" (effects (font (size 1.27 1.27))))
          (number "27" (effects (font (size 1.27 1.27))))
        )
        (pin output line (at 0 -67.31 0) (length 2.54)
          (name "OSCO" (effects (font (size 1.27 1.27))))
          (number "28" (effects (font (size 1.27 1.27))))
        )
        (pin power_in line (at 0 -101.6 0) (length 2.54)
          (name "GND" (effects (font (size 1.27 1.27))))
          (number "29" (effects (font (size 1.27 1.27))))
        )
        (pin input line (at 0 -96.52 0) (length 2.54)
          (name "TEST" (effects (font (size 1.27 1.27))))
          (number "3" (effects (font (size 1.27 1.27))))
        )
        (pin power_in line (at 0 0 0) (length 2.54)
          (name "V_{REGIN}" (effects (font (size 1.27 1.27))))
          (number "30" (effects (font (size 1.27 1.27))))
        )
        (pin power_out line (at 0 -11.43 0) (length 2.54)
          (name "V_{REGOUT}" (effects (font (size 1.27 1.27))))
          (number "31" (effects (font (size 1.27 1.27))))
        )
        (pin input line (at 0 -19.05 0) (length 2.54)
          (name "F_{SOURCE}" (effects (font (size 1.27 1.27))))
          (number "32" (effects (font (size 1.27 1.27))))
        )
        (pin power_in line (at 0 -21.59 0) (length 2.54)
          (name "V_{PP}" (effects (font (size 1.27 1.27))))
          (number "33" (effects (font (size 1.27 1.27))))
        )
        (pin bidirectional line (at 40.64 -43.18 180) (length 2.54)
          (name "CDBUS0" (effects (font (size 1.27 1.27))))
          (number "34" (effects (font (size 1.27 1.27))))
        )
        (pin bidirectional line (at 40.64 -45.72 180) (length 2.54)
          (name "CDBUS1" (effects (font (size 1.27 1.27))))
          (number "35" (effects (font (size 1.27 1.27))))
        )
        (pin bidirectional line (at 40.64 -48.26 180) (length 2.54)
          (name "CDBUS2" (effects (font (size 1.27 1.27))))
          (number "36" (effects (font (size 1.27 1.27))))
        )
        (pin bidirectional line (at 40.64 -50.8 180) (length 2.54)
          (name "CDBUS3" (effects (font (size 1.27 1.27))))
          (number "37" (effects (font (size 1.27 1.27))))
        )
        (pin bidirectional line (at 40.64 -53.34 180) (length 2.54)
          (name "CDBUS4" (effects (font (size 1.27 1.27))))
          (number "38" (effects (font (size 1.27 1.27))))
        )
        (pin passive line (at 0 -2.54 0) (length 2.54) hide
          (name "V_{CCIO}" (effects (font (size 1.27 1.27))))
          (number "39" (effects (font (size 1.27 1.27))))
        )
        (pin input line (at 0 -45.72 0) (length 2.54)
          (name "~{RESET}" (effects (font (size 1.27 1.27))))
          (number "4" (effects (font (size 1.27 1.27))))
        )
        (pin bidirectional line (at 40.64 -55.88 180) (length 2.54)
          (name "CDBUS5" (effects (font (size 1.27 1.27))))
          (number "40" (effects (font (size 1.27 1.27))))
        )
        (pin bidirectional line (at 40.64 -58.42 180) (length 2.54)
          (name "CDBUS6" (effects (font (size 1.27 1.27))))
          (number "41" (effects (font (size 1.27 1.27))))
        )
        (pin bidirectional line (at 40.64 -60.96 180) (length 2.54)
          (name "CDBUS7" (effects (font (size 1.27 1.27))))
          (number "42" (effects (font (size 1.27 1.27))))
        )
        (pin output line (at 40.64 -100.33 180) (length 2.54)
          (name "~{SUSPEND}" (effects (font (size 1.27 1.27))))
          (number "43" (effects (font (size 1.27 1.27))))
        )
        (pin passive line (at 0 -15.24 0) (length 2.54) hide
          (name "V_{CORE}" (effects (font (size 1.27 1.27))))
          (number "44" (effects (font (size 1.27 1.27))))
        )
        (pin bidirectional line (at 40.64 -64.77 180) (length 2.54)
          (name "DDBUS0" (effects (font (size 1.27 1.27))))
          (number "45" (effects (font (size 1.27 1.27))))
        )
        (pin bidirectional line (at 40.64 -67.31 180) (length 2.54)
          (name "DDBUS1" (effects (font (size 1.27 1.27))))
          (number "46" (effects (font (size 1.27 1.27))))
        )
        (pin bidirectional line (at 40.64 -69.85 180) (length 2.54)
          (name "DDBUS2" (effects (font (size 1.27 1.27))))
          (number "47" (effects (font (size 1.27 1.27))))
        )
        (pin bidirectional line (at 40.64 -72.39 180) (length 2.54)
          (name "DDBUS3" (effects (font (size 1.27 1.27))))
          (number "48" (effects (font (size 1.27 1.27))))
        )
        (pin bidirectional line (at 40.64 -74.93 180) (length 2.54)
          (name "DDBUS4" (effects (font (size 1.27 1.27))))
          (number "49" (effects (font (size 1.27 1.27))))
        )
        (pin bidirectional line (at 40.64 -93.98 180) (length 2.54)
          (name "GPIO3" (effects (font (size 1.27 1.27))))
          (number "5" (effects (font (size 1.27 1.27))))
        )
        (pin bidirectional line (at 40.64 -77.47 180) (length 2.54)
          (name "DDBUS5" (effects (font (size 1.27 1.27))))
          (number "50" (effects (font (size 1.27 1.27))))
        )
        (pin passive line (at 0 -2.54 0) (length 2.54) hide
          (name "V_{CCIO}" (effects (font (size 1.27 1.27))))
          (number "51" (effects (font (size 1.27 1.27))))
        )
        (pin bidirectional line (at 40.64 -82.55 180) (length 2.54)
          (name "DDBUS6" (effects (font (size 1.27 1.27))))
          (number "52" (effects (font (size 1.27 1.27))))
        )
        (pin bidirectional line (at 40.64 -80.01 180) (length 2.54)
          (name "DDBUS7" (effects (font (size 1.27 1.27))))
          (number "53" (effects (font (size 1.27 1.27))))
        )
        (pin bidirectional line (at 40.64 -91.44 180) (length 2.54)
          (name "GPIO2" (effects (font (size 1.27 1.27))))
          (number "54" (effects (font (size 1.27 1.27))))
        )
        (pin bidirectional line (at 40.64 -88.9 180) (length 2.54)
          (name "GPIO1" (effects (font (size 1.27 1.27))))
          (number "55" (effects (font (size 1.27 1.27))))
        )
        (pin bidirectional line (at 40.64 -86.36 180) (length 2.54)
          (name "GPIO0" (effects (font (size 1.27 1.27))))
          (number "56" (effects (font (size 1.27 1.27))))
        )
        (pin power_in line (at 0 -5.08 0) (length 2.54)
          (name "V_{CC_USB}" (effects (font (size 1.27 1.27))))
          (number "57" (effects (font (size 1.27 1.27))))
        )
        (pin bidirectional line (at 0 -27.94 0) (length 2.54)
          (name "D-" (effects (font (size 1.27 1.27))))
          (number "58" (effects (font (size 1.27 1.27))))
        )
        (pin bidirectional line (at 0 -25.4 0) (length 2.54)
          (name "D+" (effects (font (size 1.27 1.27))))
          (number "59" (effects (font (size 1.27 1.27))))
        )
        (pin bidirectional line (at 40.64 0 180) (length 2.54)
          (name "ADBUS0" (effects (font (size 1.27 1.27))))
          (number "6" (effects (font (size 1.27 1.27))))
        )
        (pin input line (at 0 -78.74 0) (length 2.54)
          (name "REF" (effects (font (size 1.27 1.27))))
          (number "60" (effects (font (size 1.27 1.27))))
        )
        (pin power_in line (at 0 -7.62 0) (length 2.54)
          (name "V_{CC_PD}" (effects (font (size 1.27 1.27))))
          (number "61" (effects (font (size 1.27 1.27))))
        )
        (pin bidirectional line (at 0 -40.64 0) (length 2.54)
          (name "PD1_{CC2}" (effects (font (size 1.27 1.27))))
          (number "62" (effects (font (size 1.27 1.27))))
        )
        (pin input line (at 0 -33.02 0) (length 2.54)
          (name "PD1_{SVBUS}" (effects (font (size 1.27 1.27))))
          (number "63" (effects (font (size 1.27 1.27))))
        )
        (pin power_in line (at 0 -35.56 0) (length 2.54)
          (name "PD1_{VCONN}" (effects (font (size 1.27 1.27))))
          (number "64" (effects (font (size 1.27 1.27))))
        )
        (pin bidirectional line (at 0 -38.1 0) (length 2.54)
          (name "PD1_{CC1}" (effects (font (size 1.27 1.27))))
          (number "65" (effects (font (size 1.27 1.27))))
        )
        (pin passive line (at 0 -15.24 0) (length 2.54) hide
          (name "V_{CORE}" (effects (font (size 1.27 1.27))))
          (number "66" (effects (font (size 1.27 1.27))))
        )
        (pin output line (at 40.64 -97.79 180) (length 2.54)
          (name "~{PWREN}" (effects (font (size 1.27 1.27))))
          (number "67" (effects (font (size 1.27 1.27))))
        )
        (pin bidirectional line (at 0 -50.8 0) (length 2.54)
          (name "EECS" (effects (font (size 1.27 1.27))))
          (number "68" (effects (font (size 1.27 1.27))))
        )
        (pin bidirectional line (at 40.64 -2.54 180) (length 2.54)
          (name "ADBUS1" (effects (font (size 1.27 1.27))))
          (number "7" (effects (font (size 1.27 1.27))))
        )
        (pin passive line (at 0 -15.24 0) (length 2.54) hide
          (name "V_{CORE}" (effects (font (size 1.27 1.27))))
          (number "8" (effects (font (size 1.27 1.27))))
        )
        (pin passive line (at 0 -101.6 0) (length 2.54) hide
          (name "GND" (effects (font (size 1.27 1.27))))
          (number "9" (effects (font (size 1.27 1.27))))
        )
        (pin passive line (at 0 -99.06 0) (length 2.54)
          (name "EP" (effects (font (size 1.27 1.27))))
          (number "EP" (effects (font (size 1.27 1.27))))
        )
      )
    )
	(symbol "kria-k26-devboard:GND" (power) (pin_numbers hide) (pin_names hide) (in_bom yes) (on_board yes)
      (property "Reference" "#PWR" (at 8.89 -2.54 0)
        (effects (font (size 1.27 1.27) (thickness 0.15)) (justify left bottom))
      )
      (property "Value" "GND" (at 8.89 -5.08 0)
        (effects (font (size 1.27 1.27) (thickness 0.15)) (justify left bottom) hide)
      )
      (property "Footprint" "" (at 8.89 -7.62 0)
        (effects (font (size 1.27 1.27) (thickness 0.15)) (justify left bottom) hide)
      )
      (property "Datasheet" "" (at 8.89 -12.7 0)
        (effects (font (size 1.27 1.27) (thickness 0.15)) (justify left bottom) hide)
      )
      (property "Author" "Antmicro" (at 8.89 -7.62 0)
        (effects (font (size 1.27 1.27) (thickness 0.15)) (justify left bottom) hide)
      )
      (property "License" "Apache-2.0" (at 8.89 -10.16 0)
        (effects (font (size 1.27 1.27) (thickness 0.15)) (justify left bottom) hide)
      )
      (symbol "GND_1_1"
        (polyline
          (pts
            (xy 0 0)
            (xy 0 -1.27)
            (xy 1.27 -1.27)
            (xy 0 -2.54)
            (xy -1.27 -1.27)
            (xy 0 -1.27)
          )
          (stroke (width 0.254) (type default))
          (fill (type none))
        )
        (pin power_in line (at 0 0 270) (length 0)
          (name "GND" (effects (font (size 1.27 1.27))))
          (number "1" (effects (font (size 1.27 1.27))))
        )
      )
    )
	(symbol "kria-k26-devboard:GNDD" (power) (pin_numbers hide) (pin_names hide) (in_bom yes) (on_board yes)
      (property "Reference" "#PWR" (at 15.24 -2.54 0)
        (effects (font (size 1.27 1.27) (thickness 0.15)) (justify left bottom))
      )
      (property "Value" "GNDD" (at 15.24 -5.08 0)
        (effects (font (size 1.27 1.27) (thickness 0.15)) (justify left bottom) hide)
      )
      (property "Footprint" "" (at 15.24 -10.16 0)
        (effects (font (size 1.27 1.27) (thickness 0.15)) (justify left bottom) hide)
      )
      (property "Datasheet" "" (at 15.24 -12.7 0)
        (effects (font (size 1.27 1.27) (thickness 0.15)) (justify left bottom) hide)
      )
      (property "Author" "Antmicro" (at 15.24 -7.62 0)
        (effects (font (size 1.27 1.27) (thickness 0.15)) (justify left bottom) hide)
      )
      (property "License" "Apache-2.0" (at 15.24 -10.16 0)
        (effects (font (size 1.27 1.27) (thickness 0.15)) (justify left bottom) hide)
      )
      (symbol "GNDD_1_1"
        (rectangle (start -1.27 -1.524) (end 1.27 -2.032)
          (stroke (width 0.254) (type default))
          (fill (type outline))
        )
        (polyline
          (pts
            (xy 0 0)
            (xy 0 -1.524)
          )
          (stroke (width 0.254) (type default))
          (fill (type background))
        )
        (pin power_in line (at 0 0 270) (length 0)
          (name "GNDD" (effects (font (size 1.27 1.27))))
          (number "1" (effects (font (size 1.27 1.27))))
        )
      )
    )
	(symbol "kria-k26-devboard:JST_SH_1x8_BM08B-SRSS-TB-LF-SN" (pin_names hide) (in_bom yes) (on_board yes)
      (property "Reference" "J" (at 13.97 0 0)
        (effects (font (size 1.27 1.27) (thickness 0.15)) (justify left bottom))
      )
      (property "Value" "JST_SH_1x8_BM08B-SRSS-TB-LF-SN" (at 13.97 -2.54 0)
        (effects (font (size 1.27 1.27) (thickness 0.15)) (justify left bottom) hide)
      )
      (property "Footprint" "kria-k26-devboard-footprints:Conn_JST_SH_1x8_BM08B-SRSS-TB-LF-SN" (at 13.97 -5.08 0)
        (effects (font (size 1.27 1.27) (thickness 0.15)) (justify left bottom) hide)
      )
      (property "Datasheet" "https://www.jst-mfg.com/product/pdf/eng/eSH.pdf?651faad4db779" (at 13.97 -7.62 0)
        (effects (font (size 1.27 1.27) (thickness 0.15)) (justify left bottom) hide)
      )
      (property "MPN" "BM08B-SRSS-TB(LF)(SN)" (at 13.97 -10.16 0)
        (effects (font (size 1.27 1.27) (thickness 0.15)) (justify left bottom))
      )
      (property "Manufacturer" "JST Automotive Connectors" (at 13.97 -12.7 0)
        (effects (font (size 1.27 1.27) (thickness 0.15)) (justify left bottom) hide)
      )
      (property "Author" "Antmicro" (at 13.97 -15.24 0)
        (effects (font (size 1.27 1.27) (thickness 0.15)) (justify left bottom) hide)
      )
      (property "License" "Apache-2.0" (at 13.97 -17.78 0)
        (effects (font (size 1.27 1.27) (thickness 0.15)) (justify left bottom) hide)
      )
      (property "ki_keywords" "VERTICAL, SMT, WIRE-BOARD, CONNECTOR" (at 0 0 0)
        (effects (font (size 1.27 1.27)) hide)
      )
      (property "ki_description" "Pin Header, Wire-to-Board, 1 mm, 1 Rows, 8 Contacts, Surface Mount, SR" (at 0 0 0)
        (effects (font (size 1.27 1.27)) hide)
      )
      (symbol "JST_SH_1x8_BM08B-SRSS-TB-LF-SN_1_1"
        (rectangle (start 2.54 -20.193) (end 3.81 -20.447)
          (stroke (width 0.254) (type default))
          (fill (type background))
        )
        (rectangle (start 2.54 -17.653) (end 3.81 -17.907)
          (stroke (width 0.254) (type default))
          (fill (type background))
        )
        (rectangle (start 2.54 -15.113) (end 3.81 -15.367)
          (stroke (width 0.254) (type default))
          (fill (type background))
        )
        (rectangle (start 2.54 -12.573) (end 3.81 -12.827)
          (stroke (width 0.254) (type default))
          (fill (type background))
        )
        (rectangle (start 2.54 -10.033) (end 3.81 -10.287)
          (stroke (width 0.254) (type default))
          (fill (type background))
        )
        (rectangle (start 2.54 -7.493) (end 3.81 -7.747)
          (stroke (width 0.254) (type default))
          (fill (type background))
        )
        (rectangle (start 2.54 -4.953) (end 3.81 -5.207)
          (stroke (width 0.254) (type default))
          (fill (type background))
        )
        (rectangle (start 2.54 -2.413) (end 3.81 -2.667)
          (stroke (width 0.254) (type default))
          (fill (type background))
        )
        (rectangle (start 2.54 0.127) (end 3.81 -0.127)
          (stroke (width 0.254) (type default))
          (fill (type background))
        )
        (rectangle (start 2.54 1.27) (end 5.08 -21.59)
          (stroke (width 0.254) (type default))
          (fill (type background))
        )
        (pin passive line (at 0 0 0) (length 2.54)
          (name "Pin_1" (effects (font (size 1.27 1.27))))
          (number "1" (effects (font (size 1.27 1.27))))
        )
        (pin passive line (at 0 -2.54 0) (length 2.54)
          (name "Pin_2" (effects (font (size 1.27 1.27))))
          (number "2" (effects (font (size 1.27 1.27))))
        )
        (pin passive line (at 0 -5.08 0) (length 2.54)
          (name "Pin_3" (effects (font (size 1.27 1.27))))
          (number "3" (effects (font (size 1.27 1.27))))
        )
        (pin passive line (at 0 -7.62 0) (length 2.54)
          (name "Pin_4" (effects (font (size 1.27 1.27))))
          (number "4" (effects (font (size 1.27 1.27))))
        )
        (pin passive line (at 0 -10.16 0) (length 2.54)
          (name "Pin_5" (effects (font (size 1.27 1.27))))
          (number "5" (effects (font (size 1.27 1.27))))
        )
        (pin passive line (at 0 -12.7 0) (length 2.54)
          (name "Pin_6" (effects (font (size 1.27 1.27))))
          (number "6" (effects (font (size 1.27 1.27))))
        )
        (pin passive line (at 0 -15.24 0) (length 2.54)
          (name "Pin_7" (effects (font (size 1.27 1.27))))
          (number "7" (effects (font (size 1.27 1.27))))
        )
        (pin passive line (at 0 -17.78 0) (length 2.54)
          (name "Pin_8" (effects (font (size 1.27 1.27))))
          (number "8" (effects (font (size 1.27 1.27))))
        )
        (pin passive line (at 0 -20.32 0) (length 2.54)
          (name "MP" (effects (font (size 1.27 1.27))))
          (number "MP" (effects (font (size 1.27 1.27))))
        )
      )
    )
	(symbol "kria-k26-devboard:Kria-K26" (in_bom yes) (on_board yes)
      (property "Reference" "A" (at 25.4 0 0)
        (effects (font (size 1.27 1.27) (thickness 0.15)) (justify left bottom))
      )
      (property "Value" "XILINX-KRIA-K26" (at 25.4 -2.54 0)
        (effects (font (size 1.27 1.27) (thickness 0.15)) (justify left bottom))
      )
      (property "Footprint" "kria-k26-devboard-footprints:XILINX-KRIA-K26" (at 25.4 -5.08 0)
        (effects (font (size 1.27 1.27) (thickness 0.15)) (justify left bottom) hide)
      )
      (property "Datasheet" "" (at 25.4 -7.62 0)
        (effects (font (size 1.27 1.27) (thickness 0.15)) (justify left bottom) hide)
      )
      (property "Manufacturer" "Xilinx" (at 25.4 -10.16 0)
        (effects (font (size 1.27 1.27) (thickness 0.15)) (justify left bottom) hide)
      )
      (property "MPN" "SM-K26-XCL2GC" (at 25.4 -12.7 0)
        (effects (font (size 1.27 1.27) (thickness 0.15)) (justify left bottom) hide)
      )
      (property "Description" "System-On-Modules - SOM K26C SOM" (at 25.4 -15.24 0)
        (effects (font (size 1.27 1.27) (thickness 0.15)) (justify left bottom) hide)
      )
      (property "Author" "Antmicro" (at 25.4 -17.78 0)
        (effects (font (size 1.27 1.27) (thickness 0.15)) (justify left bottom) hide)
      )
      (property "License" "Apache-2.0" (at 25.4 -20.32 0)
        (effects (font (size 1.27 1.27) (thickness 0.15)) (justify left bottom) hide)
      )
      (symbol "Kria-K26_1_1"
        (rectangle (start 10.16 -6.35) (end 0 0)
          (stroke (width 0.254) (type default))
          (fill (type background))
        )
      )
    )
	(symbol "kria-k26-devboard:LED_G_0603_LG_L29K-G2J1-24-Z" (pin_numbers hide) (pin_names hide) (in_bom yes) (on_board yes)
      (property "Reference" "D" (at 20.32 -2.54 0)
        (effects (font (size 1.27 1.27) (thickness 0.15)) (justify left bottom))
      )
      (property "Value" "LED_G_0603_LG_L29K-G2J1-24-Z" (at 20.32 -7.62 0)
        (effects (font (size 1.27 1.27) (thickness 0.15)) (justify left bottom) hide)
      )
      (property "Footprint" "kria-k26-devboard-footprints:LED_0603_1608Metric_G" (at 20.32 -10.16 0)
        (effects (font (size 1.27 1.27) (thickness 0.15)) (justify left bottom) hide)
      )
      (property "Datasheet" "https://dammedia.osram.info/media/resource/hires/osram-dam-2493945/LG%20L29K.pdf" (at 20.32 -12.7 0)
        (effects (font (size 1.27 1.27) (thickness 0.15)) (justify left bottom) hide)
      )
      (property "MPN" "LG L29K-G2J1-24-Z" (at 20.32 -15.24 0)
        (effects (font (size 1.27 1.27) (thickness 0.15)) (justify left bottom) hide)
      )
      (property "Manufacturer" "OSRAM" (at 20.32 -17.78 0)
        (effects (font (size 1.27 1.27) (thickness 0.15)) (justify left bottom) hide)
      )
      (property "Color" "Green" (at 20.32 -5.08 0)
        (effects (font (size 1.27 1.27)) (justify left bottom))
      )
      (property "Author" "Antmicro" (at 20.32 -20.32 0)
        (effects (font (size 1.27 1.27) (thickness 0.15)) (justify left bottom) hide)
      )
      (property "License" "Apache-2.0" (at 20.32 -22.86 0)
        (effects (font (size 1.27 1.27) (thickness 0.15)) (justify left bottom) hide)
      )
      (property "ki_keywords" "0603, SMT, DIODE, SEMICONDUCTOR, UNICOLOR" (at 0 0 0)
        (effects (font (size 1.27 1.27)) hide)
      )
      (property "ki_description" "LED, Green, SMT, 0603, 20 mA, 2.1 V, 570 nm" (at 0 0 0)
        (effects (font (size 1.27 1.27)) hide)
      )
      (symbol "LED_G_0603_LG_L29K-G2J1-24-Z_1_1"
        (polyline
          (pts
            (xy 5.08 1.27)
            (xy 5.08 -1.27)
          )
          (stroke (width 0.254) (type default))
          (fill (type none))
        )
        (polyline
          (pts
            (xy 2.54 1.27)
            (xy 2.54 -1.27)
            (xy 5.08 0)
            (xy 2.54 1.27)
          )
          (stroke (width 0.254) (type default))
          (fill (type outline))
        )
        (polyline
          (pts
            (xy 3.683 2.286)
            (xy 3.683 1.778)
            (xy 3.683 2.286)
            (xy 3.175 2.286)
            (xy 3.683 2.286)
            (xy 2.794 1.397)
          )
          (stroke (width 0.254) (type default))
          (fill (type none))
        )
        (polyline
          (pts
            (xy 4.699 2.032)
            (xy 4.699 1.524)
            (xy 4.699 2.032)
            (xy 4.191 2.032)
            (xy 4.699 2.032)
            (xy 3.683 1.016)
          )
          (stroke (width 0.254) (type default))
          (fill (type none))
        )
        (pin passive line (at 0 0 0) (length 2.54)
          (name "~" (effects (font (size 1.27 1.27))))
          (number "1" (effects (font (size 1.27 1.27))))
        )
        (pin passive line (at 7.62 0 180) (length 2.54)
          (name "2" (effects (font (size 1.27 1.27))))
          (number "2" (effects (font (size 1.27 1.27))))
        )
      )
    )
	(symbol "kria-k26-devboard:LTC4358CDE" (in_bom yes) (on_board yes)
      (property "Reference" "U" (at 35.56 -2.54 0)
        (effects (font (size 1.27 1.27) (thickness 0.15)) (justify left bottom))
      )
      (property "Value" "LTC4358CDE" (at 35.56 -5.08 0)
        (effects (font (size 1.27 1.27) (thickness 0.15)) (justify left bottom))
      )
      (property "Footprint" "kria-k26-devboard-footprints:DFN-14-1EP_4x3mm_P0.5mm" (at 35.56 -7.62 0)
        (effects (font (size 1.27 1.27) (thickness 0.15)) (justify left bottom) hide)
      )
      (property "Datasheet" "https://www.mouser.com/datasheet/2/609/4358fa-1270155.pdf" (at 35.56 -10.16 0)
        (effects (font (size 1.27 1.27) (thickness 0.15)) (justify left bottom) hide)
      )
      (property "Manufacturer" "Analog Devices" (at 35.56 -12.7 0)
        (effects (font (size 1.27 1.27) (thickness 0.15)) (justify left bottom) hide)
      )
      (property "MPN" "LTC4358CDE#PBF" (at 35.56 -15.24 0)
        (effects (font (size 1.27 1.27) (thickness 0.15)) (justify left bottom) hide)
      )
      (property "Author" "Antmicro" (at 35.56 -17.78 0)
        (effects (font (size 1.27 1.27) (thickness 0.15)) (justify left bottom) hide)
      )
      (property "License" "Apache-2.0" (at 35.56 -20.32 0)
        (effects (font (size 1.27 1.27) (thickness 0.15)) (justify left bottom) hide)
      )
      (property "ki_keywords" "SMT, PMIC, IC, POWER, MANAGEMENT, DIODE, CONTROLLER" (at 0 0 0)
        (effects (font (size 1.27 1.27)) hide)
      )
      (property "ki_description" "Ideal diode" (at 0 0 0)
        (effects (font (size 1.27 1.27)) hide)
      )
      (property "ki_fp_filters" "DFN-14_DE_LIT DFN-14_DE_LIT-M DFN-14_DE_LIT-L" (at 0 0 0)
        (effects (font (size 1.27 1.27)) hide)
      )
      (symbol "LTC4358CDE_0_1"
        (polyline
          (pts
            (xy 8.255 -2.54)
            (xy 10.16 -2.54)
          )
          (stroke (width 0.254) (type default))
          (fill (type none))
        )
        (polyline
          (pts
            (xy 12.7 -2.54)
            (xy 14.605 -2.54)
          )
          (stroke (width 0.254) (type default))
          (fill (type none))
        )
      )
      (symbol "LTC4358CDE_1_1"
        (polyline
          (pts
            (xy 12.7 -1.27)
            (xy 12.7 -3.81)
          )
          (stroke (width 0.254) (type default))
          (fill (type none))
        )
        (polyline
          (pts
            (xy 10.16 -1.27)
            (xy 10.16 -3.81)
            (xy 12.7 -2.54)
            (xy 10.16 -1.27)
          )
          (stroke (width 0.254) (type default))
          (fill (type outline))
        )
        (rectangle (start 2.54 2.54) (end 19.05 -10.16)
          (stroke (width 0.254) (type default))
          (fill (type background))
        )
        (pin input line (at 0 0 0) (length 2.54)
          (name "IN" (effects (font (size 1.27 1.27))))
          (number "1" (effects (font (size 1.27 1.27))))
        )
        (pin no_connect line (at 19.05 -7.62 180) (length 2.54) hide
          (name "NC" (effects (font (size 1.27 1.27))))
          (number "10" (effects (font (size 1.27 1.27))))
        )
        (pin passive line (at 0 0 0) (length 2.54) hide
          (name "IN" (effects (font (size 1.27 1.27))))
          (number "11" (effects (font (size 1.27 1.27))))
        )
        (pin passive line (at 0 0 0) (length 2.54) hide
          (name "IN" (effects (font (size 1.27 1.27))))
          (number "12" (effects (font (size 1.27 1.27))))
        )
        (pin passive line (at 0 0 0) (length 2.54) hide
          (name "IN" (effects (font (size 1.27 1.27))))
          (number "13" (effects (font (size 1.27 1.27))))
        )
        (pin passive line (at 0 0 0) (length 2.54) hide
          (name "IN" (effects (font (size 1.27 1.27))))
          (number "14" (effects (font (size 1.27 1.27))))
        )
        (pin passive line (at 21.59 0 180) (length 2.54)
          (name "DRAIN" (effects (font (size 1.27 1.27))))
          (number "15" (effects (font (size 1.27 1.27))))
        )
        (pin passive line (at 0 0 0) (length 2.54) hide
          (name "IN" (effects (font (size 1.27 1.27))))
          (number "2" (effects (font (size 1.27 1.27))))
        )
        (pin passive line (at 0 0 0) (length 2.54) hide
          (name "IN" (effects (font (size 1.27 1.27))))
          (number "3" (effects (font (size 1.27 1.27))))
        )
        (pin passive line (at 0 0 0) (length 2.54) hide
          (name "IN" (effects (font (size 1.27 1.27))))
          (number "4" (effects (font (size 1.27 1.27))))
        )
        (pin output line (at 0 -2.54 0) (length 2.54)
          (name "GATE" (effects (font (size 1.27 1.27))))
          (number "5" (effects (font (size 1.27 1.27))))
        )
        (pin no_connect line (at 2.54 -5.08 0) (length 2.54) hide
          (name "NC" (effects (font (size 1.27 1.27))))
          (number "6" (effects (font (size 1.27 1.27))))
        )
        (pin power_in line (at 0 -7.62 0) (length 2.54)
          (name "GND" (effects (font (size 1.27 1.27))))
          (number "7" (effects (font (size 1.27 1.27))))
        )
        (pin passive line (at 21.59 -5.08 180) (length 2.54)
          (name "VDD" (effects (font (size 1.27 1.27))))
          (number "8" (effects (font (size 1.27 1.27))))
        )
        (pin passive line (at 21.59 -2.54 180) (length 2.54)
          (name "OUT" (effects (font (size 1.27 1.27))))
          (number "9" (effects (font (size 1.27 1.27))))
        )
      )
    )
	(symbol "kria-k26-devboard:L_1u_2.5A_0805" (pin_numbers hide) (pin_names hide) (in_bom yes) (on_board yes)
      (property "Reference" "L" (at 13.97 0 0)
        (effects (font (size 1.27 1.27) (thickness 0.15)) (justify left bottom))
      )
      (property "Value" "L_1u_2.5A_0805" (at 13.97 -2.54 0)
        (effects (font (size 1.27 1.27) (thickness 0.15)) (justify left bottom) hide)
      )
      (property "Footprint" "kria-k26-devboard-footprints:L_0805_2012Metric" (at 13.97 -7.62 0)
        (effects (font (size 1.27 1.27) (thickness 0.15)) (justify left bottom) hide)
      )
      (property "Datasheet" "https://product.tdk.com/system/files/dam/doc/product/inductor/inductor/smd/catalog/inductor_commercial_power_tfm201208ald_en.pdf" (at 13.97 -10.16 0)
        (effects (font (size 1.27 1.27) (thickness 0.15)) (justify left bottom) hide)
      )
      (property "Val" "1u/2.5A" (at 13.97 -5.08 0)
        (effects (font (size 1.27 1.27) (thickness 0.15)) (justify left bottom))
      )
      (property "Manufacturer" "TDK" (at 13.97 -12.7 0)
        (effects (font (size 1.27 1.27) (thickness 0.15)) (justify left bottom) hide)
      )
      (property "MPN" "TFM201208ALD-1R0MTCA" (at 13.97 -15.24 0)
        (effects (font (size 1.27 1.27) (thickness 0.15)) (justify left bottom) hide)
      )
      (property "ISat" "" (at 13.97 -16.51 0)
        (effects (font (size 1.27 1.27)) (justify left) hide)
      )
      (property "IMax" "" (at 13.97 -20.32 0)
        (effects (font (size 1.27 1.27) (thickness 0.15)) (justify left bottom) hide)
      )
      (property "Size" "1.25x0.8" (at 13.97 -22.86 0)
        (effects (font (size 1.27 1.27) (thickness 0.15)) (justify left bottom) hide)
      )
      (property "Author" "Antmicro" (at 13.97 -25.4 0)
        (effects (font (size 1.27 1.27) (thickness 0.15)) (justify left bottom) hide)
      )
      (property "License" "Apache-2.0" (at 13.97 -27.94 0)
        (effects (font (size 1.27 1.27) (thickness 0.15)) (justify left bottom) hide)
      )
      (symbol "L_1u_2.5A_0805_0_1"
        (arc (start 1.524 0) (mid 1.016 0.5058) (end 0.508 0)
          (stroke (width 0) (type default))
          (fill (type none))
        )
        (arc (start 2.54 0) (mid 2.032 0.5058) (end 1.524 0)
          (stroke (width 0) (type default))
          (fill (type none))
        )
        (arc (start 3.556 0) (mid 3.048 0.5058) (end 2.54 0)
          (stroke (width 0) (type default))
          (fill (type none))
        )
        (arc (start 4.572 0) (mid 4.064 0.5058) (end 3.556 0)
          (stroke (width 0) (type default))
          (fill (type none))
        )
      )
      (symbol "L_1u_2.5A_0805_1_1"
        (pin passive line (at 0 0 0) (length 0.508)
          (name "~" (effects (font (size 1.27 1.27))))
          (number "1" (effects (font (size 1.27 1.27))))
        )
        (pin passive line (at 5.08 0 180) (length 0.508)
          (name "~" (effects (font (size 1.27 1.27))))
          (number "2" (effects (font (size 1.27 1.27))))
        )
      )
    )
	(symbol "kria-k26-devboard:L_1u_2.6A_0806" (pin_numbers hide) (pin_names hide) (in_bom yes) (on_board yes)
      (property "Reference" "L" (at 13.97 0 0)
        (effects (font (size 1.27 1.27) (thickness 0.15)) (justify left bottom))
      )
      (property "Value" "L_1u_2.6A_0806" (at 13.97 -2.54 0)
        (effects (font (size 1.27 1.27) (thickness 0.15)) (justify left bottom) hide)
      )
      (property "Footprint" "kria-k26-devboard-footprints:L_0806_2016Metric" (at 13.97 -7.62 0)
        (effects (font (size 1.27 1.27) (thickness 0.15)) (justify left bottom) hide)
      )
      (property "Datasheet" "https://www.bourns.com/docs/Product-Datasheets/SRP2010.pdf" (at 13.97 -10.16 0)
        (effects (font (size 1.27 1.27) (thickness 0.15)) (justify left bottom) hide)
      )
      (property "Val" "1u/2.6A" (at 13.97 -5.08 0)
        (effects (font (size 1.27 1.27) (thickness 0.15)) (justify left bottom))
      )
      (property "Manufacturer" "Bourns" (at 13.97 -12.7 0)
        (effects (font (size 1.27 1.27) (thickness 0.15)) (justify left bottom) hide)
      )
      (property "MPN" "SRP2010-1R0M" (at 13.97 -15.24 0)
        (effects (font (size 1.27 1.27) (thickness 0.15)) (justify left bottom) hide)
      )
      (property "ISat" "" (at 13.97 -16.51 0)
        (effects (font (size 1.27 1.27)) (justify left) hide)
      )
      (property "IMax" "" (at 13.97 -20.32 0)
        (effects (font (size 1.27 1.27) (thickness 0.15)) (justify left bottom) hide)
      )
      (property "Size" "2.0x1.6" (at 13.97 -22.86 0)
        (effects (font (size 1.27 1.27) (thickness 0.15)) (justify left bottom) hide)
      )
      (property "Author" "Antmicro" (at 13.97 -25.4 0)
        (effects (font (size 1.27 1.27) (thickness 0.15)) (justify left bottom) hide)
      )
      (property "License" "Apache-2.0" (at 13.97 -27.94 0)
        (effects (font (size 1.27 1.27) (thickness 0.15)) (justify left bottom) hide)
      )
      (symbol "L_1u_2.6A_0806_0_1"
        (arc (start 1.524 0) (mid 1.016 0.5058) (end 0.508 0)
          (stroke (width 0) (type default))
          (fill (type none))
        )
        (arc (start 2.54 0) (mid 2.032 0.5058) (end 1.524 0)
          (stroke (width 0) (type default))
          (fill (type none))
        )
        (arc (start 3.556 0) (mid 3.048 0.5058) (end 2.54 0)
          (stroke (width 0) (type default))
          (fill (type none))
        )
        (arc (start 4.572 0) (mid 4.064 0.5058) (end 3.556 0)
          (stroke (width 0) (type default))
          (fill (type none))
        )
      )
      (symbol "L_1u_2.6A_0806_1_1"
        (pin passive line (at 0 0 0) (length 0.508)
          (name "~" (effects (font (size 1.27 1.27))))
          (number "1" (effects (font (size 1.27 1.27))))
        )
        (pin passive line (at 5.08 0 180) (length 0.508)
          (name "~" (effects (font (size 1.27 1.27))))
          (number "2" (effects (font (size 1.27 1.27))))
        )
      )
    )
	(symbol "kria-k26-devboard:L_2u2_7.8A_Coilcraft-XEL4030" (pin_numbers hide) (pin_names hide) (in_bom yes) (on_board yes)
      (property "Reference" "L" (at 13.97 0 0)
        (effects (font (size 1.27 1.27) (thickness 0.15)) (justify left bottom))
      )
      (property "Value" "L_2u2_6.1A_XEL4030" (at 13.97 -2.54 0)
        (effects (font (size 1.27 1.27) (thickness 0.15)) (justify left bottom) hide)
      )
      (property "Footprint" "kria-k26-devboard-footprints:L_Coilcraft-XEL4030" (at 13.97 -7.62 0)
        (effects (font (size 1.27 1.27) (thickness 0.15)) (justify left bottom) hide)
      )
      (property "Datasheet" "https://www.coilcraft.com/getmedia/8245f050-f190-4295-8c41-7c03d662ee3d/xel4030.pdf" (at 13.97 -10.16 0)
        (effects (font (size 1.27 1.27) (thickness 0.15)) (justify left bottom) hide)
      )
      (property "Val" "2u2/6.1A" (at 13.97 -5.08 0)
        (effects (font (size 1.27 1.27) (thickness 0.15)) (justify left bottom))
      )
      (property "Manufacturer" "Coilcraft" (at 13.97 -12.7 0)
        (effects (font (size 1.27 1.27) (thickness 0.15)) (justify left bottom) hide)
      )
      (property "MPN" "XEL4030-222MEC" (at 13.97 -15.24 0)
        (effects (font (size 1.27 1.27) (thickness 0.15)) (justify left bottom) hide)
      )
      (property "ISat" "" (at 13.97 -16.51 0)
        (effects (font (size 1.27 1.27)) (justify left) hide)
      )
      (property "IMax" "" (at 13.97 -20.32 0)
        (effects (font (size 1.27 1.27) (thickness 0.15)) (justify left bottom) hide)
      )
      (property "Size" "4x4" (at 13.97 -22.86 0)
        (effects (font (size 1.27 1.27) (thickness 0.15)) (justify left bottom) hide)
      )
      (property "Author" "Antmicro" (at 13.97 -25.4 0)
        (effects (font (size 1.27 1.27) (thickness 0.15)) (justify left bottom) hide)
      )
      (property "License" "Apache-2.0" (at 13.97 -27.94 0)
        (effects (font (size 1.27 1.27) (thickness 0.15)) (justify left bottom) hide)
      )
      (symbol "L_2u2_7.8A_Coilcraft-XEL4030_0_1"
        (arc (start 1.524 0) (mid 1.016 0.5058) (end 0.508 0)
          (stroke (width 0) (type default))
          (fill (type none))
        )
        (arc (start 2.54 0) (mid 2.032 0.5058) (end 1.524 0)
          (stroke (width 0) (type default))
          (fill (type none))
        )
        (arc (start 3.556 0) (mid 3.048 0.5058) (end 2.54 0)
          (stroke (width 0) (type default))
          (fill (type none))
        )
        (arc (start 4.572 0) (mid 4.064 0.5058) (end 3.556 0)
          (stroke (width 0) (type default))
          (fill (type none))
        )
      )
      (symbol "L_2u2_7.8A_Coilcraft-XEL4030_1_1"
        (pin passive line (at 0 0 0) (length 0.508)
          (name "~" (effects (font (size 1.27 1.27))))
          (number "1" (effects (font (size 1.27 1.27))))
        )
        (pin passive line (at 5.08 0 180) (length 0.508)
          (name "~" (effects (font (size 1.27 1.27))))
          (number "2" (effects (font (size 1.27 1.27))))
        )
      )
    )
	(symbol "kria-k26-devboard:L_3u3_6.6A_XEL4030" (pin_numbers hide) (pin_names hide) (in_bom yes) (on_board yes)
      (property "Reference" "L" (at 13.97 0 0)
        (effects (font (size 1.27 1.27) (thickness 0.15)) (justify left bottom))
      )
      (property "Value" "L_3u3_5.9A_XEL4030" (at 13.97 -2.54 0)
        (effects (font (size 1.27 1.27) (thickness 0.15)) (justify left bottom) hide)
      )
      (property "Footprint" "kria-k26-devboard-footprints:L_Coilcraft-XEL4030" (at 13.97 -7.62 0)
        (effects (font (size 1.27 1.27) (thickness 0.15)) (justify left bottom) hide)
      )
      (property "Datasheet" "https://www.coilcraft.com/getmedia/8245f050-f190-4295-8c41-7c03d662ee3d/xel4030.pdf" (at 13.97 -10.16 0)
        (effects (font (size 1.27 1.27) (thickness 0.15)) (justify left bottom) hide)
      )
      (property "Val" "3u3/5.9A" (at 13.97 -5.08 0)
        (effects (font (size 1.27 1.27) (thickness 0.15)) (justify left bottom))
      )
      (property "Manufacturer" "Coilcraft" (at 13.97 -12.7 0)
        (effects (font (size 1.27 1.27) (thickness 0.15)) (justify left bottom) hide)
      )
      (property "MPN" "XEL4030-332MEC" (at 13.97 -15.24 0)
        (effects (font (size 1.27 1.27) (thickness 0.15)) (justify left bottom) hide)
      )
      (property "ISat" "" (at 13.97 -16.51 0)
        (effects (font (size 1.27 1.27)) (justify left) hide)
      )
      (property "IMax" "" (at 13.97 -20.32 0)
        (effects (font (size 1.27 1.27) (thickness 0.15)) (justify left bottom) hide)
      )
      (property "Size" "4x4" (at 13.97 -22.86 0)
        (effects (font (size 1.27 1.27) (thickness 0.15)) (justify left bottom) hide)
      )
      (property "Author" "Antmicro" (at 13.97 -25.4 0)
        (effects (font (size 1.27 1.27) (thickness 0.15)) (justify left bottom) hide)
      )
      (property "License" "Apache-2.0" (at 13.97 -27.94 0)
        (effects (font (size 1.27 1.27) (thickness 0.15)) (justify left bottom) hide)
      )
      (symbol "L_3u3_6.6A_XEL4030_0_1"
        (arc (start 1.524 0) (mid 1.016 0.5058) (end 0.508 0)
          (stroke (width 0) (type default))
          (fill (type none))
        )
        (arc (start 2.54 0) (mid 2.032 0.5058) (end 1.524 0)
          (stroke (width 0) (type default))
          (fill (type none))
        )
        (arc (start 3.556 0) (mid 3.048 0.5058) (end 2.54 0)
          (stroke (width 0) (type default))
          (fill (type none))
        )
        (arc (start 4.572 0) (mid 4.064 0.5058) (end 3.556 0)
          (stroke (width 0) (type default))
          (fill (type none))
        )
      )
      (symbol "L_3u3_6.6A_XEL4030_1_1"
        (pin passive line (at 0 0 0) (length 0.508)
          (name "~" (effects (font (size 1.27 1.27))))
          (number "1" (effects (font (size 1.27 1.27))))
        )
        (pin passive line (at 5.08 0 180) (length 0.508)
          (name "~" (effects (font (size 1.27 1.27))))
          (number "2" (effects (font (size 1.27 1.27))))
        )
      )
    )
	(symbol "kria-k26-devboard:M24C64-F_DFN8" (in_bom yes) (on_board yes)
      (property "Reference" "U" (at 38.1 -2.54 0)
        (effects (font (size 1.27 1.27) (thickness 0.15)) (justify left bottom))
      )
      (property "Value" "M24C64-F_DFN8" (at 38.1 -5.08 0)
        (effects (font (size 1.27 1.27) (thickness 0.15)) (justify left bottom))
      )
      (property "Footprint" "kria-k26-devboard-footprints:DFN-8-1EP_3x2mm_P0.5mm_EP1.36x1.46mm" (at 38.1 -7.62 0)
        (effects (font (size 1.27 1.27) (thickness 0.15)) (justify left bottom) hide)
      )
      (property "Datasheet" "https://eu.mouser.com/datasheet/2/389/cd00259166-1797197.pdf" (at 38.1 -10.16 0)
        (effects (font (size 1.27 1.27) (thickness 0.15)) (justify left bottom) hide)
      )
      (property "Manufacturer" "STMicroelectronics" (at 38.1 -12.7 0)
        (effects (font (size 1.27 1.27) (thickness 0.15)) (justify left bottom) hide)
      )
      (property "MPN" "M24C64-FMC6TG" (at 38.1 -15.24 0)
        (effects (font (size 1.27 1.27) (thickness 0.15)) (justify left bottom) hide)
      )
      (property "Author" "Antmicro" (at 38.1 -17.78 0)
        (effects (font (size 1.27 1.27) (thickness 0.15)) (justify left bottom) hide)
      )
      (property "License" "Apache-2.0" (at 38.1 -20.32 0)
        (effects (font (size 1.27 1.27) (thickness 0.15)) (justify left bottom) hide)
      )
      (property "ki_keywords" "SMT, MEMORY, IC, STORAGE, I2C" (at 0 0 0)
        (effects (font (size 1.27 1.27)) hide)
      )
      (property "ki_description" "EEPROM, 8K x 8bit, Serial I2C (2-Wire), 1 MHz, UFDFPN, 8 Pins" (at 0 0 0)
        (effects (font (size 1.27 1.27)) hide)
      )
      (property "ki_fp_filters" "UFDFPN8DFN8_2X3_STM UFDFPN8DFN8_2X3_STM-M UFDFPN8DFN8_2X3_STM-L" (at 0 0 0)
        (effects (font (size 1.27 1.27)) hide)
      )
      (symbol "M24C64-F_DFN8_1_1"
        (rectangle (start 2.54 2.54) (end 12.7 -13.97)
          (stroke (width 0.254) (type default))
          (fill (type background))
        )
        (pin input line (at 0 -6.35 0) (length 2.54)
          (name "E0" (effects (font (size 1.27 1.27))))
          (number "1" (effects (font (size 1.27 1.27))))
        )
        (pin input line (at 0 -8.89 0) (length 2.54)
          (name "E1" (effects (font (size 1.27 1.27))))
          (number "2" (effects (font (size 1.27 1.27))))
        )
        (pin input line (at 0 -11.43 0) (length 2.54)
          (name "E2" (effects (font (size 1.27 1.27))))
          (number "3" (effects (font (size 1.27 1.27))))
        )
        (pin power_in line (at 15.24 -11.43 180) (length 2.54)
          (name "VSS" (effects (font (size 1.27 1.27))))
          (number "4" (effects (font (size 1.27 1.27))))
        )
        (pin bidirectional line (at 0 -2.54 0) (length 2.54)
          (name "SDA" (effects (font (size 1.27 1.27))))
          (number "5" (effects (font (size 1.27 1.27))))
        )
        (pin input line (at 0 0 0) (length 2.54)
          (name "SCL" (effects (font (size 1.27 1.27))))
          (number "6" (effects (font (size 1.27 1.27))))
        )
        (pin input line (at 15.24 -5.08 180) (length 2.54)
          (name "~{WC}" (effects (font (size 1.27 1.27))))
          (number "7" (effects (font (size 1.27 1.27))))
        )
        (pin power_in line (at 15.24 0 180) (length 2.54)
          (name "VCC" (effects (font (size 1.27 1.27))))
          (number "8" (effects (font (size 1.27 1.27))))
        )
        (pin passive line (at 15.24 -11.43 180) (length 2.54) hide
          (name "VSS" (effects (font (size 1.27 1.27))))
          (number "9" (effects (font (size 1.27 1.27))))
        )
      )
    )
	(symbol "kria-k26-devboard:MB10S" (pin_names hide) (in_bom yes) (on_board yes)
      (property "Reference" "D" (at 27.94 -2.54 0)
        (effects (font (size 1.27 1.27) (thickness 0.15)) (justify left bottom))
      )
      (property "Value" "MB10S" (at 27.94 -5.08 0)
        (effects (font (size 1.27 1.27) (thickness 0.15)) (justify left bottom) hide)
      )
      (property "Footprint" "kria-k26-devboard-footprints:SOIC-4_W3.9mm" (at 27.94 -7.62 0)
        (effects (font (size 1.27 1.27) (thickness 0.15)) (justify left bottom) hide)
      )
      (property "Datasheet" "http://www.farnell.com/datasheets/2895435.pdf" (at 27.94 -10.16 0)
        (effects (font (size 1.27 1.27) (thickness 0.15)) (justify left bottom) hide)
      )
      (property "MPN" "MB10S" (at 27.94 -12.7 0)
        (effects (font (size 1.27 1.27) (thickness 0.15)) (justify left bottom))
      )
      (property "Manufacturer" "Multicomp Pro" (at 27.94 -15.24 0)
        (effects (font (size 1.27 1.27) (thickness 0.15)) (justify left bottom) hide)
      )
      (property "Author" "Antmicro" (at 27.94 -17.78 0)
        (effects (font (size 1.27 1.27) (thickness 0.15)) (justify left bottom) hide)
      )
      (property "License" "Apache-2.0" (at 27.94 -20.32 0)
        (effects (font (size 1.27 1.27) (thickness 0.15)) (justify left bottom) hide)
      )
      (property "ki_keywords" "SMT, DIODE, SEMICONDUCTOR, TVS, BRIDGE, RECTIFIER" (at 0 0 0)
        (effects (font (size 1.27 1.27)) hide)
      )
      (property "ki_description" "TVS diode" (at 0 0 0)
        (effects (font (size 1.27 1.27)) hide)
      )
      (symbol "MB10S_1_1"
        (polyline
          (pts
            (xy 2.54 -5.08)
            (xy 3.81 -5.08)
          )
          (stroke (width 0.254) (type default))
          (fill (type none))
        )
        (polyline
          (pts
            (xy 3.81 -10.16)
            (xy 2.54 -10.16)
          )
          (stroke (width 0.254) (type default))
          (fill (type none))
        )
        (polyline
          (pts
            (xy 3.81 -3.81)
            (xy 3.81 -7.62)
          )
          (stroke (width 0.254) (type default))
          (fill (type none))
        )
        (polyline
          (pts
            (xy 3.81 -2.54)
            (xy 3.81 -3.81)
          )
          (stroke (width 0.254) (type default))
          (fill (type none))
        )
        (polyline
          (pts
            (xy 3.81 0)
            (xy 2.54 0)
          )
          (stroke (width 0.254) (type default))
          (fill (type none))
        )
        (polyline
          (pts
            (xy 5.08 -7.62)
            (xy 3.81 -7.62)
          )
          (stroke (width 0.254) (type default))
          (fill (type none))
        )
        (polyline
          (pts
            (xy 5.08 -2.54)
            (xy 3.81 -2.54)
          )
          (stroke (width 0.254) (type default))
          (fill (type none))
        )
        (polyline
          (pts
            (xy 7.62 -6.35)
            (xy 7.62 -8.89)
          )
          (stroke (width 0.254) (type default))
          (fill (type none))
        )
        (polyline
          (pts
            (xy 7.62 -1.27)
            (xy 7.62 -3.81)
          )
          (stroke (width 0.254) (type default))
          (fill (type none))
        )
        (polyline
          (pts
            (xy 8.89 -7.62)
            (xy 7.62 -7.62)
          )
          (stroke (width 0.254) (type default))
          (fill (type none))
        )
        (polyline
          (pts
            (xy 8.89 -2.54)
            (xy 7.62 -2.54)
          )
          (stroke (width 0.254) (type default))
          (fill (type none))
        )
        (polyline
          (pts
            (xy 10.16 -7.62)
            (xy 7.62 -7.62)
          )
          (stroke (width 0.254) (type default))
          (fill (type none))
        )
        (polyline
          (pts
            (xy 10.16 -2.54)
            (xy 7.62 -2.54)
          )
          (stroke (width 0.254) (type default))
          (fill (type none))
        )
        (polyline
          (pts
            (xy 12.7 -7.62)
            (xy 13.97 -7.62)
          )
          (stroke (width 0.254) (type default))
          (fill (type none))
        )
        (polyline
          (pts
            (xy 12.7 -6.35)
            (xy 12.7 -8.89)
          )
          (stroke (width 0.254) (type default))
          (fill (type none))
        )
        (polyline
          (pts
            (xy 12.7 -2.54)
            (xy 13.97 -2.54)
          )
          (stroke (width 0.254) (type default))
          (fill (type none))
        )
        (polyline
          (pts
            (xy 12.7 -1.27)
            (xy 12.7 -3.81)
          )
          (stroke (width 0.254) (type default))
          (fill (type none))
        )
        (polyline
          (pts
            (xy 13.97 -5.08)
            (xy 15.24 -5.08)
          )
          (stroke (width 0.254) (type default))
          (fill (type none))
        )
        (polyline
          (pts
            (xy 13.97 -3.81)
            (xy 13.97 -7.62)
          )
          (stroke (width 0.254) (type default))
          (fill (type none))
        )
        (polyline
          (pts
            (xy 13.97 -2.54)
            (xy 13.97 -3.81)
          )
          (stroke (width 0.254) (type default))
          (fill (type none))
        )
        (polyline
          (pts
            (xy 8.89 -7.62)
            (xy 8.89 -10.16)
            (xy 3.81 -10.16)
          )
          (stroke (width 0.254) (type default))
          (fill (type none))
        )
        (polyline
          (pts
            (xy 8.89 -2.54)
            (xy 8.89 0)
            (xy 3.81 0)
          )
          (stroke (width 0.254) (type default))
          (fill (type none))
        )
        (polyline
          (pts
            (xy 5.08 -6.35)
            (xy 5.08 -8.89)
            (xy 7.62 -7.62)
            (xy 5.08 -6.35)
          )
          (stroke (width 0.254) (type default))
          (fill (type outline))
        )
        (polyline
          (pts
            (xy 5.08 -1.27)
            (xy 5.08 -3.81)
            (xy 7.62 -2.54)
            (xy 5.08 -1.27)
          )
          (stroke (width 0.254) (type default))
          (fill (type outline))
        )
        (polyline
          (pts
            (xy 10.16 -6.35)
            (xy 10.16 -8.89)
            (xy 12.7 -7.62)
            (xy 10.16 -6.35)
          )
          (stroke (width 0.254) (type default))
          (fill (type outline))
        )
        (polyline
          (pts
            (xy 10.16 -1.27)
            (xy 10.16 -3.81)
            (xy 12.7 -2.54)
            (xy 10.16 -1.27)
          )
          (stroke (width 0.254) (type default))
          (fill (type outline))
        )
        (rectangle (start 2.54 1.27) (end 15.24 -11.43)
          (stroke (width 0.254) (type default))
          (fill (type background))
        )
        (pin passive line (at 17.78 -5.08 180) (length 2.54)
          (name "1" (effects (font (size 1.27 1.27))))
          (number "1" (effects (font (size 1.27 1.27))))
        )
        (pin passive line (at 0 -5.08 0) (length 2.54)
          (name "2" (effects (font (size 1.27 1.27))))
          (number "2" (effects (font (size 1.27 1.27))))
        )
        (pin passive line (at 0 0 0) (length 2.54)
          (name "3" (effects (font (size 1.27 1.27))))
          (number "3" (effects (font (size 1.27 1.27))))
        )
        (pin passive line (at 0 -10.16 0) (length 2.54)
          (name "4" (effects (font (size 1.27 1.27))))
          (number "4" (effects (font (size 1.27 1.27))))
        )
      )
    )
	(symbol "kria-k26-devboard:MP_Pad6mm_Drill3mm" (pin_names hide) (in_bom no) (on_board yes)
      (property "Reference" "MP" (at 20.32 -2.54 0)
        (effects (font (size 1.27 1.27) (thickness 0.15)) (justify left bottom))
      )
      (property "Value" "MP_Pad6mm_Drill3mm" (at 20.32 -5.08 0)
        (effects (font (size 1.27 1.27) (thickness 0.15)) (justify left bottom))
      )
      (property "Footprint" "kria-k26-devboard-footprints:MP_Pad6mm_Drill3mm" (at 20.32 -7.62 0)
        (effects (font (size 1.27 1.27) (thickness 0.15)) (justify left bottom) hide)
      )
      (property "Datasheet" "" (at 16.84 -15.57 0)
        (effects (font (size 1.27 1.27) (thickness 0.15)) (justify left bottom) hide)
      )
      (property "Author" "Antmicro" (at 20.32 -10.16 0)
        (effects (font (size 1.27 1.27) (thickness 0.15)) (justify left bottom) hide)
      )
      (property "License" "Apache-2.0" (at 20.32 -12.7 0)
        (effects (font (size 1.27 1.27) (thickness 0.15)) (justify left bottom) hide)
      )
      (property "ki_keywords" "MECHANICAL" (at 0 0 0)
        (effects (font (size 1.27 1.27)) hide)
      )
      (property "ki_description" "Mechanical part" (at 0 0 0)
        (effects (font (size 1.27 1.27)) hide)
      )
      (symbol "MP_Pad6mm_Drill3mm_1_1"
        (circle (center 5.08 0) (radius 1.27)
          (stroke (width 0.254) (type default))
          (fill (type background))
        )
        (circle (center 5.08 0) (radius 2.54)
          (stroke (width 0.254) (type default))
          (fill (type background))
        )
        (pin passive line (at 0 0 0) (length 2.54)
          (name "~" (effects (font (size 1.27 1.27))))
          (number "1" (effects (font (size 1.27 1.27))))
        )
      )
    )
	(symbol "kria-k26-devboard:MicroSD_1140084168" (in_bom yes) (on_board yes)
      (property "Reference" "J" (at 38.1 -3.81 0)
        (effects (font (size 1.27 1.27) (thickness 0.15)) (justify left bottom))
      )
      (property "Value" "MicroSD_1140084168" (at 38.1 -6.35 0)
        (effects (font (size 1.27 1.27) (thickness 0.15)) (justify left bottom))
      )
      (property "Footprint" "kria-k26-devboard-footprints:MicroSD_Amphenol_1140084168" (at 38.1 -8.89 0)
        (effects (font (size 1.27 1.27) (thickness 0.15)) (justify left bottom) hide)
      )
      (property "Datasheet" "https://cdn.amphenol-cs.com/media/wysiwyg/files/documentation/datasheet/inputoutput/io_micro_sdcard.pdf" (at 38.1 -11.43 0)
        (effects (font (size 1.27 1.27) (thickness 0.15)) (justify left bottom) hide)
      )
      (property "MPN" "1140084168" (at 38.1 -13.97 0)
        (effects (font (size 1.27 1.27) (thickness 0.15)) (justify left bottom) hide)
      )
      (property "Manufacturer" "Amphenol" (at 38.1 -16.51 0)
        (effects (font (size 1.27 1.27) (thickness 0.15)) (justify left bottom) hide)
      )
      (property "Author" "Antmicro" (at 38.1 -19.05 0)
        (effects (font (size 1.27 1.27) (thickness 0.15)) (justify left bottom) hide)
      )
      (property "License" "Apache-2.0" (at 38.1 -21.59 0)
        (effects (font (size 1.27 1.27) (thickness 0.15)) (justify left bottom) hide)
      )
      (property "ki_keywords" "HORIZONTAL, SMT, MEMORY, CONNECTOR, MICRO" (at 0 0 0)
        (effects (font (size 1.27 1.27)) hide)
      )
      (property "ki_description" "Memory Card Connector, MicroSD, Push-Pull, 8 Contacts, Copper Alloy, Gold Plated Contacts" (at 0 0 0)
        (effects (font (size 1.27 1.27)) hide)
      )
      (symbol "MicroSD_1140084168_1_1"
        (polyline
          (pts
            (xy 2.54 2.54)
            (xy 2.54 -24.13)
            (xy 10.16 -24.13)
            (xy 13.97 -24.13)
            (xy 19.05 -24.13)
            (xy 19.05 -16.51)
            (xy 24.13 -11.43)
            (xy 24.13 2.54)
            (xy 2.54 2.54)
          )
          (stroke (width 0.254) (type default))
          (fill (type background))
        )
        (text "microSD CARD" (at 19.05 -12.7 900)
          (effects (font (size 1.27 1.27) (thickness 0.15)) (justify left bottom))
        )
        (pin bidirectional line (at 0 0 0) (length 2.54)
          (name "DAT2" (effects (font (size 1.27 1.27))))
          (number "1" (effects (font (size 1.27 1.27))))
        )
        (pin passive line (at 0 -22.86 0) (length 2.54)
          (name "CD2" (effects (font (size 1.27 1.27))))
          (number "10" (effects (font (size 1.27 1.27))))
        )
        (pin bidirectional line (at 0 -2.54 0) (length 2.54)
          (name "CD/DAT3" (effects (font (size 1.27 1.27))))
          (number "2" (effects (font (size 1.27 1.27))))
        )
        (pin bidirectional line (at 0 -5.08 0) (length 2.54)
          (name "CMD" (effects (font (size 1.27 1.27))))
          (number "3" (effects (font (size 1.27 1.27))))
        )
        (pin power_in line (at 0 -7.62 0) (length 2.54)
          (name "VDD" (effects (font (size 1.27 1.27))))
          (number "4" (effects (font (size 1.27 1.27))))
        )
        (pin output line (at 0 -10.16 0) (length 2.54)
          (name "CLK" (effects (font (size 1.27 1.27))))
          (number "5" (effects (font (size 1.27 1.27))))
        )
        (pin power_in line (at 0 -12.7 0) (length 2.54)
          (name "VSS" (effects (font (size 1.27 1.27))))
          (number "6" (effects (font (size 1.27 1.27))))
        )
        (pin bidirectional line (at 0 -15.24 0) (length 2.54)
          (name "DAT0" (effects (font (size 1.27 1.27))))
          (number "7" (effects (font (size 1.27 1.27))))
        )
        (pin bidirectional line (at 0 -17.78 0) (length 2.54)
          (name "DAT1" (effects (font (size 1.27 1.27))))
          (number "8" (effects (font (size 1.27 1.27))))
        )
        (pin passive line (at 0 -20.32 0) (length 2.54)
          (name "CD1" (effects (font (size 1.27 1.27))))
          (number "9" (effects (font (size 1.27 1.27))))
        )
        (pin passive line (at 21.59 -20.32 180) (length 2.54)
          (name "Shell" (effects (font (size 1.27 1.27))))
          (number "SH" (effects (font (size 1.27 1.27))))
        )
      )
    )
	(symbol "kria-k26-devboard:NB3L202KMN" (in_bom yes) (on_board yes)
      (property "Reference" "U" (at 55.88 -7.62 0)
        (effects (font (size 1.27 1.27) (thickness 0.15)) (justify left bottom))
      )
      (property "Value" "NB3L202KMN" (at 55.88 -10.16 0)
        (effects (font (size 1.27 1.27) (thickness 0.15)) (justify left bottom))
      )
      (property "Footprint" "kria-k26-devboard-footprints:VQFN-16-1EP_3x3mm_P0.5mm_EP1.68x1.68mm" (at 55.88 -12.7 0)
        (effects (font (size 1.27 1.27) (thickness 0.15)) (justify left bottom) hide)
      )
      (property "Datasheet" "https://www.mouser.com/datasheet/2/308/1/NB3L202K_D-2316569.pdf" (at 55.88 -15.24 0)
        (effects (font (size 1.27 1.27) (thickness 0.15)) (justify left bottom) hide)
      )
      (property "MPN" "NB3L202KMNTXG" (at 55.88 -17.78 0)
        (effects (font (size 1.27 1.27) (thickness 0.15)) (justify left bottom) hide)
      )
      (property "Manufacturer" "ON Semiconductor" (at 55.88 -20.32 0)
        (effects (font (size 1.27 1.27) (thickness 0.15)) (justify left bottom) hide)
      )
      (property "Author" "Antmicro" (at 55.88 -22.86 0)
        (effects (font (size 1.27 1.27) (thickness 0.15)) (justify left bottom) hide)
      )
      (property "License" "Apache-2.0" (at 55.88 -25.4 0)
        (effects (font (size 1.27 1.27) (thickness 0.15)) (justify left bottom) hide)
      )
      (property "ki_keywords" "SMT, CLOCK, IC" (at 0 0 0)
        (effects (font (size 1.27 1.27)) hide)
      )
      (property "ki_description" "Fanout Buffer, 2 Outputs, 2.97V to 3.63 V, QFN-16, -40°C to 85°C" (at 0 0 0)
        (effects (font (size 1.27 1.27)) hide)
      )
      (property "ki_fp_filters" "QFNN16_NB3L202_ONS QFNN16_NB3L202_ONS-M QFNN16_NB3L202_ONS-L" (at 0 0 0)
        (effects (font (size 1.27 1.27)) hide)
      )
      (symbol "NB3L202KMN_1_1"
        (rectangle (start 2.54 2.54) (end 16.51 -24.13)
          (stroke (width 0.254) (type default))
          (fill (type background))
        )
        (pin power_in line (at 19.05 -19.05 180) (length 2.54)
          (name "GND" (effects (font (size 1.27 1.27))))
          (number "1" (effects (font (size 1.27 1.27))))
        )
        (pin input line (at 19.05 -12.7 180) (length 2.54)
          (name "I_{REF}" (effects (font (size 1.27 1.27))))
          (number "10" (effects (font (size 1.27 1.27))))
        )
        (pin input line (at 0 -12.7 0) (length 2.54)
          (name "~{OE0}" (effects (font (size 1.27 1.27))))
          (number "11" (effects (font (size 1.27 1.27))))
        )
        (pin input line (at 0 -16.51 0) (length 2.54)
          (name "~{OE1}" (effects (font (size 1.27 1.27))))
          (number "12" (effects (font (size 1.27 1.27))))
        )
        (pin power_in line (at 0 0 0) (length 2.54)
          (name "VDD_O" (effects (font (size 1.27 1.27))))
          (number "13" (effects (font (size 1.27 1.27))))
        )
        (pin output line (at 19.05 0 180) (length 2.54)
          (name "DIF_{0}+" (effects (font (size 1.27 1.27))))
          (number "14" (effects (font (size 1.27 1.27))))
        )
        (pin output line (at 19.05 -2.54 180) (length 2.54)
          (name "DIF_{0}-" (effects (font (size 1.27 1.27))))
          (number "15" (effects (font (size 1.27 1.27))))
        )
        (pin power_in line (at 19.05 -21.59 180) (length 2.54)
          (name "GND_O" (effects (font (size 1.27 1.27))))
          (number "16" (effects (font (size 1.27 1.27))))
        )
        (pin power_in line (at 19.05 -16.51 180) (length 2.54)
          (name "EPAD" (effects (font (size 1.27 1.27))))
          (number "17" (effects (font (size 1.27 1.27))))
        )
        (pin input line (at 0 -6.35 0) (length 2.54)
          (name "CLK_{IN}+" (effects (font (size 1.27 1.27))))
          (number "2" (effects (font (size 1.27 1.27))))
        )
        (pin input line (at 0 -8.89 0) (length 2.54)
          (name "CLK_{IN}-" (effects (font (size 1.27 1.27))))
          (number "3" (effects (font (size 1.27 1.27))))
        )
        (pin power_in line (at 0 -2.54 0) (length 2.54)
          (name "VDD" (effects (font (size 1.27 1.27))))
          (number "4" (effects (font (size 1.27 1.27))))
        )
        (pin passive line (at 19.05 -21.59 180) (length 2.54) hide
          (name "GND_O" (effects (font (size 1.27 1.27))))
          (number "5" (effects (font (size 1.27 1.27))))
        )
        (pin output line (at 19.05 -8.89 180) (length 2.54)
          (name "DIF_{1}-" (effects (font (size 1.27 1.27))))
          (number "6" (effects (font (size 1.27 1.27))))
        )
        (pin output line (at 19.05 -6.35 180) (length 2.54)
          (name "DIF_{1}+" (effects (font (size 1.27 1.27))))
          (number "7" (effects (font (size 1.27 1.27))))
        )
        (pin passive line (at 0 0 0) (length 2.54) hide
          (name "VDD_O" (effects (font (size 1.27 1.27))))
          (number "8" (effects (font (size 1.27 1.27))))
        )
        (pin passive line (at 19.05 -19.05 180) (length 2.54) hide
          (name "GND" (effects (font (size 1.27 1.27))))
          (number "9" (effects (font (size 1.27 1.27))))
        )
      )
    )
	(symbol "kria-k26-devboard:NC7WZ07_SC" (in_bom yes) (on_board yes)
      (property "Reference" "U" (at 26.67 -2.54 0)
        (effects (font (size 1.27 1.27) (thickness 0.15)) (justify left bottom))
      )
      (property "Value" "NC7WZ07_SC" (at 26.67 -5.08 0)
        (effects (font (size 1.27 1.27) (thickness 0.15)) (justify left bottom))
      )
      (property "Footprint" "kria-k26-devboard-footprints:SOT-363" (at 26.67 -7.62 0)
        (effects (font (size 1.27 1.27) (thickness 0.15)) (justify left bottom) hide)
      )
      (property "Datasheet" "https://www.onsemi.com/pub/Collateral/NC7WZ07-D.pdf" (at 26.67 -10.16 0)
        (effects (font (size 1.27 1.27) (thickness 0.15)) (justify left bottom) hide)
      )
      (property "MPN" "NC7WZ07P6X" (at 26.67 -12.7 0)
        (effects (font (size 1.27 1.27) (thickness 0.15)) (justify left bottom) hide)
      )
      (property "Manufacturer" "ON Semiconductor" (at 26.67 -15.24 0)
        (effects (font (size 1.27 1.27) (thickness 0.15)) (justify left bottom) hide)
      )
      (property "Author" "Antmicro" (at 26.67 -17.78 0)
        (effects (font (size 1.27 1.27) (thickness 0.15)) (justify left bottom) hide)
      )
      (property "License" "Apache-2.0" (at 26.67 -20.32 0)
        (effects (font (size 1.27 1.27) (thickness 0.15)) (justify left bottom) hide)
      )
      (property "ki_keywords" "SMT, DRIVER, IC, LOGIC" (at 0 0 0)
        (effects (font (size 1.27 1.27)) hide)
      )
      (property "ki_description" "Buffer, 1.65 V to 5.5 V, SC-70-6" (at 0 0 0)
        (effects (font (size 1.27 1.27)) hide)
      )
      (symbol "NC7WZ07_SC_1_1"
        (polyline
          (pts
            (xy 2.54 -3.81)
            (xy 5.08 -3.81)
          )
          (stroke (width 0.254) (type default))
          (fill (type background))
        )
        (polyline
          (pts
            (xy 5.08 -10.16)
            (xy 2.54 -10.16)
          )
          (stroke (width 0.254) (type default))
          (fill (type background))
        )
        (polyline
          (pts
            (xy 5.715 -10.795)
            (xy 6.985 -10.795)
          )
          (stroke (width 0.254) (type default))
          (fill (type background))
        )
        (polyline
          (pts
            (xy 5.715 -4.445)
            (xy 6.985 -4.445)
          )
          (stroke (width 0.254) (type default))
          (fill (type background))
        )
        (polyline
          (pts
            (xy 12.7 -10.16)
            (xy 9.906 -10.16)
          )
          (stroke (width 0.254) (type default))
          (fill (type background))
        )
        (polyline
          (pts
            (xy 12.7 -3.81)
            (xy 10.16 -3.81)
          )
          (stroke (width 0.254) (type default))
          (fill (type background))
        )
        (polyline
          (pts
            (xy 5.08 -7.62)
            (xy 5.08 -12.7)
            (xy 10.16 -10.16)
            (xy 5.08 -7.62)
          )
          (stroke (width 0.254) (type default))
          (fill (type background))
        )
        (polyline
          (pts
            (xy 5.08 -1.27)
            (xy 5.08 -6.35)
            (xy 10.16 -3.81)
            (xy 5.08 -1.27)
          )
          (stroke (width 0.254) (type default))
          (fill (type background))
        )
        (polyline
          (pts
            (xy 6.35 -9.525)
            (xy 5.715 -10.16)
            (xy 6.35 -10.795)
            (xy 6.985 -10.16)
            (xy 6.35 -9.525)
          )
          (stroke (width 0.254) (type default))
          (fill (type background))
        )
        (polyline
          (pts
            (xy 6.35 -3.175)
            (xy 5.715 -3.81)
            (xy 6.35 -4.445)
            (xy 6.985 -3.81)
            (xy 6.35 -3.175)
          )
          (stroke (width 0.254) (type default))
          (fill (type background))
        )
        (rectangle (start 2.54 2.54) (end 12.7 -16.51)
          (stroke (width 0.254) (type default))
          (fill (type background))
        )
        (pin input line (at 0 -3.81 0) (length 2.54)
          (name "~" (effects (font (size 1.27 1.27))))
          (number "1" (effects (font (size 1.27 1.27))))
        )
        (pin power_in line (at 0 -13.97 0) (length 2.54)
          (name "GND" (effects (font (size 1.27 1.27))))
          (number "2" (effects (font (size 1.27 1.27))))
        )
        (pin input line (at 0 -10.16 0) (length 2.54)
          (name "~" (effects (font (size 1.27 1.27))))
          (number "3" (effects (font (size 1.27 1.27))))
        )
        (pin output line (at 15.24 -10.16 180) (length 2.54)
          (name "~" (effects (font (size 1.27 1.27))))
          (number "4" (effects (font (size 1.27 1.27))))
        )
        (pin power_in line (at 0 0 0) (length 2.54)
          (name "VCC" (effects (font (size 1.27 1.27))))
          (number "5" (effects (font (size 1.27 1.27))))
        )
        (pin output line (at 15.24 -3.81 180) (length 2.54)
          (name "~" (effects (font (size 1.27 1.27))))
          (number "6" (effects (font (size 1.27 1.27))))
        )
      )
    )
	(symbol "kria-k26-devboard:NCP730BMT330_WSON" (in_bom yes) (on_board yes)
      (property "Reference" "U" (at 30.48 -2.54 0)
        (effects (font (size 1.27 1.27) (thickness 0.15)) (justify left bottom))
      )
      (property "Value" "NCP730BMT330_WSON" (at 30.48 -5.08 0)
        (effects (font (size 1.27 1.27) (thickness 0.15)) (justify left bottom))
      )
      (property "Footprint" "kria-k26-devboard-footprints:WSON-6-1EP_2x2mm_P0.65mm" (at 30.48 -7.62 0)
        (effects (font (size 1.27 1.27) (thickness 0.15)) (justify left bottom) hide)
      )
      (property "Datasheet" "https://www.onsemi.com/download/data-sheet/pdf/ncp730-d.pdf" (at 30.48 -10.16 0)
        (effects (font (size 1.27 1.27) (thickness 0.15)) (justify left bottom) hide)
      )
      (property "MPN" "NCP730BMT330TBG" (at 30.48 -12.7 0)
        (effects (font (size 1.27 1.27) (thickness 0.15)) (justify left bottom) hide)
      )
      (property "Manufacturer" "ON Semiconductor" (at 30.48 -15.24 0)
        (effects (font (size 1.27 1.27) (thickness 0.15)) (justify left bottom) hide)
      )
      (property "Author" "Antmicro" (at 30.48 -17.78 0)
        (effects (font (size 1.27 1.27) (thickness 0.15)) (justify left bottom) hide)
      )
      (property "License" "Apache-2.0" (at 30.48 -20.32 0)
        (effects (font (size 1.27 1.27) (thickness 0.15)) (justify left bottom) hide)
      )
      (property "ki_keywords" "SMT, PMIC, IC, LDO, VOLTAGE, REGULATOR" (at 0 0 0)
        (effects (font (size 1.27 1.27)) hide)
      )
      (property "ki_description" "Linear Voltage Regulator IC Positive Fixed 1 Output 150mA 6-WDFN (2x2)" (at 0 0 0)
        (effects (font (size 1.27 1.27)) hide)
      )
      (symbol "NCP730BMT330_WSON_1_1"
        (rectangle (start 2.54 2.54) (end 12.7 -7.62)
          (stroke (width 0.254) (type default))
          (fill (type background))
        )
        (pin power_out line (at 15.24 0 180) (length 2.54)
          (name "V_{OUT}" (effects (font (size 1.27 1.27))))
          (number "1" (effects (font (size 1.27 1.27))))
        )
        (pin no_connect line (at 12.7 -5.08 180) (length 2.54) hide
          (name "NC" (effects (font (size 1.27 1.27))))
          (number "2" (effects (font (size 1.27 1.27))))
        )
        (pin power_in line (at 0 -5.08 0) (length 2.54)
          (name "GND" (effects (font (size 1.27 1.27))))
          (number "3" (effects (font (size 1.27 1.27))))
        )
        (pin input line (at 0 -2.54 0) (length 2.54)
          (name "EN" (effects (font (size 1.27 1.27))))
          (number "4" (effects (font (size 1.27 1.27))))
        )
        (pin open_collector line (at 15.24 -2.54 180) (length 2.54)
          (name "PG" (effects (font (size 1.27 1.27))))
          (number "5" (effects (font (size 1.27 1.27))))
        )
        (pin power_in line (at 0 0 0) (length 2.54)
          (name "V_{IN}" (effects (font (size 1.27 1.27))))
          (number "6" (effects (font (size 1.27 1.27))))
        )
        (pin passive line (at 0 -5.08 0) (length 2.54) hide
          (name "GND" (effects (font (size 1.27 1.27))))
          (number "7" (effects (font (size 1.27 1.27))))
        )
      )
    )
	(symbol "kria-k26-devboard:NVT4858_XQFN" (in_bom yes) (on_board yes)
      (property "Reference" "U" (at 53.34 -2.54 0)
        (effects (font (size 1.27 1.27) (thickness 0.15)) (justify left bottom))
      )
      (property "Value" "NVT4858_XQFN" (at 53.34 -5.08 0)
        (effects (font (size 1.27 1.27) (thickness 0.15)) (justify left bottom))
      )
      (property "Footprint" "kria-k26-devboard-footprints:SOT1161-2" (at 53.34 -7.62 0)
        (effects (font (size 1.27 1.27) (thickness 0.15)) (justify left bottom) hide)
      )
      (property "Datasheet" "https://www.nxp.com/docs/en/data-sheet/NVT4858DS.pdf" (at 53.34 -10.16 0)
        (effects (font (size 1.27 1.27) (thickness 0.15)) (justify left bottom) hide)
      )
      (property "Manufacturer" "NXP" (at 53.34 -12.7 0)
        (effects (font (size 1.27 1.27) (thickness 0.15)) (justify left bottom) hide)
      )
      (property "MPN" "NVT4858HKZ" (at 53.34 -15.24 0)
        (effects (font (size 1.27 1.27) (thickness 0.15)) (justify left bottom) hide)
      )
      (property "Author" "Antmicro" (at 53.34 -17.78 0)
        (effects (font (size 1.27 1.27) (thickness 0.15)) (justify left bottom) hide)
      )
      (property "License" "Apache-2.0" (at 53.34 -20.32 0)
        (effects (font (size 1.27 1.27) (thickness 0.15)) (justify left bottom) hide)
      )
      (property "ki_keywords" "SMT, LEVEL-SHIFTER, IC, LOGIC" (at 0 0 0)
        (effects (font (size 1.27 1.27)) hide)
      )
      (property "ki_description" "Level Translator, 4 Input, 1.08 V to 1.98 V, xQFN-16" (at 0 0 0)
        (effects (font (size 1.27 1.27)) hide)
      )
      (symbol "NVT4858_XQFN_1_1"
        (rectangle (start 2.54 2.54) (end 16.51 -27.94)
          (stroke (width 0.254) (type default))
          (fill (type background))
        )
        (pin bidirectional line (at 0 -17.78 0) (length 2.54)
          (name "DAT2_{A}" (effects (font (size 1.27 1.27))))
          (number "1" (effects (font (size 1.27 1.27))))
        )
        (pin bidirectional line (at 19.05 -12.7 180) (length 2.54)
          (name "DAT0_{B}" (effects (font (size 1.27 1.27))))
          (number "10" (effects (font (size 1.27 1.27))))
        )
        (pin bidirectional line (at 19.05 -20.32 180) (length 2.54)
          (name "DAT3_{B}" (effects (font (size 1.27 1.27))))
          (number "11" (effects (font (size 1.27 1.27))))
        )
        (pin bidirectional line (at 19.05 -17.78 180) (length 2.54)
          (name "DAT2_{B}" (effects (font (size 1.27 1.27))))
          (number "12" (effects (font (size 1.27 1.27))))
        )
        (pin bidirectional line (at 19.05 -5.08 180) (length 2.54)
          (name "CMD_{B}" (effects (font (size 1.27 1.27))))
          (number "13" (effects (font (size 1.27 1.27))))
        )
        (pin power_in line (at 19.05 0 180) (length 2.54)
          (name "VCC_{B}" (effects (font (size 1.27 1.27))))
          (number "14" (effects (font (size 1.27 1.27))))
        )
        (pin power_in line (at 0 0 0) (length 2.54)
          (name "VCC_{A}" (effects (font (size 1.27 1.27))))
          (number "15" (effects (font (size 1.27 1.27))))
        )
        (pin bidirectional line (at 0 -5.08 0) (length 2.54)
          (name "CMD_{A}" (effects (font (size 1.27 1.27))))
          (number "16" (effects (font (size 1.27 1.27))))
        )
        (pin bidirectional line (at 0 -20.32 0) (length 2.54)
          (name "DAT3_{A}" (effects (font (size 1.27 1.27))))
          (number "2" (effects (font (size 1.27 1.27))))
        )
        (pin bidirectional line (at 0 -12.7 0) (length 2.54)
          (name "DAT0_{A}" (effects (font (size 1.27 1.27))))
          (number "3" (effects (font (size 1.27 1.27))))
        )
        (pin bidirectional line (at 0 -15.24 0) (length 2.54)
          (name "DAT1_{A}" (effects (font (size 1.27 1.27))))
          (number "4" (effects (font (size 1.27 1.27))))
        )
        (pin input line (at 0 -7.62 0) (length 2.54)
          (name "CLK_{A}" (effects (font (size 1.27 1.27))))
          (number "5" (effects (font (size 1.27 1.27))))
        )
        (pin output line (at 0 -25.4 0) (length 2.54)
          (name "CLK_{FB}" (effects (font (size 1.27 1.27))))
          (number "6" (effects (font (size 1.27 1.27))))
        )
        (pin power_in line (at 19.05 -25.4 180) (length 2.54)
          (name "GND" (effects (font (size 1.27 1.27))))
          (number "7" (effects (font (size 1.27 1.27))))
        )
        (pin output line (at 19.05 -7.62 180) (length 2.54)
          (name "CLK_{B}" (effects (font (size 1.27 1.27))))
          (number "8" (effects (font (size 1.27 1.27))))
        )
        (pin bidirectional line (at 19.05 -15.24 180) (length 2.54)
          (name "DAT1_{B}" (effects (font (size 1.27 1.27))))
          (number "9" (effects (font (size 1.27 1.27))))
        )
      )
    )
	(symbol "kria-k26-devboard:Oscillator_100MHz_NX324" (in_bom yes) (on_board yes)
      (property "Reference" "Y" (at 29.21 -1.905 0)
        (effects (font (size 1.27 1.27) (thickness 0.15)) (justify left bottom))
      )
      (property "Value" "Oscillator_100MHz_NX324" (at 29.21 -12.065 0)
        (effects (font (size 1.27 1.27) (thickness 0.15)) (justify left bottom) hide)
      )
      (property "Footprint" "kria-k26-devboard-footprints:Oscillator_SMD_Abracon_AX3_3.2x2.5x1mm" (at 29.21 -14.605 0)
        (effects (font (size 1.27 1.27) (thickness 0.15)) (justify left bottom) hide)
      )
      (property "Datasheet" "https://www.diodes.com/assets/Datasheets/NX324.pdf" (at 29.21 -17.145 0)
        (effects (font (size 1.27 1.27) (thickness 0.15)) (justify left bottom) hide)
      )
      (property "Manufacturer" "Diodes Incorporated" (at 29.21 -4.445 0)
        (effects (font (size 1.27 1.27) (thickness 0.15)) (justify left bottom) hide)
      )
      (property "MPN" "NX3241E0100.000000" (at 29.21 -6.985 0)
        (effects (font (size 1.27 1.27) (thickness 0.15)) (justify left bottom))
      )
      (property "Val" "100 MHz" (at 29.21 -9.525 0)
        (effects (font (size 1.27 1.27) (thickness 0.15)) (justify left bottom))
      )
      (property "Author" "Antmicro" (at 29.21 -19.685 0)
        (effects (font (size 1.27 1.27) (thickness 0.15)) (justify left bottom) hide)
      )
      (property "License" "Apache-2.0" (at 29.21 -22.225 0)
        (effects (font (size 1.27 1.27) (thickness 0.15)) (justify left bottom) hide)
      )
      (property "ki_keywords" "OSCILLATOR" (at 0 0 0)
        (effects (font (size 1.27 1.27)) hide)
      )
      (property "ki_description" "100 MHz XO (Standard) HCSL Oscillator 3.3V Enable/Disable 6-SMD, No Lead" (at 0 0 0)
        (effects (font (size 1.27 1.27)) hide)
      )
      (symbol "Oscillator_100MHz_NX324_1_1"
        (polyline
          (pts
            (xy 7.62 -1.27)
            (xy 8.255 -1.27)
            (xy 8.255 0)
            (xy 8.89 0)
            (xy 8.89 -1.27)
            (xy 9.525 -1.27)
            (xy 9.525 0)
            (xy 10.16 0)
            (xy 10.16 -1.27)
          )
          (stroke (width 0.254) (type default))
          (fill (type background))
        )
        (rectangle (start 2.54 2.54) (end 16.51 -7.62)
          (stroke (width 0.254) (type default))
          (fill (type background))
        )
        (pin input line (at 0 -2.54 0) (length 2.54)
          (name "EN" (effects (font (size 1.27 1.27))))
          (number "1" (effects (font (size 1.27 1.27))))
        )
        (pin no_connect line (at 16.51 -5.08 180) (length 2.54) hide
          (name "NC" (effects (font (size 1.27 1.27))))
          (number "2" (effects (font (size 1.27 1.27))))
        )
        (pin power_in line (at 0 -5.08 0) (length 2.54)
          (name "GND" (effects (font (size 1.27 1.27))))
          (number "3" (effects (font (size 1.27 1.27))))
        )
        (pin output line (at 19.05 0 180) (length 2.54)
          (name "OUT+" (effects (font (size 1.27 1.27))))
          (number "4" (effects (font (size 1.27 1.27))))
        )
        (pin output line (at 19.05 -2.54 180) (length 2.54)
          (name "OUT-" (effects (font (size 1.27 1.27))))
          (number "5" (effects (font (size 1.27 1.27))))
        )
        (pin power_in line (at 0 0 0) (length 2.54)
          (name "VCC" (effects (font (size 1.27 1.27))))
          (number "6" (effects (font (size 1.27 1.27))))
        )
      )
    )
	(symbol "kria-k26-devboard:Oscillator_125MHz_AX3DA" (in_bom yes) (on_board yes)
      (property "Reference" "Y" (at 28.575 -1.905 0)
        (effects (font (size 1.27 1.27) (thickness 0.15)) (justify left bottom))
      )
      (property "Value" "Oscillator_125MHz_AX3DA" (at 28.575 -12.065 0)
        (effects (font (size 1.27 1.27) (thickness 0.15)) (justify left bottom) hide)
      )
      (property "Footprint" "kria-k26-devboard-footprints:Oscillator_SMD_Abracon_AX3_3.2x2.5x1mm" (at 28.575 -14.605 0)
        (effects (font (size 1.27 1.27) (thickness 0.15)) (justify left bottom) hide)
      )
      (property "Datasheet" "https://abracon.com/datasheets/AX3.pdf" (at 28.575 -17.145 0)
        (effects (font (size 1.27 1.27) (thickness 0.15)) (justify left bottom) hide)
      )
      (property "Manufacturer" "Abracon" (at 28.575 -4.445 0)
        (effects (font (size 1.27 1.27) (thickness 0.15)) (justify left bottom) hide)
      )
      (property "MPN" "AX3DAF1-125.0000" (at 28.575 -6.985 0)
        (effects (font (size 1.27 1.27) (thickness 0.15)) (justify left bottom))
      )
      (property "Val" "125 MHz" (at 28.575 -9.525 0)
        (effects (font (size 1.27 1.27) (thickness 0.15)) (justify left bottom))
      )
      (property "Author" "Antmicro" (at 28.575 -19.685 0)
        (effects (font (size 1.27 1.27) (thickness 0.15)) (justify left bottom) hide)
      )
      (property "License" "Apache-2.0" (at 28.575 -22.225 0)
        (effects (font (size 1.27 1.27) (thickness 0.15)) (justify left bottom) hide)
      )
      (property "ki_keywords" "OSCILLATOR, LVDS" (at 0 0 0)
        (effects (font (size 1.27 1.27)) hide)
      )
      (property "ki_description" "125 MHz XO (Standard) LVDS Oscillator 3.3V Enable/Disable 6-SMD, No Lead" (at 0 0 0)
        (effects (font (size 1.27 1.27)) hide)
      )
      (symbol "Oscillator_125MHz_AX3DA_1_1"
        (polyline
          (pts
            (xy 7.62 -1.27)
            (xy 8.255 -1.27)
            (xy 8.255 0)
            (xy 8.89 0)
            (xy 8.89 -1.27)
            (xy 9.525 -1.27)
            (xy 9.525 0)
            (xy 10.16 0)
            (xy 10.16 -1.27)
          )
          (stroke (width 0.254) (type default))
          (fill (type background))
        )
        (rectangle (start 2.54 2.54) (end 16.51 -7.62)
          (stroke (width 0.254) (type default))
          (fill (type background))
        )
        (pin input line (at 0 -2.54 0) (length 2.54)
          (name "EN" (effects (font (size 1.27 1.27))))
          (number "1" (effects (font (size 1.27 1.27))))
        )
        (pin no_connect line (at 16.51 -5.08 180) (length 2.54) hide
          (name "NC" (effects (font (size 1.27 1.27))))
          (number "2" (effects (font (size 1.27 1.27))))
        )
        (pin power_in line (at 0 -5.08 0) (length 2.54)
          (name "GND" (effects (font (size 1.27 1.27))))
          (number "3" (effects (font (size 1.27 1.27))))
        )
        (pin output line (at 19.05 0 180) (length 2.54)
          (name "OUT+" (effects (font (size 1.27 1.27))))
          (number "4" (effects (font (size 1.27 1.27))))
        )
        (pin output line (at 19.05 -2.54 180) (length 2.54)
          (name "OUT-" (effects (font (size 1.27 1.27))))
          (number "5" (effects (font (size 1.27 1.27))))
        )
        (pin power_in line (at 0 0 0) (length 2.54)
          (name "VCC" (effects (font (size 1.27 1.27))))
          (number "6" (effects (font (size 1.27 1.27))))
        )
      )
    )
	(symbol "kria-k26-devboard:Oscillator_24MHz_ESC_2016MV" (in_bom yes) (on_board yes)
      (property "Reference" "Y" (at 17.78 -5.08 0)
        (effects (font (size 1.27 1.27) (thickness 0.15)) (justify left bottom))
      )
      (property "Value" "Oscillator_24MHz_ESC_2016MV" (at 17.78 -15.24 0)
        (effects (font (size 1.27 1.27) (thickness 0.15)) (justify left bottom) hide)
      )
      (property "Footprint" "kria-k26-devboard-footprints:Oscillator_SMD_ECS_2016MV_2x1.6x0.85mm" (at 17.78 -17.78 0)
        (effects (font (size 1.27 1.27) (thickness 0.15)) (justify left bottom) hide)
      )
      (property "Datasheet" "https://ecsxtal.com/store/pdf/ECS-2016MV.pdf" (at 17.78 -20.32 0)
        (effects (font (size 1.27 1.27) (thickness 0.15)) (justify left bottom) hide)
      )
      (property "MPN" "ECS-2016MV-240-CN-TR" (at 17.78 -7.62 0)
        (effects (font (size 1.27 1.27) (thickness 0.15)) (justify left bottom))
      )
      (property "Manufacturer" "ECS Inc. International" (at 17.78 -10.16 0)
        (effects (font (size 1.27 1.27) (thickness 0.15)) (justify left bottom) hide)
      )
      (property "Val" "24 MHz" (at 17.78 -12.7 0)
        (effects (font (size 1.27 1.27) (thickness 0.15)) (justify left bottom))
      )
      (property "Author" "Antmicro" (at 17.78 -22.86 0)
        (effects (font (size 1.27 1.27) (thickness 0.15)) (justify left bottom) hide)
      )
      (property "License" "Apache-2.0" (at 17.78 -25.4 0)
        (effects (font (size 1.27 1.27) (thickness 0.15)) (justify left bottom) hide)
      )
      (property "ki_keywords" "OSCILLATOR" (at 0 0 0)
        (effects (font (size 1.27 1.27)) hide)
      )
      (property "ki_description" "Oscillator, 24 MHz XO (Standard) CMOS 1.6V ~ 3.6V Enable/Disable 4-SMD, No Lead" (at 0 0 0)
        (effects (font (size 1.27 1.27)) hide)
      )
      (symbol "Oscillator_24MHz_ESC_2016MV_1_1"
        (polyline
          (pts
            (xy 7.62 -1.27)
            (xy 8.255 -1.27)
            (xy 8.255 0)
            (xy 8.89 0)
            (xy 8.89 -1.27)
            (xy 9.525 -1.27)
            (xy 9.525 0)
            (xy 10.16 0)
            (xy 10.16 -1.27)
          )
          (stroke (width 0.254) (type default))
          (fill (type background))
        )
        (rectangle (start 2.54 2.54) (end 16.51 -7.62)
          (stroke (width 0.254) (type default))
          (fill (type background))
        )
        (pin input line (at 0 -2.54 0) (length 2.54)
          (name "EN" (effects (font (size 1.27 1.27))))
          (number "1" (effects (font (size 1.27 1.27))))
        )
        (pin power_in line (at 0 -5.08 0) (length 2.54)
          (name "GND" (effects (font (size 1.27 1.27))))
          (number "2" (effects (font (size 1.27 1.27))))
        )
        (pin output line (at 19.05 0 180) (length 2.54)
          (name "OUT" (effects (font (size 1.27 1.27))))
          (number "3" (effects (font (size 1.27 1.27))))
        )
        (pin power_in line (at 0 0 0) (length 2.54)
          (name "VDD" (effects (font (size 1.27 1.27))))
          (number "4" (effects (font (size 1.27 1.27))))
        )
      )
    )
	(symbol "kria-k26-devboard:Oscillator_25MHz_ESC_2016MV" (in_bom yes) (on_board yes)
      (property "Reference" "Y" (at 25.4 -2.54 0)
        (effects (font (size 1.27 1.27) (thickness 0.15)) (justify left bottom))
      )
      (property "Value" "Oscillator_25MHz_ESC_2016MV" (at 25.4 -12.7 0)
        (effects (font (size 1.27 1.27) (thickness 0.15)) (justify left bottom) hide)
      )
      (property "Footprint" "kria-k26-devboard-footprints:Oscillator_SMD_ECS_2016MV_2x1.6x0.85mm" (at 25.4 -15.24 0)
        (effects (font (size 1.27 1.27) (thickness 0.15)) (justify left bottom) hide)
      )
      (property "Datasheet" "https://ecsxtal.com/store/pdf/ECS-2016MV.pdf" (at 25.4 -17.78 0)
        (effects (font (size 1.27 1.27) (thickness 0.15)) (justify left bottom) hide)
      )
      (property "MPN" "ECS-2016MV-250-CN-TR" (at 25.4 -5.08 0)
        (effects (font (size 1.27 1.27) (thickness 0.15)) (justify left bottom))
      )
      (property "Manufacturer" "ECS Inc. International" (at 25.4 -7.62 0)
        (effects (font (size 1.27 1.27) (thickness 0.15)) (justify left bottom) hide)
      )
      (property "Val" "25 MHz" (at 25.4 -10.16 0)
        (effects (font (size 1.27 1.27) (thickness 0.15)) (justify left bottom))
      )
      (property "Author" "Antmicro" (at 25.4 -20.32 0)
        (effects (font (size 1.27 1.27) (thickness 0.15)) (justify left bottom) hide)
      )
      (property "License" "Apache-2.0" (at 25.4 -22.86 0)
        (effects (font (size 1.27 1.27) (thickness 0.15)) (justify left bottom) hide)
      )
      (property "ki_keywords" "OSCILLATOR" (at 0 0 0)
        (effects (font (size 1.27 1.27)) hide)
      )
      (property "ki_description" "Oscillator, 25 MHz, HCMOS, SMD, 2mm x 1.6mm, MultiVolt ECS-2016MV Series" (at 0 0 0)
        (effects (font (size 1.27 1.27)) hide)
      )
      (symbol "Oscillator_25MHz_ESC_2016MV_1_1"
        (polyline
          (pts
            (xy 7.62 -1.27)
            (xy 8.255 -1.27)
            (xy 8.255 0)
            (xy 8.89 0)
            (xy 8.89 -1.27)
            (xy 9.525 -1.27)
            (xy 9.525 0)
            (xy 10.16 0)
            (xy 10.16 -1.27)
          )
          (stroke (width 0.254) (type default))
          (fill (type background))
        )
        (rectangle (start 2.54 2.54) (end 16.51 -7.62)
          (stroke (width 0.254) (type default))
          (fill (type background))
        )
        (pin input line (at 0 -2.54 0) (length 2.54)
          (name "EN" (effects (font (size 1.27 1.27))))
          (number "1" (effects (font (size 1.27 1.27))))
        )
        (pin power_in line (at 0 -5.08 0) (length 2.54)
          (name "GND" (effects (font (size 1.27 1.27))))
          (number "2" (effects (font (size 1.27 1.27))))
        )
        (pin output line (at 19.05 0 180) (length 2.54)
          (name "OUT" (effects (font (size 1.27 1.27))))
          (number "3" (effects (font (size 1.27 1.27))))
        )
        (pin power_in line (at 0 0 0) (length 2.54)
          (name "VDD" (effects (font (size 1.27 1.27))))
          (number "4" (effects (font (size 1.27 1.27))))
        )
      )
    )
	(symbol "kria-k26-devboard:Oscillator_26MHz_ESC_2520MV" (in_bom yes) (on_board yes)
      (property "Reference" "Y" (at 26.035 -1.905 0)
        (effects (font (size 1.27 1.27) (thickness 0.15)) (justify left bottom))
      )
      (property "Value" "Oscillator_26MHz_ESC_2520MV" (at 26.035 -12.065 0)
        (effects (font (size 1.27 1.27) (thickness 0.15)) (justify left bottom) hide)
      )
      (property "Footprint" "kria-k26-devboard-footprints:Oscillator_SMD_ECS_2520MV_2.5x2mm" (at 26.035 -14.605 0)
        (effects (font (size 1.27 1.27) (thickness 0.15)) (justify left bottom) hide)
      )
      (property "Datasheet" "https://ecsxtal.com/store/pdf/ECS-2520MV.pdf" (at 26.035 -17.145 0)
        (effects (font (size 1.27 1.27) (thickness 0.15)) (justify left bottom) hide)
      )
      (property "MPN" "ECS-2520MVLC-260-CM-TR" (at 26.035 -4.445 0)
        (effects (font (size 1.27 1.27) (thickness 0.15)) (justify left bottom))
      )
      (property "Manufacturer" "ECS Inc. International" (at 26.035 -6.985 0)
        (effects (font (size 1.27 1.27) (thickness 0.15)) (justify left bottom) hide)
      )
      (property "Val" "26 MHz" (at 26.035 -9.525 0)
        (effects (font (size 1.27 1.27) (thickness 0.15)) (justify left bottom))
      )
      (property "Author" "Antmicro" (at 26.035 -19.685 0)
        (effects (font (size 1.27 1.27) (thickness 0.15)) (justify left bottom) hide)
      )
      (property "License" "Apache-2.0" (at 26.035 -22.225 0)
        (effects (font (size 1.27 1.27) (thickness 0.15)) (justify left bottom) hide)
      )
      (property "ki_keywords" "OSCILLATOR" (at 0 0 0)
        (effects (font (size 1.27 1.27)) hide)
      )
      (property "ki_description" "Oscillator, 26 MHz, CMOS, 25 ppm, SMD, 2.5mm x 2mm, 3.6 V, MultiVolt ECS-2520MVLC Series" (at 0 0 0)
        (effects (font (size 1.27 1.27)) hide)
      )
      (symbol "Oscillator_26MHz_ESC_2520MV_1_1"
        (polyline
          (pts
            (xy 7.62 -1.27)
            (xy 8.255 -1.27)
            (xy 8.255 0)
            (xy 8.89 0)
            (xy 8.89 -1.27)
            (xy 9.525 -1.27)
            (xy 9.525 0)
            (xy 10.16 0)
            (xy 10.16 -1.27)
          )
          (stroke (width 0.254) (type default))
          (fill (type background))
        )
        (rectangle (start 2.54 2.54) (end 16.51 -7.62)
          (stroke (width 0.254) (type default))
          (fill (type background))
        )
        (pin input line (at 0 -2.54 0) (length 2.54)
          (name "EN" (effects (font (size 1.27 1.27))))
          (number "1" (effects (font (size 1.27 1.27))))
        )
        (pin power_in line (at 0 -5.08 0) (length 2.54)
          (name "GND" (effects (font (size 1.27 1.27))))
          (number "2" (effects (font (size 1.27 1.27))))
        )
        (pin output line (at 19.05 0 180) (length 2.54)
          (name "OUT" (effects (font (size 1.27 1.27))))
          (number "3" (effects (font (size 1.27 1.27))))
        )
        (pin power_in line (at 0 0 0) (length 2.54)
          (name "VDD" (effects (font (size 1.27 1.27))))
          (number "4" (effects (font (size 1.27 1.27))))
        )
      )
    )
	(symbol "kria-k26-devboard:Oscillator_27MHz_JU6" (in_bom yes) (on_board yes)
      (property "Reference" "Y" (at 20.32 -10.16 0)
        (effects (font (size 1.27 1.27) (thickness 0.15)) (justify left bottom))
      )
      (property "Value" "Oscillator_27MHz_JU6" (at 20.32 -20.32 0)
        (effects (font (size 1.27 1.27) (thickness 0.15)) (justify left bottom) hide)
      )
      (property "Footprint" "kria-k26-devboard-footprints:Oscillator_SMD_JU6_7x5mm_P2.54mm" (at 20.32 -22.86 0)
        (effects (font (size 1.27 1.27) (thickness 0.15)) (justify left bottom) hide)
      )
      (property "Datasheet" "https://www.idt.com/document/dst/xl-family-low-phase-noise-quartz-based-pll-oscillators-datasheet" (at 20.32 -25.4 0)
        (effects (font (size 1.27 1.27) (thickness 0.15)) (justify left bottom) hide)
      )
      (property "Manufacturer" "Renesas" (at 20.32 -12.7 0)
        (effects (font (size 1.27 1.27) (thickness 0.15)) (justify left bottom) hide)
      )
      (property "MPN" "XLL736027.000000X" (at 20.32 -15.24 0)
        (effects (font (size 1.27 1.27) (thickness 0.15)) (justify left bottom))
      )
      (property "Val" "27 MHz" (at 20.32 -17.78 0)
        (effects (font (size 1.27 1.27) (thickness 0.15)) (justify left bottom))
      )
      (property "Author" "Antmicro" (at 20.32 -27.94 0)
        (effects (font (size 1.27 1.27) (thickness 0.15)) (justify left bottom) hide)
      )
      (property "License" "Apache-2.0" (at 20.32 -30.48 0)
        (effects (font (size 1.27 1.27) (thickness 0.15)) (justify left bottom) hide)
      )
      (property "ki_keywords" "OSCILLATOR, LVDS" (at 0 0 0)
        (effects (font (size 1.27 1.27)) hide)
      )
      (property "ki_description" "27 MHz XO (Standard) LVDS Oscillator 3.3V Enable/Disable 6-SMD, No Lead" (at 0 0 0)
        (effects (font (size 1.27 1.27)) hide)
      )
      (symbol "Oscillator_27MHz_JU6_1_1"
        (polyline
          (pts
            (xy 7.62 -1.27)
            (xy 8.255 -1.27)
            (xy 8.255 0)
            (xy 8.89 0)
            (xy 8.89 -1.27)
            (xy 9.525 -1.27)
            (xy 9.525 0)
            (xy 10.16 0)
            (xy 10.16 -1.27)
          )
          (stroke (width 0.254) (type default))
          (fill (type background))
        )
        (rectangle (start 2.54 2.54) (end 16.51 -7.62)
          (stroke (width 0.254) (type default))
          (fill (type background))
        )
        (pin input line (at 0 -2.54 0) (length 2.54)
          (name "EN" (effects (font (size 1.27 1.27))))
          (number "1" (effects (font (size 1.27 1.27))))
        )
        (pin no_connect line (at 16.51 -5.08 180) (length 2.54) hide
          (name "NC" (effects (font (size 1.27 1.27))))
          (number "2" (effects (font (size 1.27 1.27))))
        )
        (pin power_in line (at 0 -5.08 0) (length 2.54)
          (name "GND" (effects (font (size 1.27 1.27))))
          (number "3" (effects (font (size 1.27 1.27))))
        )
        (pin output line (at 19.05 0 180) (length 2.54)
          (name "OUT+" (effects (font (size 1.27 1.27))))
          (number "4" (effects (font (size 1.27 1.27))))
        )
        (pin output line (at 19.05 -2.54 180) (length 2.54)
          (name "OUT-" (effects (font (size 1.27 1.27))))
          (number "5" (effects (font (size 1.27 1.27))))
        )
        (pin power_in line (at 0 0 0) (length 2.54)
          (name "VCC" (effects (font (size 1.27 1.27))))
          (number "6" (effects (font (size 1.27 1.27))))
        )
      )
    )
	(symbol "kria-k26-devboard:PCA9306D_SOIC" (in_bom yes) (on_board yes)
      (property "Reference" "U" (at 33.02 -3.81 0)
        (effects (font (size 1.27 1.27) (thickness 0.15)) (justify left bottom))
      )
      (property "Value" "PCA9306D_SOIC" (at 33.02 -6.35 0)
        (effects (font (size 1.27 1.27) (thickness 0.15)) (justify left bottom))
      )
      (property "Footprint" "kria-k26-devboard-footprints:SOIC-8_3.9x4.9x1.75mm_P1.27mm" (at 33.02 -8.89 0)
        (effects (font (size 1.27 1.27) (thickness 0.15)) (justify left bottom) hide)
      )
      (property "Datasheet" "https://www.nxp.com/docs/en/data-sheet/PCA9306.pdf" (at 33.02 -11.43 0)
        (effects (font (size 1.27 1.27) (thickness 0.15)) (justify left bottom) hide)
      )
      (property "MPN" "PCA9306D,118" (at 33.02 -13.97 0)
        (effects (font (size 1.27 1.27) (thickness 0.15)) (justify left bottom) hide)
      )
      (property "Manufacturer" "NXP" (at 33.02 -16.51 0)
        (effects (font (size 1.27 1.27) (thickness 0.15)) (justify left bottom) hide)
      )
      (property "Author" "Antmicro" (at 33.02 -19.05 0)
        (effects (font (size 1.27 1.27) (thickness 0.15)) (justify left bottom) hide)
      )
      (property "License" "Apache-2.0" (at 33.02 -21.59 0)
        (effects (font (size 1.27 1.27) (thickness 0.15)) (justify left bottom) hide)
      )
      (property "ki_keywords" "SMT, LEVEL-SHIFTER, IC" (at 0 0 0)
        (effects (font (size 1.27 1.27)) hide)
      )
      (property "ki_description" "Specialized Interface, I2C, SMBus, I2C Bus & SMBus Systems Applications, 0 V, 5 V, SOIC, 8 Pins" (at 0 0 0)
        (effects (font (size 1.27 1.27)) hide)
      )
      (symbol "PCA9306D_SOIC_1_1"
        (rectangle (start 2.54 2.54) (end 16.51 -15.24)
          (stroke (width 0.254) (type default))
          (fill (type background))
        )
        (pin power_in line (at 0 -12.7 0) (length 2.54)
          (name "GND" (effects (font (size 1.27 1.27))))
          (number "1" (effects (font (size 1.27 1.27))))
        )
        (pin power_in line (at 0 0 0) (length 2.54)
          (name "VREF_{1}" (effects (font (size 1.27 1.27))))
          (number "2" (effects (font (size 1.27 1.27))))
        )
        (pin bidirectional line (at 0 -6.35 0) (length 2.54)
          (name "SCL_{1}" (effects (font (size 1.27 1.27))))
          (number "3" (effects (font (size 1.27 1.27))))
        )
        (pin bidirectional line (at 0 -8.89 0) (length 2.54)
          (name "SDA_{1}" (effects (font (size 1.27 1.27))))
          (number "4" (effects (font (size 1.27 1.27))))
        )
        (pin bidirectional line (at 19.05 -8.89 180) (length 2.54)
          (name "SDA_{2}" (effects (font (size 1.27 1.27))))
          (number "5" (effects (font (size 1.27 1.27))))
        )
        (pin bidirectional line (at 19.05 -6.35 180) (length 2.54)
          (name "SCL_{2}" (effects (font (size 1.27 1.27))))
          (number "6" (effects (font (size 1.27 1.27))))
        )
        (pin power_in line (at 19.05 0 180) (length 2.54)
          (name "VREF_{2}" (effects (font (size 1.27 1.27))))
          (number "7" (effects (font (size 1.27 1.27))))
        )
        (pin input line (at 0 -2.54 0) (length 2.54)
          (name "EN" (effects (font (size 1.27 1.27))))
          (number "8" (effects (font (size 1.27 1.27))))
        )
      )
    )
	(symbol "kria-k26-devboard:PDQE30-Q48-S12-D" (in_bom yes) (on_board yes)
      (property "Reference" "U" (at 35.56 -2.54 0)
        (effects (font (size 1.27 1.27) (thickness 0.15)) (justify left bottom))
      )
      (property "Value" "PDQE30-Q48-S12-D" (at 35.56 -7.62 0)
        (effects (font (size 1.27 1.27) (thickness 0.15)) (justify left bottom) hide)
      )
      (property "Footprint" "kria-k26-devboard-footprints:CONV_PDQE30-Q48-S5-D" (at 35.56 -10.16 0)
        (effects (font (size 1.27 1.27) (thickness 0.15)) (justify left bottom) hide)
      )
      (property "Datasheet" "https://www.cui.com/product/resource/pdqe30-d.pdf" (at 35.56 -12.7 0)
        (effects (font (size 1.27 1.27) (thickness 0.15)) (justify left bottom) hide)
      )
      (property "MPN" "PDQE30-Q48-S12-D" (at 35.56 -5.08 0)
        (effects (font (size 1.27 1.27) (thickness 0.15)) (justify left bottom))
      )
      (property "Manufacturer" "CUI Inc" (at 35.56 -15.24 0)
        (effects (font (size 1.27 1.27) (thickness 0.15)) (justify left bottom) hide)
      )
      (property "Author" "Antmicro" (at 35.56 -17.78 0)
        (effects (font (size 1.27 1.27) (thickness 0.15)) (justify left bottom) hide)
      )
      (property "License" "Apache-2.0" (at 35.56 -20.32 0)
        (effects (font (size 1.27 1.27) (thickness 0.15)) (justify left bottom) hide)
      )
      (property "ki_keywords" "THT, PMIC, IC, DC-DC, CONVERTER" (at 0 0 0)
        (effects (font (size 1.27 1.27)) hide)
      )
      (property "ki_description" "Isolated Through Hole DC/DC Converter, ITE, 4:1, 30 W, 1 Output, 12 V, 2.5 A" (at 0 0 0)
        (effects (font (size 1.27 1.27)) hide)
      )
      (symbol "PDQE30-Q48-S12-D_1_1"
        (rectangle (start 2.54 2.54) (end 17.78 -17.78)
          (stroke (width 0.254) (type default))
          (fill (type background))
        )
        (pin input line (at 0 -7.62 0) (length 2.54)
          (name "CTRL" (effects (font (size 1.27 1.27))))
          (number "1" (effects (font (size 1.27 1.27))))
        )
        (pin power_in line (at 0 -15.24 0) (length 2.54)
          (name "GND" (effects (font (size 1.27 1.27))))
          (number "2" (effects (font (size 1.27 1.27))))
        )
        (pin power_in line (at 0 0 0) (length 2.54)
          (name "V_{IN}" (effects (font (size 1.27 1.27))))
          (number "3" (effects (font (size 1.27 1.27))))
        )
        (pin power_out line (at 20.32 0 180) (length 2.54)
          (name "V_{O}" (effects (font (size 1.27 1.27))))
          (number "4" (effects (font (size 1.27 1.27))))
        )
        (pin passive line (at 20.32 -7.62 180) (length 2.54)
          (name "TRIM" (effects (font (size 1.27 1.27))))
          (number "5" (effects (font (size 1.27 1.27))))
        )
        (pin power_out line (at 20.32 -15.24 180) (length 2.54)
          (name "0V" (effects (font (size 1.27 1.27))))
          (number "6" (effects (font (size 1.27 1.27))))
        )
      )
    )
	(symbol "kria-k26-devboard:PI4MSD5V9540B_MSOP" (in_bom yes) (on_board yes)
      (property "Reference" "U" (at 35.56 -2.54 0)
        (effects (font (size 1.27 1.27) (thickness 0.15)) (justify left bottom))
      )
      (property "Value" "PI4MSD5V9540B_MSOP" (at 35.56 -5.08 0)
        (effects (font (size 1.27 1.27) (thickness 0.15)) (justify left bottom))
      )
      (property "Footprint" "kria-k26-devboard-footprints:MSOP-8-1EP_3x3x1.1mm_P0.65mm" (at 35.56 -7.62 0)
        (effects (font (size 1.27 1.27) (thickness 0.15)) (justify left bottom) hide)
      )
      (property "Datasheet" "https://www.diodes.com/assets/Datasheets/PI4MSD5V9540B.pdf" (at 35.56 -10.16 0)
        (effects (font (size 1.27 1.27) (thickness 0.15)) (justify left bottom) hide)
      )
      (property "Manufacturer" "Diodes Incorporated" (at 35.56 -12.7 0)
        (effects (font (size 1.27 1.27) (thickness 0.15)) (justify left bottom) hide)
      )
      (property "MPN" "PI4MSD5V9540BUEX" (at 35.56 -15.24 0)
        (effects (font (size 1.27 1.27) (thickness 0.15)) (justify left bottom) hide)
      )
      (property "Author" "Antmicro" (at 35.56 -17.78 0)
        (effects (font (size 1.27 1.27) (thickness 0.15)) (justify left bottom) hide)
      )
      (property "License" "Apache-2.0" (at 35.56 -20.32 0)
        (effects (font (size 1.27 1.27) (thickness 0.15)) (justify left bottom) hide)
      )
      (property "ki_keywords" "SMT, MUX, IC, I2C" (at 0 0 0)
        (effects (font (size 1.27 1.27)) hide)
      )
      (property "ki_description" "Multiplexer, 2 Channels, 1:2, 1.65 V to 5.5 V, MSOP-8" (at 0 0 0)
        (effects (font (size 1.27 1.27)) hide)
      )
      (symbol "PI4MSD5V9540B_MSOP_1_1"
        (rectangle (start 2.54 -12.7) (end 17.78 2.54)
          (stroke (width 0.254) (type default))
          (fill (type background))
        )
        (pin bidirectional line (at 0 -3.81 0) (length 2.54)
          (name "SCL" (effects (font (size 1.27 1.27))))
          (number "1" (effects (font (size 1.27 1.27))))
        )
        (pin bidirectional line (at 0 -6.35 0) (length 2.54)
          (name "SDA" (effects (font (size 1.27 1.27))))
          (number "2" (effects (font (size 1.27 1.27))))
        )
        (pin bidirectional line (at 0 0 0) (length 2.54)
          (name "VCC" (effects (font (size 1.27 1.27))))
          (number "3" (effects (font (size 1.27 1.27))))
        )
        (pin bidirectional line (at 20.32 -2.54 180) (length 2.54)
          (name "SDA_{0}" (effects (font (size 1.27 1.27))))
          (number "4" (effects (font (size 1.27 1.27))))
        )
        (pin bidirectional line (at 20.32 0 180) (length 2.54)
          (name "SCL_{0}" (effects (font (size 1.27 1.27))))
          (number "5" (effects (font (size 1.27 1.27))))
        )
        (pin bidirectional line (at 0 -10.16 0) (length 2.54)
          (name "GND" (effects (font (size 1.27 1.27))))
          (number "6" (effects (font (size 1.27 1.27))))
        )
        (pin bidirectional line (at 20.32 -10.16 180) (length 2.54)
          (name "SDA_{1}" (effects (font (size 1.27 1.27))))
          (number "7" (effects (font (size 1.27 1.27))))
        )
        (pin bidirectional line (at 20.32 -7.62 180) (length 2.54)
          (name "SCL_{1}" (effects (font (size 1.27 1.27))))
          (number "8" (effects (font (size 1.27 1.27))))
        )
      )
    )
	(symbol "kria-k26-devboard:PJA3441" (pin_names (offset 0)) (in_bom yes) (on_board yes)
      (property "Reference" "Q" (at 20.32 6.35 0)
        (effects (font (size 1.27 1.27) (thickness 0.15)) (justify left bottom))
      )
      (property "Value" "PJA3441" (at 20.32 3.81 0)
        (effects (font (size 1.27 1.27) (thickness 0.15)) (justify left bottom))
      )
      (property "Footprint" "kria-k26-devboard-footprints:SOT-23-3" (at 20.32 1.27 0)
        (effects (font (size 1.27 1.27) (thickness 0.15)) (justify left bottom) hide)
      )
      (property "Datasheet" "https://www.mouser.pl/datasheet/2/1057/PJA3441-1867252.pdf" (at 20.32 -1.27 0)
        (effects (font (size 1.27 1.27) (thickness 0.15)) (justify left bottom) hide)
      )
      (property "Manufacturer" "Panjit" (at 20.32 -3.81 0)
        (effects (font (size 1.27 1.27) (thickness 0.15)) (justify left bottom) hide)
      )
      (property "MPN" "PJA3441_R1_00001" (at 20.32 -6.35 0)
        (effects (font (size 1.27 1.27) (thickness 0.15)) (justify left bottom) hide)
      )
      (property "Author" "Antmicro" (at 20.32 -8.89 0)
        (effects (font (size 1.27 1.27) (thickness 0.15)) (justify left bottom) hide)
      )
      (property "License" "Apache-2.0" (at 20.32 -11.43 0)
        (effects (font (size 1.27 1.27) (thickness 0.15)) (justify left bottom) hide)
      )
      (property "ki_description" "MOSFET 40V P-Channel Enhancement Mode MOSFET" (at 0 0 0)
        (effects (font (size 1.27 1.27)) hide)
      )
      (symbol "PJA3441_1_1"
        (polyline
          (pts
            (xy 5.08 1.143)
            (xy 5.08 0.635)
          )
          (stroke (width 0.254) (type default))
          (fill (type background))
        )
        (polyline
          (pts
            (xy 5.08 1.143)
            (xy 5.08 1.651)
          )
          (stroke (width 0.254) (type default))
          (fill (type background))
        )
        (polyline
          (pts
            (xy 5.08 2.54)
            (xy 5.08 2.032)
          )
          (stroke (width 0.254) (type default))
          (fill (type background))
        )
        (polyline
          (pts
            (xy 5.08 2.54)
            (xy 5.08 3.048)
          )
          (stroke (width 0.254) (type default))
          (fill (type background))
        )
        (polyline
          (pts
            (xy 5.08 4.445)
            (xy 5.08 3.429)
          )
          (stroke (width 0.254) (type default))
          (fill (type background))
        )
        (polyline
          (pts
            (xy 7.62 1.143)
            (xy 5.08 1.143)
          )
          (stroke (width 0.254) (type default))
          (fill (type background))
        )
        (polyline
          (pts
            (xy 9.144 2.2352)
            (xy 8.128 2.2352)
          )
          (stroke (width 0.254) (type default))
          (fill (type background))
        )
        (polyline
          (pts
            (xy 2.54 0)
            (xy 4.572 0)
            (xy 4.572 3.937)
          )
          (stroke (width 0.254) (type default))
          (fill (type none))
        )
        (polyline
          (pts
            (xy 7.62 -1.27)
            (xy 7.62 2.54)
            (xy 5.08 2.54)
          )
          (stroke (width 0.254) (type default))
          (fill (type none))
        )
        (polyline
          (pts
            (xy 7.62 6.35)
            (xy 7.62 3.937)
            (xy 5.08 3.937)
          )
          (stroke (width 0.254) (type default))
          (fill (type none))
        )
        (polyline
          (pts
            (xy 7.239 2.54)
            (xy 6.477 3.048)
            (xy 6.477 2.032)
            (xy 7.239 2.54)
          )
          (stroke (width 0.254) (type default))
          (fill (type outline))
        )
        (polyline
          (pts
            (xy 8.636 2.286)
            (xy 8.128 3.048)
            (xy 9.144 3.048)
            (xy 8.636 2.286)
          )
          (stroke (width 0.254) (type default))
          (fill (type outline))
        )
        (polyline
          (pts
            (xy 7.493 0.635)
            (xy 8.636 0.635)
            (xy 8.636 3.937)
            (xy 8.636 4.445)
            (xy 7.493 4.445)
          )
          (stroke (width 0.254) (type default))
          (fill (type background))
        )
        (circle (center 6.35 2.54) (radius 3.302)
          (stroke (width 0.254) (type default))
          (fill (type background))
        )
        (circle (center 7.62 0.635) (radius 0.127)
          (stroke (width 0.254) (type default))
          (fill (type background))
        )
        (circle (center 7.62 1.143) (radius 0.127)
          (stroke (width 0.254) (type default))
          (fill (type background))
        )
        (circle (center 7.62 4.445) (radius 0.127)
          (stroke (width 0.254) (type default))
          (fill (type background))
        )
        (pin bidirectional line (at 0 0 0) (length 2.54)
          (name "G" (effects (font (size 1.27 1.27))))
          (number "1" (effects (font (size 1.27 1.27))))
        )
        (pin bidirectional line (at 7.62 -3.81 90) (length 2.54)
          (name "S" (effects (font (size 1.27 1.27))))
          (number "2" (effects (font (size 1.27 1.27))))
        )
        (pin bidirectional line (at 7.62 8.89 270) (length 2.54)
          (name "D" (effects (font (size 1.27 1.27))))
          (number "3" (effects (font (size 1.27 1.27))))
        )
      )
    )
	(symbol "kria-k26-devboard:PMEG3010CE_SOD323" (pin_numbers hide) (pin_names hide) (in_bom yes) (on_board yes)
      (property "Reference" "D" (at 22.86 -5.08 0)
        (effects (font (size 1.27 1.27) (thickness 0.15)) (justify left bottom))
      )
      (property "Value" "PMEG3010CE_SOD323" (at 22.86 -7.62 0)
        (effects (font (size 1.27 1.27) (thickness 0.15)) (justify left bottom))
      )
      (property "Footprint" "kria-k26-devboard-footprints:D_SOD-323F" (at 22.86 -10.16 0)
        (effects (font (size 1.27 1.27) (thickness 0.15)) (justify left bottom) hide)
      )
      (property "Datasheet" "https://assets.nexperia.com/documents/data-sheet/PMEG3010CEH_PMEG3010CEJ.pdf" (at 22.86 -12.7 0)
        (effects (font (size 1.27 1.27) (thickness 0.15)) (justify left bottom) hide)
      )
      (property "MPN" "PMEG3010CEJ" (at 22.86 -15.24 0)
        (effects (font (size 1.27 1.27) (thickness 0.15)) (justify left bottom) hide)
      )
      (property "Manufacturer" "Nexperia" (at 22.86 -17.78 0)
        (effects (font (size 1.27 1.27) (thickness 0.15)) (justify left bottom) hide)
      )
      (property "Author" "Antmicro" (at 22.86 -20.32 0)
        (effects (font (size 1.27 1.27) (thickness 0.15)) (justify left bottom) hide)
      )
      (property "License" "Apache-2.0" (at 22.86 -22.86 0)
        (effects (font (size 1.27 1.27) (thickness 0.15)) (justify left bottom) hide)
      )
      (property "ki_keywords" "1 A very low V F MEGA Schottky barrier rectifiers" (at 0 0 0)
        (effects (font (size 1.27 1.27)) hide)
      )
      (property "ki_description" "1 A very low V F MEGA Schottky barrier rectifiers" (at 0 0 0)
        (effects (font (size 1.27 1.27)) hide)
      )
      (symbol "PMEG3010CE_SOD323_1_1"
        (polyline
          (pts
            (xy 4.572 -1.016)
            (xy 4.572 -1.3462)
          )
          (stroke (width 0.254) (type default))
          (fill (type none))
        )
        (polyline
          (pts
            (xy 5.588 1.1938)
            (xy 5.588 0.8128)
          )
          (stroke (width 0.254) (type default))
          (fill (type none))
        )
        (polyline
          (pts
            (xy 2.54 1.27)
            (xy 2.54 -1.27)
            (xy 5.08 0)
            (xy 2.54 1.27)
          )
          (stroke (width 0.254) (type default))
          (fill (type outline))
        )
        (polyline
          (pts
            (xy 5.588 1.1938)
            (xy 5.08 1.1938)
            (xy 5.08 -1.3462)
            (xy 4.572 -1.3462)
          )
          (stroke (width 0.254) (type default))
          (fill (type none))
        )
        (pin passive line (at 0 0 0) (length 2.54)
          (name "A" (effects (font (size 1.27 1.27))))
          (number "A" (effects (font (size 1.27 1.27))))
        )
        (pin passive line (at 7.62 0 180) (length 2.54)
          (name "K" (effects (font (size 1.27 1.27))))
          (number "K" (effects (font (size 1.27 1.27))))
        )
      )
    )
	(symbol "kria-k26-devboard:PMEG3050EP,115" (pin_names hide) (in_bom yes) (on_board yes)
      (property "Reference" "D" (at 21.59 -5.08 0)
        (effects (font (size 1.27 1.27) (thickness 0.15)) (justify left bottom))
      )
      (property "Value" "PMEG3050EP,115" (at 21.59 -7.62 0)
        (effects (font (size 1.27 1.27) (thickness 0.15)) (justify left bottom))
      )
      (property "Footprint" "kria-k26-devboard-footprints:Nexperia_SOD128" (at 21.59 -10.16 0)
        (effects (font (size 1.27 1.27) (thickness 0.15)) (justify left bottom) hide)
      )
      (property "Datasheet" "https://www.mouser.pl/datasheet/2/916/PMEG3050EP-2938519.pdf" (at 21.59 -12.7 0)
        (effects (font (size 1.27 1.27) (thickness 0.15)) (justify left bottom) hide)
      )
      (property "MPN" "PMEG3050EP,115" (at 21.59 -15.24 0)
        (effects (font (size 1.27 1.27) (thickness 0.15)) (justify left bottom) hide)
      )
      (property "Manufacturer" "Nexperia" (at 21.59 -17.78 0)
        (effects (font (size 1.27 1.27) (thickness 0.15)) (justify left bottom) hide)
      )
      (property "Author" "Antmicro" (at 21.59 -20.32 0)
        (effects (font (size 1.27 1.27) (thickness 0.15)) (justify left bottom) hide)
      )
      (property "License" "Apache-2.0" (at 21.59 -22.86 0)
        (effects (font (size 1.27 1.27) (thickness 0.15)) (justify left bottom) hide)
      )
      (property "ki_description" "SCHOTTKY RECT 30V 5A, Vf=315 mV" (at 0 0 0)
        (effects (font (size 1.27 1.27)) hide)
      )
      (symbol "PMEG3050EP,115_0_1"
        (polyline
          (pts
            (xy 3.302 0)
            (xy 1.778 0)
          )
          (stroke (width 0) (type default))
          (fill (type none))
        )
        (polyline
          (pts
            (xy 3.302 1.016)
            (xy 3.302 -1.016)
          )
          (stroke (width 0.254) (type default))
          (fill (type none))
        )
        (polyline
          (pts
            (xy 1.778 1.016)
            (xy 3.302 0)
            (xy 1.778 -1.016)
            (xy 1.778 1.016)
          )
          (stroke (width 0.254) (type default))
          (fill (type outline))
        )
      )
      (symbol "PMEG3050EP,115_1_1"
        (polyline
          (pts
            (xy 3.302 -1.016)
            (xy 3.302 -1.651)
            (xy 3.937 -1.651)
            (xy 3.937 -1.016)
          )
          (stroke (width 0.254) (type default))
          (fill (type none))
        )
        (polyline
          (pts
            (xy 3.302 1.016)
            (xy 3.302 1.651)
            (xy 2.667 1.651)
            (xy 2.667 1.016)
          )
          (stroke (width 0.254) (type default))
          (fill (type none))
        )
        (pin passive line (at 5.08 0 180) (length 1.778)
          (name "1" (effects (font (size 1.27 1.27))))
          (number "1" (effects (font (size 1.27 1.27))))
        )
        (pin passive line (at 0 0 0) (length 1.778)
          (name "2" (effects (font (size 1.27 1.27))))
          (number "2" (effects (font (size 1.27 1.27))))
        )
      )
    )
	(symbol "kria-k26-devboard:PTVS5V0Z1USKP" (pin_numbers hide) (pin_names hide) (in_bom yes) (on_board yes)
      (property "Reference" "D" (at 21.59 -2.54 0)
        (effects (font (size 1.27 1.27) (thickness 0.15)) (justify left bottom))
      )
      (property "Value" "PTVS5V0Z1USKP" (at 21.59 -5.08 0)
        (effects (font (size 1.27 1.27) (thickness 0.15)) (justify left bottom))
      )
      (property "Footprint" "kria-k26-devboard-footprints:SOD-964" (at 21.59 -7.62 0)
        (effects (font (size 1.27 1.27) (thickness 0.15)) (justify left bottom) hide)
      )
      (property "Datasheet" "https://pl.mouser.com/datasheet/2/916/PTVS5V0Z1USKP-1600477.pdf" (at 21.59 -10.16 0)
        (effects (font (size 1.27 1.27) (thickness 0.15)) (justify left bottom) hide)
      )
      (property "Manufacturer" "Nexperia" (at 21.59 -12.7 0)
        (effects (font (size 1.27 1.27) (thickness 0.15)) (justify left bottom) hide)
      )
      (property "MPN" "PTVS5V0Z1USKPYL" (at 21.59 -15.24 0)
        (effects (font (size 1.27 1.27) (thickness 0.15)) (justify left bottom) hide)
      )
      (property "Author" "Antmicro" (at 21.59 -17.78 0)
        (effects (font (size 1.27 1.27) (thickness 0.15)) (justify left bottom) hide)
      )
      (property "License" "Apache-2.0" (at 21.59 -20.32 0)
        (effects (font (size 1.27 1.27) (thickness 0.15)) (justify left bottom) hide)
      )
      (property "ki_keywords" "Transient voltage suppressor in DSN1608-2 for mobile applications" (at 0 0 0)
        (effects (font (size 1.27 1.27)) hide)
      )
      (property "ki_description" "Transient voltage suppressor in DSN1608-2 for mobile applications" (at 0 0 0)
        (effects (font (size 1.27 1.27)) hide)
      )
      (symbol "PTVS5V0Z1USKP_0_1"
        (polyline
          (pts
            (xy 5.715 1.905)
            (xy 5.08 1.27)
            (xy 5.08 -1.27)
            (xy 4.445 -1.905)
          )
          (stroke (width 0.254) (type default))
          (fill (type none))
        )
      )
      (symbol "PTVS5V0Z1USKP_1_1"
        (polyline
          (pts
            (xy 2.54 1.27)
            (xy 2.54 -1.27)
            (xy 5.08 0)
            (xy 2.54 1.27)
          )
          (stroke (width 0.254) (type default))
          (fill (type outline))
        )
        (pin passive line (at 0 0 0) (length 2.54)
          (name "A" (effects (font (size 1.27 1.27))))
          (number "A" (effects (font (size 1.27 1.27))))
        )
        (pin passive line (at 7.62 0 180) (length 2.54)
          (name "K" (effects (font (size 1.27 1.27))))
          (number "K" (effects (font (size 1.27 1.27))))
        )
      )
    )
	(symbol "kria-k26-devboard:PinHeader_1x2_P2.54mm_Drill1.02mm" (in_bom yes) (on_board yes)
      (property "Reference" "J" (at 20.32 -5.08 0)
        (effects (font (size 1.27 1.27) (thickness 0.15)) (justify left bottom))
      )
      (property "Value" "PinHeader_1x2_P2.54mm_Drill1.02mm" (at 20.32 -7.62 0)
        (effects (font (size 1.27 1.27) (thickness 0.15)) (justify left bottom))
      )
      (property "Footprint" "kria-k26-devboard-footprints:PinHeader_1x2_P2.54mm_Drill1.02mm" (at 20.32 -10.16 0)
        (effects (font (size 1.27 1.27) (thickness 0.15)) (justify left bottom) hide)
      )
      (property "Datasheet" "https://www.mouser.pl/datasheet/2/181/M20-999-1218971.pdf" (at 20.32 -12.7 0)
        (effects (font (size 1.27 1.27) (thickness 0.15)) (justify left bottom) hide)
      )
      (property "MPN" "M20-9990246" (at 20.32 -15.24 0)
        (effects (font (size 1.27 1.27) (thickness 0.15)) (justify left bottom) hide)
      )
      (property "Manufacturer" "Harwin" (at 20.32 -17.78 0)
        (effects (font (size 1.27 1.27) (thickness 0.15)) (justify left bottom) hide)
      )
      (property "Author" "Antmicro" (at 20.32 -20.32 0)
        (effects (font (size 1.27 1.27) (thickness 0.15)) (justify left bottom) hide)
      )
      (property "License" "Apache-2.0" (at 20.32 -22.86 0)
        (effects (font (size 1.27 1.27) (thickness 0.15)) (justify left bottom) hide)
      )
      (symbol "PinHeader_1x2_P2.54mm_Drill1.02mm_1_1"
        (rectangle (start 4.191 -2.794) (end 3.683 -2.286)
          (stroke (width 0.254) (type default))
          (fill (type none))
        )
        (rectangle (start 4.191 -0.254) (end 3.683 0.254)
          (stroke (width 0.254) (type default))
          (fill (type none))
        )
        (rectangle (start 5.08 -3.81) (end 2.54 1.27)
          (stroke (width 0.254) (type default))
          (fill (type background))
        )
        (pin passive line (at 0 0 0) (length 2.54)
          (name "~" (effects (font (size 1.27 1.27))))
          (number "1" (effects (font (size 1.27 1.27))))
        )
        (pin passive line (at 0 -2.54 0) (length 2.54)
          (name "~" (effects (font (size 1.27 1.27))))
          (number "2" (effects (font (size 1.27 1.27))))
        )
      )
    )
	(symbol "kria-k26-devboard:PinHeader_2x7_P2mm_Drill1mm_Shrouded" (in_bom yes) (on_board yes)
      (property "Reference" "J" (at 25.4 -2.54 0)
        (effects (font (size 1.27 1.27) (thickness 0.15)) (justify left bottom))
      )
      (property "Value" "PinHeader_2x7_P2mm_Drill1mm_Shrouded" (at 25.4 -5.08 0)
        (effects (font (size 1.27 1.27) (thickness 0.15)) (justify left bottom) hide)
      )
      (property "Footprint" "kria-k26-devboard-footprints:PinHeader_2x7_P2mm_Drill1mm_Shrouded" (at 25.4 -7.62 0)
        (effects (font (size 1.27 1.27) (thickness 0.15)) (justify left bottom) hide)
      )
      (property "Datasheet" "https://www.molex.com/pdm_docs/sd/878322620_sd.pdf" (at 25.4 -10.16 0)
        (effects (font (size 1.27 1.27) (thickness 0.15)) (justify left bottom) hide)
      )
      (property "MPN" "0878311420" (at 25.4 -12.7 0)
        (effects (font (size 1.27 1.27) (thickness 0.15)) (justify left bottom))
      )
      (property "Manufacturer" "Molex" (at 25.4 -15.24 0)
        (effects (font (size 1.27 1.27) (thickness 0.15)) (justify left bottom) hide)
      )
      (property "Author" "Antmicro" (at 25.4 -17.78 0)
        (effects (font (size 1.27 1.27) (thickness 0.15)) (justify left bottom) hide)
      )
      (property "License" "Apache-2.0" (at 25.4 -20.32 0)
        (effects (font (size 1.27 1.27) (thickness 0.15)) (justify left bottom) hide)
      )
      (property "ki_keywords" "PINSTRIP, HEADER " (at 0 0 0)
        (effects (font (size 1.27 1.27)) hide)
      )
      (property "ki_description" "Pin Header, Wire-to-Board, 2 mm, 2 Rows, 14 Contacts, Surface Mount Straight, Milli-Grid 87832" (at 0 0 0)
        (effects (font (size 1.27 1.27)) hide)
      )
      (symbol "PinHeader_2x7_P2mm_Drill1mm_Shrouded_1_1"
        (rectangle (start 2.54 1.27) (end 7.62 -16.51)
          (stroke (width 0.254) (type default))
          (fill (type background))
        )
        (rectangle (start 3.556 -14.986) (end 4.064 -15.494)
          (stroke (width 0.254) (type default))
          (fill (type background))
        )
        (rectangle (start 3.556 -12.446) (end 4.064 -12.954)
          (stroke (width 0.254) (type default))
          (fill (type background))
        )
        (rectangle (start 3.556 -9.906) (end 4.064 -10.414)
          (stroke (width 0.254) (type default))
          (fill (type background))
        )
        (rectangle (start 3.556 -7.366) (end 4.064 -7.874)
          (stroke (width 0.254) (type default))
          (fill (type background))
        )
        (rectangle (start 3.556 -4.826) (end 4.064 -5.334)
          (stroke (width 0.254) (type default))
          (fill (type background))
        )
        (rectangle (start 3.556 -2.286) (end 4.064 -2.794)
          (stroke (width 0.254) (type default))
          (fill (type background))
        )
        (rectangle (start 3.556 0.254) (end 4.064 -0.254)
          (stroke (width 0.254) (type default))
          (fill (type background))
        )
        (rectangle (start 6.096 -14.986) (end 6.604 -15.494)
          (stroke (width 0.254) (type default))
          (fill (type background))
        )
        (rectangle (start 6.096 -12.446) (end 6.604 -12.954)
          (stroke (width 0.254) (type default))
          (fill (type background))
        )
        (rectangle (start 6.096 -9.906) (end 6.604 -10.414)
          (stroke (width 0.254) (type default))
          (fill (type background))
        )
        (rectangle (start 6.096 -7.366) (end 6.604 -7.874)
          (stroke (width 0.254) (type default))
          (fill (type background))
        )
        (rectangle (start 6.096 -4.826) (end 6.604 -5.334)
          (stroke (width 0.254) (type default))
          (fill (type background))
        )
        (rectangle (start 6.096 -2.286) (end 6.604 -2.794)
          (stroke (width 0.254) (type default))
          (fill (type background))
        )
        (rectangle (start 6.096 0.254) (end 6.604 -0.254)
          (stroke (width 0.254) (type default))
          (fill (type background))
        )
        (pin passive line (at 0 0 0) (length 2.54)
          (name "~" (effects (font (size 1.27 1.27))))
          (number "1" (effects (font (size 1.27 1.27))))
        )
        (pin passive line (at 10.16 -10.16 180) (length 2.54)
          (name "~" (effects (font (size 1.27 1.27))))
          (number "10" (effects (font (size 1.27 1.27))))
        )
        (pin passive line (at 0 -12.7 0) (length 2.54)
          (name "~" (effects (font (size 1.27 1.27))))
          (number "11" (effects (font (size 1.27 1.27))))
        )
        (pin passive line (at 10.16 -12.7 180) (length 2.54)
          (name "~" (effects (font (size 1.27 1.27))))
          (number "12" (effects (font (size 1.27 1.27))))
        )
        (pin passive line (at 0 -15.24 0) (length 2.54)
          (name "~" (effects (font (size 1.27 1.27))))
          (number "13" (effects (font (size 1.27 1.27))))
        )
        (pin passive line (at 10.16 -15.24 180) (length 2.54)
          (name "~" (effects (font (size 1.27 1.27))))
          (number "14" (effects (font (size 1.27 1.27))))
        )
        (pin passive line (at 10.16 0 180) (length 2.54)
          (name "~" (effects (font (size 1.27 1.27))))
          (number "2" (effects (font (size 1.27 1.27))))
        )
        (pin passive line (at 0 -2.54 0) (length 2.54)
          (name "~" (effects (font (size 1.27 1.27))))
          (number "3" (effects (font (size 1.27 1.27))))
        )
        (pin passive line (at 10.16 -2.54 180) (length 2.54)
          (name "~" (effects (font (size 1.27 1.27))))
          (number "4" (effects (font (size 1.27 1.27))))
        )
        (pin passive line (at 0 -5.08 0) (length 2.54)
          (name "~" (effects (font (size 1.27 1.27))))
          (number "5" (effects (font (size 1.27 1.27))))
        )
        (pin passive line (at 10.16 -5.08 180) (length 2.54)
          (name "~" (effects (font (size 1.27 1.27))))
          (number "6" (effects (font (size 1.27 1.27))))
        )
        (pin passive line (at 0 -7.62 0) (length 2.54)
          (name "~" (effects (font (size 1.27 1.27))))
          (number "7" (effects (font (size 1.27 1.27))))
        )
        (pin passive line (at 10.16 -7.62 180) (length 2.54)
          (name "~" (effects (font (size 1.27 1.27))))
          (number "8" (effects (font (size 1.27 1.27))))
        )
        (pin passive line (at 0 -10.16 0) (length 2.54)
          (name "~" (effects (font (size 1.27 1.27))))
          (number "9" (effects (font (size 1.27 1.27))))
        )
      )
    )
	(symbol "kria-k26-devboard:PinSocket_2x6_P2.54mm_Drill1.04mm_Horizontal" (in_bom yes) (on_board yes)
      (property "Reference" "J" (at 19.05 0 0)
        (effects (font (size 1.27 1.27) (thickness 0.15)) (justify left bottom))
      )
      (property "Value" "PinSocket_2x6_P2.54mm_Drill1.04mm_Horizontal" (at 19.05 -2.54 0)
        (effects (font (size 1.27 1.27) (thickness 0.15)) (justify left bottom) hide)
      )
      (property "Footprint" "kria-k26-devboard-footprints:PinSocket_2x6_P2.54mm_Drill1.04mm_Horizontal" (at 19.05 -5.08 0)
        (effects (font (size 1.27 1.27) (thickness 0.15)) (justify left bottom) hide)
      )
      (property "Datasheet" "https://suddendocs.samtec.com/prints/ssw-1xx-xx-xxx-x-xx-xxx-xx-mkt.pdf" (at 19.05 -7.62 0)
        (effects (font (size 1.27 1.27) (thickness 0.15)) (justify left bottom) hide)
      )
      (property "MPN" "SSW-106-02-G-D-RA" (at 19.05 -12.7 0)
        (effects (font (size 1.27 1.27) (thickness 0.15)) (justify left bottom))
      )
      (property "Manufacturer" "Samtec" (at 19.05 -10.16 0)
        (effects (font (size 1.27 1.27) (thickness 0.15)) (justify left bottom) hide)
      )
      (property "Author" "Antmicro" (at 19.05 -15.24 0)
        (effects (font (size 1.27 1.27) (thickness 0.15)) (justify left bottom) hide)
      )
      (property "License" "Apache-2.0" (at 19.05 -17.78 0)
        (effects (font (size 1.27 1.27) (thickness 0.15)) (justify left bottom) hide)
      )
      (property "ki_keywords" "CONNECTOR, SOCKET, THT, HORIZONTAL" (at 0 0 0)
        (effects (font (size 1.27 1.27)) hide)
      )
      (property "ki_description" "PCB Receptacle, Board-to-Board, 2.54 mm, 2 Rows, 12 Contacts, Through Hole Mount Right Angle, SSW" (at 0 0 0)
        (effects (font (size 1.27 1.27)) hide)
      )
      (symbol "PinSocket_2x6_P2.54mm_Drill1.04mm_Horizontal_1_1"
        (rectangle (start 2.54 2.54) (end 7.62 -15.24)
          (stroke (width 0.254) (type default))
          (fill (type background))
        )
        (rectangle (start 3.556 -12.446) (end 4.064 -12.954)
          (stroke (width 0.254) (type default))
          (fill (type background))
        )
        (rectangle (start 3.556 -9.906) (end 4.064 -10.414)
          (stroke (width 0.254) (type default))
          (fill (type background))
        )
        (rectangle (start 3.556 -7.366) (end 4.064 -7.874)
          (stroke (width 0.254) (type default))
          (fill (type background))
        )
        (rectangle (start 3.556 -4.826) (end 4.064 -5.334)
          (stroke (width 0.254) (type default))
          (fill (type background))
        )
        (rectangle (start 3.556 -2.286) (end 4.064 -2.794)
          (stroke (width 0.254) (type default))
          (fill (type background))
        )
        (rectangle (start 3.556 0.254) (end 4.064 -0.254)
          (stroke (width 0.254) (type default))
          (fill (type background))
        )
        (rectangle (start 6.096 -12.446) (end 6.604 -12.954)
          (stroke (width 0.254) (type default))
          (fill (type background))
        )
        (rectangle (start 6.096 -9.906) (end 6.604 -10.414)
          (stroke (width 0.254) (type default))
          (fill (type background))
        )
        (rectangle (start 6.096 -7.366) (end 6.604 -7.874)
          (stroke (width 0.254) (type default))
          (fill (type background))
        )
        (rectangle (start 6.096 -4.826) (end 6.604 -5.334)
          (stroke (width 0.254) (type default))
          (fill (type background))
        )
        (rectangle (start 6.096 -2.286) (end 6.604 -2.794)
          (stroke (width 0.254) (type default))
          (fill (type background))
        )
        (rectangle (start 6.096 0.254) (end 6.604 -0.254)
          (stroke (width 0.254) (type default))
          (fill (type background))
        )
        (pin passive line (at 0 0 0) (length 2.54)
          (name "~" (effects (font (size 1.27 1.27))))
          (number "1" (effects (font (size 1.27 1.27))))
        )
        (pin passive line (at 10.16 -10.16 180) (length 2.54)
          (name "~" (effects (font (size 1.27 1.27))))
          (number "10" (effects (font (size 1.27 1.27))))
        )
        (pin passive line (at 0 -12.7 0) (length 2.54)
          (name "~" (effects (font (size 1.27 1.27))))
          (number "11" (effects (font (size 1.27 1.27))))
        )
        (pin passive line (at 10.16 -12.7 180) (length 2.54)
          (name "~" (effects (font (size 1.27 1.27))))
          (number "12" (effects (font (size 1.27 1.27))))
        )
        (pin passive line (at 10.16 0 180) (length 2.54)
          (name "~" (effects (font (size 1.27 1.27))))
          (number "2" (effects (font (size 1.27 1.27))))
        )
        (pin passive line (at 0 -2.54 0) (length 2.54)
          (name "~" (effects (font (size 1.27 1.27))))
          (number "3" (effects (font (size 1.27 1.27))))
        )
        (pin passive line (at 10.16 -2.54 180) (length 2.54)
          (name "~" (effects (font (size 1.27 1.27))))
          (number "4" (effects (font (size 1.27 1.27))))
        )
        (pin passive line (at 0 -5.08 0) (length 2.54)
          (name "~" (effects (font (size 1.27 1.27))))
          (number "5" (effects (font (size 1.27 1.27))))
        )
        (pin passive line (at 10.16 -5.08 180) (length 2.54)
          (name "~" (effects (font (size 1.27 1.27))))
          (number "6" (effects (font (size 1.27 1.27))))
        )
        (pin passive line (at 0 -7.62 0) (length 2.54)
          (name "~" (effects (font (size 1.27 1.27))))
          (number "7" (effects (font (size 1.27 1.27))))
        )
        (pin passive line (at 10.16 -7.62 180) (length 2.54)
          (name "~" (effects (font (size 1.27 1.27))))
          (number "8" (effects (font (size 1.27 1.27))))
        )
        (pin passive line (at 0 -10.16 0) (length 2.54)
          (name "~" (effects (font (size 1.27 1.27))))
          (number "9" (effects (font (size 1.27 1.27))))
        )
      )
    )
	(symbol "kria-k26-devboard:Plug_Samtec_ADM6_4x60_ADM6-60-01.5-L-4-2-A-TR" (in_bom yes) (on_board yes)
      (property "Reference" "J" (at 43.18 -2.54 0)
        (effects (font (size 1.27 1.27) (thickness 0.15)) (justify left bottom))
      )
      (property "Value" "ADM6-60-01.5-L-4-2-A-TR" (at 43.18 -5.08 0)
        (effects (font (size 1.27 1.27) (thickness 0.15)) (justify left bottom))
      )
      (property "Footprint" "kria-k26-devboard-footprints:Conn_Plug_Samtec_ADM6_4x60_ADM6-60-01.5-L-4-2-A-TR" (at 43.18 -7.62 0)
        (effects (font (size 1.27 1.27) (thickness 0.15)) (justify left bottom) hide)
      )
      (property "Datasheet" "https://suddendocs.samtec.com/catalog_english/adm6.pdf?_gl=1*bo1jwj*_ga*MTc4NzA2NDkyLjE2NjQ4NzY0OTY.*_ga_3KFNZC07WW*MTY3ODg4NTY3MS4xMC4wLjE2Nzg4ODU2NzEuNjAuMC4w" (at 43.18 -10.16 0)
        (effects (font (size 1.27 1.27) (thickness 0.15)) (justify left bottom) hide)
      )
      (property "Manufacturer" "Samtec" (at 43.18 -12.7 0)
        (effects (font (size 1.27 1.27) (thickness 0.15)) (justify left bottom) hide)
      )
      (property "MPN" "ADM6-60-01.5-L-4-2-A-TR" (at 43.18 -15.24 0)
        (effects (font (size 1.27 1.27) (thickness 0.15)) (justify left bottom) hide)
      )
      (property "Author" "Antmicro" (at 43.18 -17.78 0)
        (effects (font (size 1.27 1.27) (thickness 0.15)) (justify left bottom) hide)
      )
      (property "License" "Apache-2.0" (at 43.18 -20.32 0)
        (effects (font (size 1.27 1.27) (thickness 0.15)) (justify left bottom) hide)
      )
      (property "ki_locked" "" (at 0 0 0)
        (effects (font (size 1.27 1.27)))
      )
      (property "ki_description" "Board to Board & Mezzanine Connectors 0.635 mm AcceleRate HD High-Density 4-Row Header 60P" (at 0 0 0)
        (effects (font (size 1.27 1.27)) hide)
      )
      (symbol "Plug_Samtec_ADM6_4x60_ADM6-60-01.5-L-4-2-A-TR_1_1"
        (rectangle (start 3.81 -152.4) (end 24.13 2.54)
          (stroke (width 0.254) (type default))
          (fill (type background))
        )
        (rectangle (start 11.43 -149.225) (end 10.795 -150.495)
          (stroke (width 0.254) (type default))
          (fill (type outline))
        )
        (rectangle (start 11.43 -146.685) (end 10.795 -147.955)
          (stroke (width 0.254) (type default))
          (fill (type outline))
        )
        (rectangle (start 11.43 -144.145) (end 10.795 -145.415)
          (stroke (width 0.254) (type default))
          (fill (type outline))
        )
        (rectangle (start 11.43 -141.605) (end 10.795 -142.875)
          (stroke (width 0.254) (type default))
          (fill (type outline))
        )
        (rectangle (start 11.43 -139.065) (end 10.795 -140.335)
          (stroke (width 0.254) (type default))
          (fill (type outline))
        )
        (rectangle (start 11.43 -136.525) (end 10.795 -137.795)
          (stroke (width 0.254) (type default))
          (fill (type outline))
        )
        (rectangle (start 11.43 -133.985) (end 10.795 -135.255)
          (stroke (width 0.254) (type default))
          (fill (type outline))
        )
        (rectangle (start 11.43 -131.445) (end 10.795 -132.715)
          (stroke (width 0.254) (type default))
          (fill (type outline))
        )
        (rectangle (start 11.43 -128.905) (end 10.795 -130.175)
          (stroke (width 0.254) (type default))
          (fill (type outline))
        )
        (rectangle (start 11.43 -126.365) (end 10.795 -127.635)
          (stroke (width 0.254) (type default))
          (fill (type outline))
        )
        (rectangle (start 11.43 -123.825) (end 10.795 -125.095)
          (stroke (width 0.254) (type default))
          (fill (type outline))
        )
        (rectangle (start 11.43 -121.285) (end 10.795 -122.555)
          (stroke (width 0.254) (type default))
          (fill (type outline))
        )
        (rectangle (start 11.43 -118.745) (end 10.795 -120.015)
          (stroke (width 0.254) (type default))
          (fill (type outline))
        )
        (rectangle (start 11.43 -116.205) (end 10.795 -117.475)
          (stroke (width 0.254) (type default))
          (fill (type outline))
        )
        (rectangle (start 11.43 -113.665) (end 10.795 -114.935)
          (stroke (width 0.254) (type default))
          (fill (type outline))
        )
        (rectangle (start 11.43 -111.125) (end 10.795 -112.395)
          (stroke (width 0.254) (type default))
          (fill (type outline))
        )
        (rectangle (start 11.43 -108.585) (end 10.795 -109.855)
          (stroke (width 0.254) (type default))
          (fill (type outline))
        )
        (rectangle (start 11.43 -106.045) (end 10.795 -107.315)
          (stroke (width 0.254) (type default))
          (fill (type outline))
        )
        (rectangle (start 11.43 -103.505) (end 10.795 -104.775)
          (stroke (width 0.254) (type default))
          (fill (type outline))
        )
        (rectangle (start 11.43 -100.965) (end 10.795 -102.235)
          (stroke (width 0.254) (type default))
          (fill (type outline))
        )
        (rectangle (start 11.43 -98.425) (end 10.795 -99.695)
          (stroke (width 0.254) (type default))
          (fill (type outline))
        )
        (rectangle (start 11.43 -95.885) (end 10.795 -97.155)
          (stroke (width 0.254) (type default))
          (fill (type outline))
        )
        (rectangle (start 11.43 -93.345) (end 10.795 -94.615)
          (stroke (width 0.254) (type default))
          (fill (type outline))
        )
        (rectangle (start 11.43 -90.805) (end 10.795 -92.075)
          (stroke (width 0.254) (type default))
          (fill (type outline))
        )
        (rectangle (start 11.43 -88.265) (end 10.795 -89.535)
          (stroke (width 0.254) (type default))
          (fill (type outline))
        )
        (rectangle (start 11.43 -85.725) (end 10.795 -86.995)
          (stroke (width 0.254) (type default))
          (fill (type outline))
        )
        (rectangle (start 11.43 -83.185) (end 10.795 -84.455)
          (stroke (width 0.254) (type default))
          (fill (type outline))
        )
        (rectangle (start 11.43 -80.645) (end 10.795 -81.915)
          (stroke (width 0.254) (type default))
          (fill (type outline))
        )
        (rectangle (start 11.43 -78.105) (end 10.795 -79.375)
          (stroke (width 0.254) (type default))
          (fill (type outline))
        )
        (rectangle (start 11.43 -75.565) (end 10.795 -76.835)
          (stroke (width 0.254) (type default))
          (fill (type outline))
        )
        (rectangle (start 11.43 -73.025) (end 10.795 -74.295)
          (stroke (width 0.254) (type default))
          (fill (type outline))
        )
        (rectangle (start 11.43 -70.485) (end 10.795 -71.755)
          (stroke (width 0.254) (type default))
          (fill (type outline))
        )
        (rectangle (start 11.43 -67.945) (end 10.795 -69.215)
          (stroke (width 0.254) (type default))
          (fill (type outline))
        )
        (rectangle (start 11.43 -65.405) (end 10.795 -66.675)
          (stroke (width 0.254) (type default))
          (fill (type outline))
        )
        (rectangle (start 11.43 -62.865) (end 10.795 -64.135)
          (stroke (width 0.254) (type default))
          (fill (type outline))
        )
        (rectangle (start 11.43 -60.325) (end 10.795 -61.595)
          (stroke (width 0.254) (type default))
          (fill (type outline))
        )
        (rectangle (start 11.43 -57.785) (end 10.795 -59.055)
          (stroke (width 0.254) (type default))
          (fill (type outline))
        )
        (rectangle (start 11.43 -55.245) (end 10.795 -56.515)
          (stroke (width 0.254) (type default))
          (fill (type outline))
        )
        (rectangle (start 11.43 -52.705) (end 10.795 -53.975)
          (stroke (width 0.254) (type default))
          (fill (type outline))
        )
        (rectangle (start 11.43 -50.165) (end 10.795 -51.435)
          (stroke (width 0.254) (type default))
          (fill (type outline))
        )
        (rectangle (start 11.43 -47.625) (end 10.795 -48.895)
          (stroke (width 0.254) (type default))
          (fill (type outline))
        )
        (rectangle (start 11.43 -45.085) (end 10.795 -46.355)
          (stroke (width 0.254) (type default))
          (fill (type outline))
        )
        (rectangle (start 11.43 -42.545) (end 10.795 -43.815)
          (stroke (width 0.254) (type default))
          (fill (type outline))
        )
        (rectangle (start 11.43 -40.005) (end 10.795 -41.275)
          (stroke (width 0.254) (type default))
          (fill (type outline))
        )
        (rectangle (start 11.43 -37.465) (end 10.795 -38.735)
          (stroke (width 0.254) (type default))
          (fill (type outline))
        )
        (rectangle (start 11.43 -34.925) (end 10.795 -36.195)
          (stroke (width 0.254) (type default))
          (fill (type outline))
        )
        (rectangle (start 11.43 -32.385) (end 10.795 -33.655)
          (stroke (width 0.254) (type default))
          (fill (type outline))
        )
        (rectangle (start 11.43 -29.845) (end 10.795 -31.115)
          (stroke (width 0.254) (type default))
          (fill (type outline))
        )
        (rectangle (start 11.43 -27.305) (end 10.795 -28.575)
          (stroke (width 0.254) (type default))
          (fill (type outline))
        )
        (rectangle (start 11.43 -24.765) (end 10.795 -26.035)
          (stroke (width 0.254) (type default))
          (fill (type outline))
        )
        (rectangle (start 11.43 -22.225) (end 10.795 -23.495)
          (stroke (width 0.254) (type default))
          (fill (type outline))
        )
        (rectangle (start 11.43 -19.685) (end 10.795 -20.955)
          (stroke (width 0.254) (type default))
          (fill (type outline))
        )
        (rectangle (start 11.43 -17.145) (end 10.795 -18.415)
          (stroke (width 0.254) (type default))
          (fill (type outline))
        )
        (rectangle (start 11.43 -14.605) (end 10.795 -15.875)
          (stroke (width 0.254) (type default))
          (fill (type outline))
        )
        (rectangle (start 11.43 -12.065) (end 10.795 -13.335)
          (stroke (width 0.254) (type default))
          (fill (type outline))
        )
        (rectangle (start 11.43 -9.525) (end 10.795 -10.795)
          (stroke (width 0.254) (type default))
          (fill (type outline))
        )
        (rectangle (start 11.43 -6.985) (end 10.795 -8.255)
          (stroke (width 0.254) (type default))
          (fill (type outline))
        )
        (rectangle (start 11.43 -4.445) (end 10.795 -5.715)
          (stroke (width 0.254) (type default))
          (fill (type outline))
        )
        (rectangle (start 11.43 -1.905) (end 10.795 -3.175)
          (stroke (width 0.254) (type default))
          (fill (type outline))
        )
        (rectangle (start 11.43 0.635) (end 10.795 -0.635)
          (stroke (width 0.254) (type default))
          (fill (type outline))
        )
        (rectangle (start 11.43 1.27) (end 16.51 -151.13)
          (stroke (width 0.254) (type default))
          (fill (type background))
        )
        (rectangle (start 17.145 -149.225) (end 16.51 -150.495)
          (stroke (width 0.254) (type default))
          (fill (type outline))
        )
        (rectangle (start 17.145 -146.685) (end 16.51 -147.955)
          (stroke (width 0.254) (type default))
          (fill (type outline))
        )
        (rectangle (start 17.145 -144.145) (end 16.51 -145.415)
          (stroke (width 0.254) (type default))
          (fill (type outline))
        )
        (rectangle (start 17.145 -141.605) (end 16.51 -142.875)
          (stroke (width 0.254) (type default))
          (fill (type outline))
        )
        (rectangle (start 17.145 -139.065) (end 16.51 -140.335)
          (stroke (width 0.254) (type default))
          (fill (type outline))
        )
        (rectangle (start 17.145 -136.525) (end 16.51 -137.795)
          (stroke (width 0.254) (type default))
          (fill (type outline))
        )
        (rectangle (start 17.145 -133.985) (end 16.51 -135.255)
          (stroke (width 0.254) (type default))
          (fill (type outline))
        )
        (rectangle (start 17.145 -131.445) (end 16.51 -132.715)
          (stroke (width 0.254) (type default))
          (fill (type outline))
        )
        (rectangle (start 17.145 -128.905) (end 16.51 -130.175)
          (stroke (width 0.254) (type default))
          (fill (type outline))
        )
        (rectangle (start 17.145 -126.365) (end 16.51 -127.635)
          (stroke (width 0.254) (type default))
          (fill (type outline))
        )
        (rectangle (start 17.145 -123.825) (end 16.51 -125.095)
          (stroke (width 0.254) (type default))
          (fill (type outline))
        )
        (rectangle (start 17.145 -121.285) (end 16.51 -122.555)
          (stroke (width 0.254) (type default))
          (fill (type outline))
        )
        (rectangle (start 17.145 -118.745) (end 16.51 -120.015)
          (stroke (width 0.254) (type default))
          (fill (type outline))
        )
        (rectangle (start 17.145 -116.205) (end 16.51 -117.475)
          (stroke (width 0.254) (type default))
          (fill (type outline))
        )
        (rectangle (start 17.145 -113.665) (end 16.51 -114.935)
          (stroke (width 0.254) (type default))
          (fill (type outline))
        )
        (rectangle (start 17.145 -111.125) (end 16.51 -112.395)
          (stroke (width 0.254) (type default))
          (fill (type outline))
        )
        (rectangle (start 17.145 -108.585) (end 16.51 -109.855)
          (stroke (width 0.254) (type default))
          (fill (type outline))
        )
        (rectangle (start 17.145 -106.045) (end 16.51 -107.315)
          (stroke (width 0.254) (type default))
          (fill (type outline))
        )
        (rectangle (start 17.145 -103.505) (end 16.51 -104.775)
          (stroke (width 0.254) (type default))
          (fill (type outline))
        )
        (rectangle (start 17.145 -100.965) (end 16.51 -102.235)
          (stroke (width 0.254) (type default))
          (fill (type outline))
        )
        (rectangle (start 17.145 -98.425) (end 16.51 -99.695)
          (stroke (width 0.254) (type default))
          (fill (type outline))
        )
        (rectangle (start 17.145 -95.885) (end 16.51 -97.155)
          (stroke (width 0.254) (type default))
          (fill (type outline))
        )
        (rectangle (start 17.145 -93.345) (end 16.51 -94.615)
          (stroke (width 0.254) (type default))
          (fill (type outline))
        )
        (rectangle (start 17.145 -90.805) (end 16.51 -92.075)
          (stroke (width 0.254) (type default))
          (fill (type outline))
        )
        (rectangle (start 17.145 -88.265) (end 16.51 -89.535)
          (stroke (width 0.254) (type default))
          (fill (type outline))
        )
        (rectangle (start 17.145 -85.725) (end 16.51 -86.995)
          (stroke (width 0.254) (type default))
          (fill (type outline))
        )
        (rectangle (start 17.145 -83.185) (end 16.51 -84.455)
          (stroke (width 0.254) (type default))
          (fill (type outline))
        )
        (rectangle (start 17.145 -80.645) (end 16.51 -81.915)
          (stroke (width 0.254) (type default))
          (fill (type outline))
        )
        (rectangle (start 17.145 -78.105) (end 16.51 -79.375)
          (stroke (width 0.254) (type default))
          (fill (type outline))
        )
        (rectangle (start 17.145 -75.565) (end 16.51 -76.835)
          (stroke (width 0.254) (type default))
          (fill (type outline))
        )
        (rectangle (start 17.145 -73.025) (end 16.51 -74.295)
          (stroke (width 0.254) (type default))
          (fill (type outline))
        )
        (rectangle (start 17.145 -70.485) (end 16.51 -71.755)
          (stroke (width 0.254) (type default))
          (fill (type outline))
        )
        (rectangle (start 17.145 -67.945) (end 16.51 -69.215)
          (stroke (width 0.254) (type default))
          (fill (type outline))
        )
        (rectangle (start 17.145 -65.405) (end 16.51 -66.675)
          (stroke (width 0.254) (type default))
          (fill (type outline))
        )
        (rectangle (start 17.145 -62.865) (end 16.51 -64.135)
          (stroke (width 0.254) (type default))
          (fill (type outline))
        )
        (rectangle (start 17.145 -60.325) (end 16.51 -61.595)
          (stroke (width 0.254) (type default))
          (fill (type outline))
        )
        (rectangle (start 17.145 -57.785) (end 16.51 -59.055)
          (stroke (width 0.254) (type default))
          (fill (type outline))
        )
        (rectangle (start 17.145 -55.245) (end 16.51 -56.515)
          (stroke (width 0.254) (type default))
          (fill (type outline))
        )
        (rectangle (start 17.145 -52.705) (end 16.51 -53.975)
          (stroke (width 0.254) (type default))
          (fill (type outline))
        )
        (rectangle (start 17.145 -50.165) (end 16.51 -51.435)
          (stroke (width 0.254) (type default))
          (fill (type outline))
        )
        (rectangle (start 17.145 -47.625) (end 16.51 -48.895)
          (stroke (width 0.254) (type default))
          (fill (type outline))
        )
        (rectangle (start 17.145 -45.085) (end 16.51 -46.355)
          (stroke (width 0.254) (type default))
          (fill (type outline))
        )
        (rectangle (start 17.145 -42.545) (end 16.51 -43.815)
          (stroke (width 0.254) (type default))
          (fill (type outline))
        )
        (rectangle (start 17.145 -40.005) (end 16.51 -41.275)
          (stroke (width 0.254) (type default))
          (fill (type outline))
        )
        (rectangle (start 17.145 -37.465) (end 16.51 -38.735)
          (stroke (width 0.254) (type default))
          (fill (type outline))
        )
        (rectangle (start 17.145 -34.925) (end 16.51 -36.195)
          (stroke (width 0.254) (type default))
          (fill (type outline))
        )
        (rectangle (start 17.145 -32.385) (end 16.51 -33.655)
          (stroke (width 0.254) (type default))
          (fill (type outline))
        )
        (rectangle (start 17.145 -29.845) (end 16.51 -31.115)
          (stroke (width 0.254) (type default))
          (fill (type outline))
        )
        (rectangle (start 17.145 -27.305) (end 16.51 -28.575)
          (stroke (width 0.254) (type default))
          (fill (type outline))
        )
        (rectangle (start 17.145 -24.765) (end 16.51 -26.035)
          (stroke (width 0.254) (type default))
          (fill (type outline))
        )
        (rectangle (start 17.145 -22.225) (end 16.51 -23.495)
          (stroke (width 0.254) (type default))
          (fill (type outline))
        )
        (rectangle (start 17.145 -19.685) (end 16.51 -20.955)
          (stroke (width 0.254) (type default))
          (fill (type outline))
        )
        (rectangle (start 17.145 -17.145) (end 16.51 -18.415)
          (stroke (width 0.254) (type default))
          (fill (type outline))
        )
        (rectangle (start 17.145 -14.605) (end 16.51 -15.875)
          (stroke (width 0.254) (type default))
          (fill (type outline))
        )
        (rectangle (start 17.145 -12.065) (end 16.51 -13.335)
          (stroke (width 0.254) (type default))
          (fill (type outline))
        )
        (rectangle (start 17.145 -9.525) (end 16.51 -10.795)
          (stroke (width 0.254) (type default))
          (fill (type outline))
        )
        (rectangle (start 17.145 -6.985) (end 16.51 -8.255)
          (stroke (width 0.254) (type default))
          (fill (type outline))
        )
        (rectangle (start 17.145 -4.445) (end 16.51 -5.715)
          (stroke (width 0.254) (type default))
          (fill (type outline))
        )
        (rectangle (start 17.145 -1.905) (end 16.51 -3.175)
          (stroke (width 0.254) (type default))
          (fill (type outline))
        )
        (rectangle (start 17.145 0.635) (end 16.51 -0.635)
          (stroke (width 0.254) (type default))
          (fill (type outline))
        )
        (pin passive line (at 0 0 0) (length 3.81)
          (name "A01" (effects (font (size 1.27 1.27))))
          (number "A01" (effects (font (size 1.27 1.27))))
        )
        (pin passive line (at 0 -2.54 0) (length 3.81)
          (name "A02" (effects (font (size 1.27 1.27))))
          (number "A02" (effects (font (size 1.27 1.27))))
        )
        (pin passive line (at 0 -5.08 0) (length 3.81)
          (name "A03" (effects (font (size 1.27 1.27))))
          (number "A03" (effects (font (size 1.27 1.27))))
        )
        (pin passive line (at 0 -7.62 0) (length 3.81)
          (name "A04" (effects (font (size 1.27 1.27))))
          (number "A04" (effects (font (size 1.27 1.27))))
        )
        (pin passive line (at 0 -10.16 0) (length 3.81)
          (name "A05" (effects (font (size 1.27 1.27))))
          (number "A05" (effects (font (size 1.27 1.27))))
        )
        (pin passive line (at 0 -12.7 0) (length 3.81)
          (name "A06" (effects (font (size 1.27 1.27))))
          (number "A06" (effects (font (size 1.27 1.27))))
        )
        (pin passive line (at 0 -15.24 0) (length 3.81)
          (name "A07" (effects (font (size 1.27 1.27))))
          (number "A07" (effects (font (size 1.27 1.27))))
        )
        (pin passive line (at 0 -17.78 0) (length 3.81)
          (name "A08" (effects (font (size 1.27 1.27))))
          (number "A08" (effects (font (size 1.27 1.27))))
        )
        (pin passive line (at 0 -20.32 0) (length 3.81)
          (name "A09" (effects (font (size 1.27 1.27))))
          (number "A09" (effects (font (size 1.27 1.27))))
        )
        (pin passive line (at 0 -22.86 0) (length 3.81)
          (name "A10" (effects (font (size 1.27 1.27))))
          (number "A10" (effects (font (size 1.27 1.27))))
        )
        (pin passive line (at 0 -25.4 0) (length 3.81)
          (name "A11" (effects (font (size 1.27 1.27))))
          (number "A11" (effects (font (size 1.27 1.27))))
        )
        (pin passive line (at 0 -27.94 0) (length 3.81)
          (name "A12" (effects (font (size 1.27 1.27))))
          (number "A12" (effects (font (size 1.27 1.27))))
        )
        (pin passive line (at 0 -30.48 0) (length 3.81)
          (name "A13" (effects (font (size 1.27 1.27))))
          (number "A13" (effects (font (size 1.27 1.27))))
        )
        (pin passive line (at 0 -33.02 0) (length 3.81)
          (name "A14" (effects (font (size 1.27 1.27))))
          (number "A14" (effects (font (size 1.27 1.27))))
        )
        (pin passive line (at 0 -35.56 0) (length 3.81)
          (name "A15" (effects (font (size 1.27 1.27))))
          (number "A15" (effects (font (size 1.27 1.27))))
        )
        (pin passive line (at 0 -38.1 0) (length 3.81)
          (name "A16" (effects (font (size 1.27 1.27))))
          (number "A16" (effects (font (size 1.27 1.27))))
        )
        (pin passive line (at 0 -40.64 0) (length 3.81)
          (name "A17" (effects (font (size 1.27 1.27))))
          (number "A17" (effects (font (size 1.27 1.27))))
        )
        (pin passive line (at 0 -43.18 0) (length 3.81)
          (name "A18" (effects (font (size 1.27 1.27))))
          (number "A18" (effects (font (size 1.27 1.27))))
        )
        (pin passive line (at 0 -45.72 0) (length 3.81)
          (name "A19" (effects (font (size 1.27 1.27))))
          (number "A19" (effects (font (size 1.27 1.27))))
        )
        (pin passive line (at 0 -48.26 0) (length 3.81)
          (name "A20" (effects (font (size 1.27 1.27))))
          (number "A20" (effects (font (size 1.27 1.27))))
        )
        (pin passive line (at 0 -50.8 0) (length 3.81)
          (name "A21" (effects (font (size 1.27 1.27))))
          (number "A21" (effects (font (size 1.27 1.27))))
        )
        (pin passive line (at 0 -53.34 0) (length 3.81)
          (name "A22" (effects (font (size 1.27 1.27))))
          (number "A22" (effects (font (size 1.27 1.27))))
        )
        (pin passive line (at 0 -55.88 0) (length 3.81)
          (name "A23" (effects (font (size 1.27 1.27))))
          (number "A23" (effects (font (size 1.27 1.27))))
        )
        (pin passive line (at 0 -58.42 0) (length 3.81)
          (name "A24" (effects (font (size 1.27 1.27))))
          (number "A24" (effects (font (size 1.27 1.27))))
        )
        (pin passive line (at 0 -60.96 0) (length 3.81)
          (name "A25" (effects (font (size 1.27 1.27))))
          (number "A25" (effects (font (size 1.27 1.27))))
        )
        (pin passive line (at 0 -63.5 0) (length 3.81)
          (name "A26" (effects (font (size 1.27 1.27))))
          (number "A26" (effects (font (size 1.27 1.27))))
        )
        (pin passive line (at 0 -66.04 0) (length 3.81)
          (name "A27" (effects (font (size 1.27 1.27))))
          (number "A27" (effects (font (size 1.27 1.27))))
        )
        (pin passive line (at 0 -68.58 0) (length 3.81)
          (name "A28" (effects (font (size 1.27 1.27))))
          (number "A28" (effects (font (size 1.27 1.27))))
        )
        (pin passive line (at 0 -71.12 0) (length 3.81)
          (name "A29" (effects (font (size 1.27 1.27))))
          (number "A29" (effects (font (size 1.27 1.27))))
        )
        (pin passive line (at 0 -73.66 0) (length 3.81)
          (name "A30" (effects (font (size 1.27 1.27))))
          (number "A30" (effects (font (size 1.27 1.27))))
        )
        (pin passive line (at 0 -76.2 0) (length 3.81)
          (name "A31" (effects (font (size 1.27 1.27))))
          (number "A31" (effects (font (size 1.27 1.27))))
        )
        (pin passive line (at 0 -78.74 0) (length 3.81)
          (name "A32" (effects (font (size 1.27 1.27))))
          (number "A32" (effects (font (size 1.27 1.27))))
        )
        (pin passive line (at 0 -81.28 0) (length 3.81)
          (name "A33" (effects (font (size 1.27 1.27))))
          (number "A33" (effects (font (size 1.27 1.27))))
        )
        (pin passive line (at 0 -83.82 0) (length 3.81)
          (name "A34" (effects (font (size 1.27 1.27))))
          (number "A34" (effects (font (size 1.27 1.27))))
        )
        (pin passive line (at 0 -86.36 0) (length 3.81)
          (name "A35" (effects (font (size 1.27 1.27))))
          (number "A35" (effects (font (size 1.27 1.27))))
        )
        (pin passive line (at 0 -88.9 0) (length 3.81)
          (name "A36" (effects (font (size 1.27 1.27))))
          (number "A36" (effects (font (size 1.27 1.27))))
        )
        (pin passive line (at 0 -91.44 0) (length 3.81)
          (name "A37" (effects (font (size 1.27 1.27))))
          (number "A37" (effects (font (size 1.27 1.27))))
        )
        (pin passive line (at 0 -93.98 0) (length 3.81)
          (name "A38" (effects (font (size 1.27 1.27))))
          (number "A38" (effects (font (size 1.27 1.27))))
        )
        (pin passive line (at 0 -96.52 0) (length 3.81)
          (name "A39" (effects (font (size 1.27 1.27))))
          (number "A39" (effects (font (size 1.27 1.27))))
        )
        (pin passive line (at 0 -99.06 0) (length 3.81)
          (name "A40" (effects (font (size 1.27 1.27))))
          (number "A40" (effects (font (size 1.27 1.27))))
        )
        (pin passive line (at 0 -101.6 0) (length 3.81)
          (name "A41" (effects (font (size 1.27 1.27))))
          (number "A41" (effects (font (size 1.27 1.27))))
        )
        (pin passive line (at 0 -104.14 0) (length 3.81)
          (name "A42" (effects (font (size 1.27 1.27))))
          (number "A42" (effects (font (size 1.27 1.27))))
        )
        (pin passive line (at 0 -106.68 0) (length 3.81)
          (name "A43" (effects (font (size 1.27 1.27))))
          (number "A43" (effects (font (size 1.27 1.27))))
        )
        (pin passive line (at 0 -109.22 0) (length 3.81)
          (name "A44" (effects (font (size 1.27 1.27))))
          (number "A44" (effects (font (size 1.27 1.27))))
        )
        (pin passive line (at 0 -111.76 0) (length 3.81)
          (name "A45" (effects (font (size 1.27 1.27))))
          (number "A45" (effects (font (size 1.27 1.27))))
        )
        (pin passive line (at 0 -114.3 0) (length 3.81)
          (name "A46" (effects (font (size 1.27 1.27))))
          (number "A46" (effects (font (size 1.27 1.27))))
        )
        (pin passive line (at 0 -116.84 0) (length 3.81)
          (name "A47" (effects (font (size 1.27 1.27))))
          (number "A47" (effects (font (size 1.27 1.27))))
        )
        (pin passive line (at 0 -119.38 0) (length 3.81)
          (name "A48" (effects (font (size 1.27 1.27))))
          (number "A48" (effects (font (size 1.27 1.27))))
        )
        (pin passive line (at 0 -121.92 0) (length 3.81)
          (name "A49" (effects (font (size 1.27 1.27))))
          (number "A49" (effects (font (size 1.27 1.27))))
        )
        (pin passive line (at 0 -124.46 0) (length 3.81)
          (name "A50" (effects (font (size 1.27 1.27))))
          (number "A50" (effects (font (size 1.27 1.27))))
        )
        (pin passive line (at 0 -127 0) (length 3.81)
          (name "A51" (effects (font (size 1.27 1.27))))
          (number "A51" (effects (font (size 1.27 1.27))))
        )
        (pin passive line (at 0 -129.54 0) (length 3.81)
          (name "A52" (effects (font (size 1.27 1.27))))
          (number "A52" (effects (font (size 1.27 1.27))))
        )
        (pin passive line (at 0 -132.08 0) (length 3.81)
          (name "A53" (effects (font (size 1.27 1.27))))
          (number "A53" (effects (font (size 1.27 1.27))))
        )
        (pin passive line (at 0 -134.62 0) (length 3.81)
          (name "A54" (effects (font (size 1.27 1.27))))
          (number "A54" (effects (font (size 1.27 1.27))))
        )
        (pin passive line (at 0 -137.16 0) (length 3.81)
          (name "A55" (effects (font (size 1.27 1.27))))
          (number "A55" (effects (font (size 1.27 1.27))))
        )
        (pin passive line (at 0 -139.7 0) (length 3.81)
          (name "A56" (effects (font (size 1.27 1.27))))
          (number "A56" (effects (font (size 1.27 1.27))))
        )
        (pin passive line (at 0 -142.24 0) (length 3.81)
          (name "A57" (effects (font (size 1.27 1.27))))
          (number "A57" (effects (font (size 1.27 1.27))))
        )
        (pin passive line (at 0 -144.78 0) (length 3.81)
          (name "A58" (effects (font (size 1.27 1.27))))
          (number "A58" (effects (font (size 1.27 1.27))))
        )
        (pin passive line (at 0 -147.32 0) (length 3.81)
          (name "A59" (effects (font (size 1.27 1.27))))
          (number "A59" (effects (font (size 1.27 1.27))))
        )
        (pin passive line (at 0 -149.86 0) (length 3.81)
          (name "A60" (effects (font (size 1.27 1.27))))
          (number "A60" (effects (font (size 1.27 1.27))))
        )
        (pin passive line (at 27.94 0 180) (length 3.81)
          (name "B01" (effects (font (size 1.27 1.27))))
          (number "B01" (effects (font (size 1.27 1.27))))
        )
        (pin passive line (at 27.94 -2.54 180) (length 3.81)
          (name "B02" (effects (font (size 1.27 1.27))))
          (number "B02" (effects (font (size 1.27 1.27))))
        )
        (pin passive line (at 27.94 -5.08 180) (length 3.81)
          (name "B03" (effects (font (size 1.27 1.27))))
          (number "B03" (effects (font (size 1.27 1.27))))
        )
        (pin passive line (at 27.94 -7.62 180) (length 3.81)
          (name "B04" (effects (font (size 1.27 1.27))))
          (number "B04" (effects (font (size 1.27 1.27))))
        )
        (pin passive line (at 27.94 -10.16 180) (length 3.81)
          (name "B05" (effects (font (size 1.27 1.27))))
          (number "B05" (effects (font (size 1.27 1.27))))
        )
        (pin passive line (at 27.94 -12.7 180) (length 3.81)
          (name "B06" (effects (font (size 1.27 1.27))))
          (number "B06" (effects (font (size 1.27 1.27))))
        )
        (pin passive line (at 27.94 -15.24 180) (length 3.81)
          (name "B07" (effects (font (size 1.27 1.27))))
          (number "B07" (effects (font (size 1.27 1.27))))
        )
        (pin passive line (at 27.94 -17.78 180) (length 3.81)
          (name "B08" (effects (font (size 1.27 1.27))))
          (number "B08" (effects (font (size 1.27 1.27))))
        )
        (pin passive line (at 27.94 -20.32 180) (length 3.81)
          (name "B09" (effects (font (size 1.27 1.27))))
          (number "B09" (effects (font (size 1.27 1.27))))
        )
        (pin passive line (at 27.94 -22.86 180) (length 3.81)
          (name "B10" (effects (font (size 1.27 1.27))))
          (number "B10" (effects (font (size 1.27 1.27))))
        )
        (pin passive line (at 27.94 -25.4 180) (length 3.81)
          (name "B11" (effects (font (size 1.27 1.27))))
          (number "B11" (effects (font (size 1.27 1.27))))
        )
        (pin passive line (at 27.94 -27.94 180) (length 3.81)
          (name "B12" (effects (font (size 1.27 1.27))))
          (number "B12" (effects (font (size 1.27 1.27))))
        )
        (pin passive line (at 27.94 -30.48 180) (length 3.81)
          (name "B13" (effects (font (size 1.27 1.27))))
          (number "B13" (effects (font (size 1.27 1.27))))
        )
        (pin passive line (at 27.94 -33.02 180) (length 3.81)
          (name "B14" (effects (font (size 1.27 1.27))))
          (number "B14" (effects (font (size 1.27 1.27))))
        )
        (pin passive line (at 27.94 -35.56 180) (length 3.81)
          (name "B15" (effects (font (size 1.27 1.27))))
          (number "B15" (effects (font (size 1.27 1.27))))
        )
        (pin passive line (at 27.94 -38.1 180) (length 3.81)
          (name "B16" (effects (font (size 1.27 1.27))))
          (number "B16" (effects (font (size 1.27 1.27))))
        )
        (pin passive line (at 27.94 -40.64 180) (length 3.81)
          (name "B17" (effects (font (size 1.27 1.27))))
          (number "B17" (effects (font (size 1.27 1.27))))
        )
        (pin passive line (at 27.94 -43.18 180) (length 3.81)
          (name "B18" (effects (font (size 1.27 1.27))))
          (number "B18" (effects (font (size 1.27 1.27))))
        )
        (pin passive line (at 27.94 -45.72 180) (length 3.81)
          (name "B19" (effects (font (size 1.27 1.27))))
          (number "B19" (effects (font (size 1.27 1.27))))
        )
        (pin passive line (at 27.94 -48.26 180) (length 3.81)
          (name "B20" (effects (font (size 1.27 1.27))))
          (number "B20" (effects (font (size 1.27 1.27))))
        )
        (pin passive line (at 27.94 -50.8 180) (length 3.81)
          (name "B21" (effects (font (size 1.27 1.27))))
          (number "B21" (effects (font (size 1.27 1.27))))
        )
        (pin passive line (at 27.94 -53.34 180) (length 3.81)
          (name "B22" (effects (font (size 1.27 1.27))))
          (number "B22" (effects (font (size 1.27 1.27))))
        )
        (pin passive line (at 27.94 -55.88 180) (length 3.81)
          (name "B23" (effects (font (size 1.27 1.27))))
          (number "B23" (effects (font (size 1.27 1.27))))
        )
        (pin passive line (at 27.94 -58.42 180) (length 3.81)
          (name "B24" (effects (font (size 1.27 1.27))))
          (number "B24" (effects (font (size 1.27 1.27))))
        )
        (pin passive line (at 27.94 -60.96 180) (length 3.81)
          (name "B25" (effects (font (size 1.27 1.27))))
          (number "B25" (effects (font (size 1.27 1.27))))
        )
        (pin passive line (at 27.94 -63.5 180) (length 3.81)
          (name "B26" (effects (font (size 1.27 1.27))))
          (number "B26" (effects (font (size 1.27 1.27))))
        )
        (pin passive line (at 27.94 -66.04 180) (length 3.81)
          (name "B27" (effects (font (size 1.27 1.27))))
          (number "B27" (effects (font (size 1.27 1.27))))
        )
        (pin passive line (at 27.94 -68.58 180) (length 3.81)
          (name "B28" (effects (font (size 1.27 1.27))))
          (number "B28" (effects (font (size 1.27 1.27))))
        )
        (pin passive line (at 27.94 -71.12 180) (length 3.81)
          (name "B29" (effects (font (size 1.27 1.27))))
          (number "B29" (effects (font (size 1.27 1.27))))
        )
        (pin passive line (at 27.94 -73.66 180) (length 3.81)
          (name "B30" (effects (font (size 1.27 1.27))))
          (number "B30" (effects (font (size 1.27 1.27))))
        )
        (pin passive line (at 27.94 -76.2 180) (length 3.81)
          (name "B31" (effects (font (size 1.27 1.27))))
          (number "B31" (effects (font (size 1.27 1.27))))
        )
        (pin passive line (at 27.94 -78.74 180) (length 3.81)
          (name "B32" (effects (font (size 1.27 1.27))))
          (number "B32" (effects (font (size 1.27 1.27))))
        )
        (pin passive line (at 27.94 -81.28 180) (length 3.81)
          (name "B33" (effects (font (size 1.27 1.27))))
          (number "B33" (effects (font (size 1.27 1.27))))
        )
        (pin passive line (at 27.94 -83.82 180) (length 3.81)
          (name "B34" (effects (font (size 1.27 1.27))))
          (number "B34" (effects (font (size 1.27 1.27))))
        )
        (pin passive line (at 27.94 -86.36 180) (length 3.81)
          (name "B35" (effects (font (size 1.27 1.27))))
          (number "B35" (effects (font (size 1.27 1.27))))
        )
        (pin passive line (at 27.94 -88.9 180) (length 3.81)
          (name "B36" (effects (font (size 1.27 1.27))))
          (number "B36" (effects (font (size 1.27 1.27))))
        )
        (pin passive line (at 27.94 -91.44 180) (length 3.81)
          (name "B37" (effects (font (size 1.27 1.27))))
          (number "B37" (effects (font (size 1.27 1.27))))
        )
        (pin passive line (at 27.94 -93.98 180) (length 3.81)
          (name "B38" (effects (font (size 1.27 1.27))))
          (number "B38" (effects (font (size 1.27 1.27))))
        )
        (pin passive line (at 27.94 -96.52 180) (length 3.81)
          (name "B39" (effects (font (size 1.27 1.27))))
          (number "B39" (effects (font (size 1.27 1.27))))
        )
        (pin passive line (at 27.94 -99.06 180) (length 3.81)
          (name "B40" (effects (font (size 1.27 1.27))))
          (number "B40" (effects (font (size 1.27 1.27))))
        )
        (pin passive line (at 27.94 -101.6 180) (length 3.81)
          (name "B41" (effects (font (size 1.27 1.27))))
          (number "B41" (effects (font (size 1.27 1.27))))
        )
        (pin passive line (at 27.94 -104.14 180) (length 3.81)
          (name "B42" (effects (font (size 1.27 1.27))))
          (number "B42" (effects (font (size 1.27 1.27))))
        )
        (pin passive line (at 27.94 -106.68 180) (length 3.81)
          (name "B43" (effects (font (size 1.27 1.27))))
          (number "B43" (effects (font (size 1.27 1.27))))
        )
        (pin passive line (at 27.94 -109.22 180) (length 3.81)
          (name "B44" (effects (font (size 1.27 1.27))))
          (number "B44" (effects (font (size 1.27 1.27))))
        )
        (pin passive line (at 27.94 -111.76 180) (length 3.81)
          (name "B45" (effects (font (size 1.27 1.27))))
          (number "B45" (effects (font (size 1.27 1.27))))
        )
        (pin passive line (at 27.94 -114.3 180) (length 3.81)
          (name "B46" (effects (font (size 1.27 1.27))))
          (number "B46" (effects (font (size 1.27 1.27))))
        )
        (pin passive line (at 27.94 -116.84 180) (length 3.81)
          (name "B47" (effects (font (size 1.27 1.27))))
          (number "B47" (effects (font (size 1.27 1.27))))
        )
        (pin passive line (at 27.94 -119.38 180) (length 3.81)
          (name "B48" (effects (font (size 1.27 1.27))))
          (number "B48" (effects (font (size 1.27 1.27))))
        )
        (pin passive line (at 27.94 -121.92 180) (length 3.81)
          (name "B49" (effects (font (size 1.27 1.27))))
          (number "B49" (effects (font (size 1.27 1.27))))
        )
        (pin passive line (at 27.94 -124.46 180) (length 3.81)
          (name "B50" (effects (font (size 1.27 1.27))))
          (number "B50" (effects (font (size 1.27 1.27))))
        )
        (pin passive line (at 27.94 -127 180) (length 3.81)
          (name "B51" (effects (font (size 1.27 1.27))))
          (number "B51" (effects (font (size 1.27 1.27))))
        )
        (pin passive line (at 27.94 -129.54 180) (length 3.81)
          (name "B52" (effects (font (size 1.27 1.27))))
          (number "B52" (effects (font (size 1.27 1.27))))
        )
        (pin passive line (at 27.94 -132.08 180) (length 3.81)
          (name "B53" (effects (font (size 1.27 1.27))))
          (number "B53" (effects (font (size 1.27 1.27))))
        )
        (pin passive line (at 27.94 -134.62 180) (length 3.81)
          (name "B54" (effects (font (size 1.27 1.27))))
          (number "B54" (effects (font (size 1.27 1.27))))
        )
        (pin passive line (at 27.94 -137.16 180) (length 3.81)
          (name "B55" (effects (font (size 1.27 1.27))))
          (number "B55" (effects (font (size 1.27 1.27))))
        )
        (pin passive line (at 27.94 -139.7 180) (length 3.81)
          (name "B56" (effects (font (size 1.27 1.27))))
          (number "B56" (effects (font (size 1.27 1.27))))
        )
        (pin passive line (at 27.94 -142.24 180) (length 3.81)
          (name "B57" (effects (font (size 1.27 1.27))))
          (number "B57" (effects (font (size 1.27 1.27))))
        )
        (pin passive line (at 27.94 -144.78 180) (length 3.81)
          (name "B58" (effects (font (size 1.27 1.27))))
          (number "B58" (effects (font (size 1.27 1.27))))
        )
        (pin passive line (at 27.94 -147.32 180) (length 3.81)
          (name "B59" (effects (font (size 1.27 1.27))))
          (number "B59" (effects (font (size 1.27 1.27))))
        )
        (pin passive line (at 27.94 -149.86 180) (length 3.81)
          (name "B60" (effects (font (size 1.27 1.27))))
          (number "B60" (effects (font (size 1.27 1.27))))
        )
      )
      (symbol "Plug_Samtec_ADM6_4x60_ADM6-60-01.5-L-4-2-A-TR_2_1"
        (rectangle (start 3.81 -152.4) (end 24.13 2.54)
          (stroke (width 0.254) (type default))
          (fill (type background))
        )
        (rectangle (start 11.43 -149.225) (end 10.795 -150.495)
          (stroke (width 0.254) (type default))
          (fill (type outline))
        )
        (rectangle (start 11.43 -146.685) (end 10.795 -147.955)
          (stroke (width 0.254) (type default))
          (fill (type outline))
        )
        (rectangle (start 11.43 -144.145) (end 10.795 -145.415)
          (stroke (width 0.254) (type default))
          (fill (type outline))
        )
        (rectangle (start 11.43 -141.605) (end 10.795 -142.875)
          (stroke (width 0.254) (type default))
          (fill (type outline))
        )
        (rectangle (start 11.43 -139.065) (end 10.795 -140.335)
          (stroke (width 0.254) (type default))
          (fill (type outline))
        )
        (rectangle (start 11.43 -136.525) (end 10.795 -137.795)
          (stroke (width 0.254) (type default))
          (fill (type outline))
        )
        (rectangle (start 11.43 -133.985) (end 10.795 -135.255)
          (stroke (width 0.254) (type default))
          (fill (type outline))
        )
        (rectangle (start 11.43 -131.445) (end 10.795 -132.715)
          (stroke (width 0.254) (type default))
          (fill (type outline))
        )
        (rectangle (start 11.43 -128.905) (end 10.795 -130.175)
          (stroke (width 0.254) (type default))
          (fill (type outline))
        )
        (rectangle (start 11.43 -126.365) (end 10.795 -127.635)
          (stroke (width 0.254) (type default))
          (fill (type outline))
        )
        (rectangle (start 11.43 -123.825) (end 10.795 -125.095)
          (stroke (width 0.254) (type default))
          (fill (type outline))
        )
        (rectangle (start 11.43 -121.285) (end 10.795 -122.555)
          (stroke (width 0.254) (type default))
          (fill (type outline))
        )
        (rectangle (start 11.43 -118.745) (end 10.795 -120.015)
          (stroke (width 0.254) (type default))
          (fill (type outline))
        )
        (rectangle (start 11.43 -116.205) (end 10.795 -117.475)
          (stroke (width 0.254) (type default))
          (fill (type outline))
        )
        (rectangle (start 11.43 -113.665) (end 10.795 -114.935)
          (stroke (width 0.254) (type default))
          (fill (type outline))
        )
        (rectangle (start 11.43 -111.125) (end 10.795 -112.395)
          (stroke (width 0.254) (type default))
          (fill (type outline))
        )
        (rectangle (start 11.43 -108.585) (end 10.795 -109.855)
          (stroke (width 0.254) (type default))
          (fill (type outline))
        )
        (rectangle (start 11.43 -106.045) (end 10.795 -107.315)
          (stroke (width 0.254) (type default))
          (fill (type outline))
        )
        (rectangle (start 11.43 -103.505) (end 10.795 -104.775)
          (stroke (width 0.254) (type default))
          (fill (type outline))
        )
        (rectangle (start 11.43 -100.965) (end 10.795 -102.235)
          (stroke (width 0.254) (type default))
          (fill (type outline))
        )
        (rectangle (start 11.43 -98.425) (end 10.795 -99.695)
          (stroke (width 0.254) (type default))
          (fill (type outline))
        )
        (rectangle (start 11.43 -95.885) (end 10.795 -97.155)
          (stroke (width 0.254) (type default))
          (fill (type outline))
        )
        (rectangle (start 11.43 -93.345) (end 10.795 -94.615)
          (stroke (width 0.254) (type default))
          (fill (type outline))
        )
        (rectangle (start 11.43 -90.805) (end 10.795 -92.075)
          (stroke (width 0.254) (type default))
          (fill (type outline))
        )
        (rectangle (start 11.43 -88.265) (end 10.795 -89.535)
          (stroke (width 0.254) (type default))
          (fill (type outline))
        )
        (rectangle (start 11.43 -85.725) (end 10.795 -86.995)
          (stroke (width 0.254) (type default))
          (fill (type outline))
        )
        (rectangle (start 11.43 -83.185) (end 10.795 -84.455)
          (stroke (width 0.254) (type default))
          (fill (type outline))
        )
        (rectangle (start 11.43 -80.645) (end 10.795 -81.915)
          (stroke (width 0.254) (type default))
          (fill (type outline))
        )
        (rectangle (start 11.43 -78.105) (end 10.795 -79.375)
          (stroke (width 0.254) (type default))
          (fill (type outline))
        )
        (rectangle (start 11.43 -75.565) (end 10.795 -76.835)
          (stroke (width 0.254) (type default))
          (fill (type outline))
        )
        (rectangle (start 11.43 -73.025) (end 10.795 -74.295)
          (stroke (width 0.254) (type default))
          (fill (type outline))
        )
        (rectangle (start 11.43 -70.485) (end 10.795 -71.755)
          (stroke (width 0.254) (type default))
          (fill (type outline))
        )
        (rectangle (start 11.43 -67.945) (end 10.795 -69.215)
          (stroke (width 0.254) (type default))
          (fill (type outline))
        )
        (rectangle (start 11.43 -65.405) (end 10.795 -66.675)
          (stroke (width 0.254) (type default))
          (fill (type outline))
        )
        (rectangle (start 11.43 -62.865) (end 10.795 -64.135)
          (stroke (width 0.254) (type default))
          (fill (type outline))
        )
        (rectangle (start 11.43 -60.325) (end 10.795 -61.595)
          (stroke (width 0.254) (type default))
          (fill (type outline))
        )
        (rectangle (start 11.43 -57.785) (end 10.795 -59.055)
          (stroke (width 0.254) (type default))
          (fill (type outline))
        )
        (rectangle (start 11.43 -55.245) (end 10.795 -56.515)
          (stroke (width 0.254) (type default))
          (fill (type outline))
        )
        (rectangle (start 11.43 -52.705) (end 10.795 -53.975)
          (stroke (width 0.254) (type default))
          (fill (type outline))
        )
        (rectangle (start 11.43 -50.165) (end 10.795 -51.435)
          (stroke (width 0.254) (type default))
          (fill (type outline))
        )
        (rectangle (start 11.43 -47.625) (end 10.795 -48.895)
          (stroke (width 0.254) (type default))
          (fill (type outline))
        )
        (rectangle (start 11.43 -45.085) (end 10.795 -46.355)
          (stroke (width 0.254) (type default))
          (fill (type outline))
        )
        (rectangle (start 11.43 -42.545) (end 10.795 -43.815)
          (stroke (width 0.254) (type default))
          (fill (type outline))
        )
        (rectangle (start 11.43 -40.005) (end 10.795 -41.275)
          (stroke (width 0.254) (type default))
          (fill (type outline))
        )
        (rectangle (start 11.43 -37.465) (end 10.795 -38.735)
          (stroke (width 0.254) (type default))
          (fill (type outline))
        )
        (rectangle (start 11.43 -34.925) (end 10.795 -36.195)
          (stroke (width 0.254) (type default))
          (fill (type outline))
        )
        (rectangle (start 11.43 -32.385) (end 10.795 -33.655)
          (stroke (width 0.254) (type default))
          (fill (type outline))
        )
        (rectangle (start 11.43 -29.845) (end 10.795 -31.115)
          (stroke (width 0.254) (type default))
          (fill (type outline))
        )
        (rectangle (start 11.43 -27.305) (end 10.795 -28.575)
          (stroke (width 0.254) (type default))
          (fill (type outline))
        )
        (rectangle (start 11.43 -24.765) (end 10.795 -26.035)
          (stroke (width 0.254) (type default))
          (fill (type outline))
        )
        (rectangle (start 11.43 -22.225) (end 10.795 -23.495)
          (stroke (width 0.254) (type default))
          (fill (type outline))
        )
        (rectangle (start 11.43 -19.685) (end 10.795 -20.955)
          (stroke (width 0.254) (type default))
          (fill (type outline))
        )
        (rectangle (start 11.43 -17.145) (end 10.795 -18.415)
          (stroke (width 0.254) (type default))
          (fill (type outline))
        )
        (rectangle (start 11.43 -14.605) (end 10.795 -15.875)
          (stroke (width 0.254) (type default))
          (fill (type outline))
        )
        (rectangle (start 11.43 -12.065) (end 10.795 -13.335)
          (stroke (width 0.254) (type default))
          (fill (type outline))
        )
        (rectangle (start 11.43 -9.525) (end 10.795 -10.795)
          (stroke (width 0.254) (type default))
          (fill (type outline))
        )
        (rectangle (start 11.43 -6.985) (end 10.795 -8.255)
          (stroke (width 0.254) (type default))
          (fill (type outline))
        )
        (rectangle (start 11.43 -4.445) (end 10.795 -5.715)
          (stroke (width 0.254) (type default))
          (fill (type outline))
        )
        (rectangle (start 11.43 -1.905) (end 10.795 -3.175)
          (stroke (width 0.254) (type default))
          (fill (type outline))
        )
        (rectangle (start 11.43 0.635) (end 10.795 -0.635)
          (stroke (width 0.254) (type default))
          (fill (type outline))
        )
        (rectangle (start 11.43 1.27) (end 16.51 -151.13)
          (stroke (width 0.254) (type default))
          (fill (type background))
        )
        (rectangle (start 17.145 -149.225) (end 16.51 -150.495)
          (stroke (width 0.254) (type default))
          (fill (type outline))
        )
        (rectangle (start 17.145 -146.685) (end 16.51 -147.955)
          (stroke (width 0.254) (type default))
          (fill (type outline))
        )
        (rectangle (start 17.145 -144.145) (end 16.51 -145.415)
          (stroke (width 0.254) (type default))
          (fill (type outline))
        )
        (rectangle (start 17.145 -141.605) (end 16.51 -142.875)
          (stroke (width 0.254) (type default))
          (fill (type outline))
        )
        (rectangle (start 17.145 -139.065) (end 16.51 -140.335)
          (stroke (width 0.254) (type default))
          (fill (type outline))
        )
        (rectangle (start 17.145 -136.525) (end 16.51 -137.795)
          (stroke (width 0.254) (type default))
          (fill (type outline))
        )
        (rectangle (start 17.145 -133.985) (end 16.51 -135.255)
          (stroke (width 0.254) (type default))
          (fill (type outline))
        )
        (rectangle (start 17.145 -131.445) (end 16.51 -132.715)
          (stroke (width 0.254) (type default))
          (fill (type outline))
        )
        (rectangle (start 17.145 -128.905) (end 16.51 -130.175)
          (stroke (width 0.254) (type default))
          (fill (type outline))
        )
        (rectangle (start 17.145 -126.365) (end 16.51 -127.635)
          (stroke (width 0.254) (type default))
          (fill (type outline))
        )
        (rectangle (start 17.145 -123.825) (end 16.51 -125.095)
          (stroke (width 0.254) (type default))
          (fill (type outline))
        )
        (rectangle (start 17.145 -121.285) (end 16.51 -122.555)
          (stroke (width 0.254) (type default))
          (fill (type outline))
        )
        (rectangle (start 17.145 -118.745) (end 16.51 -120.015)
          (stroke (width 0.254) (type default))
          (fill (type outline))
        )
        (rectangle (start 17.145 -116.205) (end 16.51 -117.475)
          (stroke (width 0.254) (type default))
          (fill (type outline))
        )
        (rectangle (start 17.145 -113.665) (end 16.51 -114.935)
          (stroke (width 0.254) (type default))
          (fill (type outline))
        )
        (rectangle (start 17.145 -111.125) (end 16.51 -112.395)
          (stroke (width 0.254) (type default))
          (fill (type outline))
        )
        (rectangle (start 17.145 -108.585) (end 16.51 -109.855)
          (stroke (width 0.254) (type default))
          (fill (type outline))
        )
        (rectangle (start 17.145 -106.045) (end 16.51 -107.315)
          (stroke (width 0.254) (type default))
          (fill (type outline))
        )
        (rectangle (start 17.145 -103.505) (end 16.51 -104.775)
          (stroke (width 0.254) (type default))
          (fill (type outline))
        )
        (rectangle (start 17.145 -100.965) (end 16.51 -102.235)
          (stroke (width 0.254) (type default))
          (fill (type outline))
        )
        (rectangle (start 17.145 -98.425) (end 16.51 -99.695)
          (stroke (width 0.254) (type default))
          (fill (type outline))
        )
        (rectangle (start 17.145 -95.885) (end 16.51 -97.155)
          (stroke (width 0.254) (type default))
          (fill (type outline))
        )
        (rectangle (start 17.145 -93.345) (end 16.51 -94.615)
          (stroke (width 0.254) (type default))
          (fill (type outline))
        )
        (rectangle (start 17.145 -90.805) (end 16.51 -92.075)
          (stroke (width 0.254) (type default))
          (fill (type outline))
        )
        (rectangle (start 17.145 -88.265) (end 16.51 -89.535)
          (stroke (width 0.254) (type default))
          (fill (type outline))
        )
        (rectangle (start 17.145 -85.725) (end 16.51 -86.995)
          (stroke (width 0.254) (type default))
          (fill (type outline))
        )
        (rectangle (start 17.145 -83.185) (end 16.51 -84.455)
          (stroke (width 0.254) (type default))
          (fill (type outline))
        )
        (rectangle (start 17.145 -80.645) (end 16.51 -81.915)
          (stroke (width 0.254) (type default))
          (fill (type outline))
        )
        (rectangle (start 17.145 -78.105) (end 16.51 -79.375)
          (stroke (width 0.254) (type default))
          (fill (type outline))
        )
        (rectangle (start 17.145 -75.565) (end 16.51 -76.835)
          (stroke (width 0.254) (type default))
          (fill (type outline))
        )
        (rectangle (start 17.145 -73.025) (end 16.51 -74.295)
          (stroke (width 0.254) (type default))
          (fill (type outline))
        )
        (rectangle (start 17.145 -70.485) (end 16.51 -71.755)
          (stroke (width 0.254) (type default))
          (fill (type outline))
        )
        (rectangle (start 17.145 -67.945) (end 16.51 -69.215)
          (stroke (width 0.254) (type default))
          (fill (type outline))
        )
        (rectangle (start 17.145 -65.405) (end 16.51 -66.675)
          (stroke (width 0.254) (type default))
          (fill (type outline))
        )
        (rectangle (start 17.145 -62.865) (end 16.51 -64.135)
          (stroke (width 0.254) (type default))
          (fill (type outline))
        )
        (rectangle (start 17.145 -60.325) (end 16.51 -61.595)
          (stroke (width 0.254) (type default))
          (fill (type outline))
        )
        (rectangle (start 17.145 -57.785) (end 16.51 -59.055)
          (stroke (width 0.254) (type default))
          (fill (type outline))
        )
        (rectangle (start 17.145 -55.245) (end 16.51 -56.515)
          (stroke (width 0.254) (type default))
          (fill (type outline))
        )
        (rectangle (start 17.145 -52.705) (end 16.51 -53.975)
          (stroke (width 0.254) (type default))
          (fill (type outline))
        )
        (rectangle (start 17.145 -50.165) (end 16.51 -51.435)
          (stroke (width 0.254) (type default))
          (fill (type outline))
        )
        (rectangle (start 17.145 -47.625) (end 16.51 -48.895)
          (stroke (width 0.254) (type default))
          (fill (type outline))
        )
        (rectangle (start 17.145 -45.085) (end 16.51 -46.355)
          (stroke (width 0.254) (type default))
          (fill (type outline))
        )
        (rectangle (start 17.145 -42.545) (end 16.51 -43.815)
          (stroke (width 0.254) (type default))
          (fill (type outline))
        )
        (rectangle (start 17.145 -40.005) (end 16.51 -41.275)
          (stroke (width 0.254) (type default))
          (fill (type outline))
        )
        (rectangle (start 17.145 -37.465) (end 16.51 -38.735)
          (stroke (width 0.254) (type default))
          (fill (type outline))
        )
        (rectangle (start 17.145 -34.925) (end 16.51 -36.195)
          (stroke (width 0.254) (type default))
          (fill (type outline))
        )
        (rectangle (start 17.145 -32.385) (end 16.51 -33.655)
          (stroke (width 0.254) (type default))
          (fill (type outline))
        )
        (rectangle (start 17.145 -29.845) (end 16.51 -31.115)
          (stroke (width 0.254) (type default))
          (fill (type outline))
        )
        (rectangle (start 17.145 -27.305) (end 16.51 -28.575)
          (stroke (width 0.254) (type default))
          (fill (type outline))
        )
        (rectangle (start 17.145 -24.765) (end 16.51 -26.035)
          (stroke (width 0.254) (type default))
          (fill (type outline))
        )
        (rectangle (start 17.145 -22.225) (end 16.51 -23.495)
          (stroke (width 0.254) (type default))
          (fill (type outline))
        )
        (rectangle (start 17.145 -19.685) (end 16.51 -20.955)
          (stroke (width 0.254) (type default))
          (fill (type outline))
        )
        (rectangle (start 17.145 -17.145) (end 16.51 -18.415)
          (stroke (width 0.254) (type default))
          (fill (type outline))
        )
        (rectangle (start 17.145 -14.605) (end 16.51 -15.875)
          (stroke (width 0.254) (type default))
          (fill (type outline))
        )
        (rectangle (start 17.145 -12.065) (end 16.51 -13.335)
          (stroke (width 0.254) (type default))
          (fill (type outline))
        )
        (rectangle (start 17.145 -9.525) (end 16.51 -10.795)
          (stroke (width 0.254) (type default))
          (fill (type outline))
        )
        (rectangle (start 17.145 -6.985) (end 16.51 -8.255)
          (stroke (width 0.254) (type default))
          (fill (type outline))
        )
        (rectangle (start 17.145 -4.445) (end 16.51 -5.715)
          (stroke (width 0.254) (type default))
          (fill (type outline))
        )
        (rectangle (start 17.145 -1.905) (end 16.51 -3.175)
          (stroke (width 0.254) (type default))
          (fill (type outline))
        )
        (rectangle (start 17.145 0.635) (end 16.51 -0.635)
          (stroke (width 0.254) (type default))
          (fill (type outline))
        )
        (pin passive line (at 0 0 0) (length 3.81)
          (name "C01" (effects (font (size 1.27 1.27))))
          (number "C01" (effects (font (size 1.27 1.27))))
        )
        (pin passive line (at 0 -2.54 0) (length 3.81)
          (name "C02" (effects (font (size 1.27 1.27))))
          (number "C02" (effects (font (size 1.27 1.27))))
        )
        (pin passive line (at 0 -5.08 0) (length 3.81)
          (name "C03" (effects (font (size 1.27 1.27))))
          (number "C03" (effects (font (size 1.27 1.27))))
        )
        (pin passive line (at 0 -7.62 0) (length 3.81)
          (name "C04" (effects (font (size 1.27 1.27))))
          (number "C04" (effects (font (size 1.27 1.27))))
        )
        (pin passive line (at 0 -10.16 0) (length 3.81)
          (name "C05" (effects (font (size 1.27 1.27))))
          (number "C05" (effects (font (size 1.27 1.27))))
        )
        (pin passive line (at 0 -12.7 0) (length 3.81)
          (name "C06" (effects (font (size 1.27 1.27))))
          (number "C06" (effects (font (size 1.27 1.27))))
        )
        (pin passive line (at 0 -15.24 0) (length 3.81)
          (name "C07" (effects (font (size 1.27 1.27))))
          (number "C07" (effects (font (size 1.27 1.27))))
        )
        (pin passive line (at 0 -17.78 0) (length 3.81)
          (name "C08" (effects (font (size 1.27 1.27))))
          (number "C08" (effects (font (size 1.27 1.27))))
        )
        (pin passive line (at 0 -20.32 0) (length 3.81)
          (name "C09" (effects (font (size 1.27 1.27))))
          (number "C09" (effects (font (size 1.27 1.27))))
        )
        (pin passive line (at 0 -22.86 0) (length 3.81)
          (name "C10" (effects (font (size 1.27 1.27))))
          (number "C10" (effects (font (size 1.27 1.27))))
        )
        (pin passive line (at 0 -25.4 0) (length 3.81)
          (name "C11" (effects (font (size 1.27 1.27))))
          (number "C11" (effects (font (size 1.27 1.27))))
        )
        (pin passive line (at 0 -27.94 0) (length 3.81)
          (name "C12" (effects (font (size 1.27 1.27))))
          (number "C12" (effects (font (size 1.27 1.27))))
        )
        (pin passive line (at 0 -30.48 0) (length 3.81)
          (name "C13" (effects (font (size 1.27 1.27))))
          (number "C13" (effects (font (size 1.27 1.27))))
        )
        (pin passive line (at 0 -33.02 0) (length 3.81)
          (name "C14" (effects (font (size 1.27 1.27))))
          (number "C14" (effects (font (size 1.27 1.27))))
        )
        (pin passive line (at 0 -35.56 0) (length 3.81)
          (name "C15" (effects (font (size 1.27 1.27))))
          (number "C15" (effects (font (size 1.27 1.27))))
        )
        (pin passive line (at 0 -38.1 0) (length 3.81)
          (name "C16" (effects (font (size 1.27 1.27))))
          (number "C16" (effects (font (size 1.27 1.27))))
        )
        (pin passive line (at 0 -40.64 0) (length 3.81)
          (name "C17" (effects (font (size 1.27 1.27))))
          (number "C17" (effects (font (size 1.27 1.27))))
        )
        (pin passive line (at 0 -43.18 0) (length 3.81)
          (name "C18" (effects (font (size 1.27 1.27))))
          (number "C18" (effects (font (size 1.27 1.27))))
        )
        (pin passive line (at 0 -45.72 0) (length 3.81)
          (name "C19" (effects (font (size 1.27 1.27))))
          (number "C19" (effects (font (size 1.27 1.27))))
        )
        (pin passive line (at 0 -48.26 0) (length 3.81)
          (name "C20" (effects (font (size 1.27 1.27))))
          (number "C20" (effects (font (size 1.27 1.27))))
        )
        (pin passive line (at 0 -50.8 0) (length 3.81)
          (name "C21" (effects (font (size 1.27 1.27))))
          (number "C21" (effects (font (size 1.27 1.27))))
        )
        (pin passive line (at 0 -53.34 0) (length 3.81)
          (name "C22" (effects (font (size 1.27 1.27))))
          (number "C22" (effects (font (size 1.27 1.27))))
        )
        (pin passive line (at 0 -55.88 0) (length 3.81)
          (name "C23" (effects (font (size 1.27 1.27))))
          (number "C23" (effects (font (size 1.27 1.27))))
        )
        (pin passive line (at 0 -58.42 0) (length 3.81)
          (name "C24" (effects (font (size 1.27 1.27))))
          (number "C24" (effects (font (size 1.27 1.27))))
        )
        (pin passive line (at 0 -60.96 0) (length 3.81)
          (name "C25" (effects (font (size 1.27 1.27))))
          (number "C25" (effects (font (size 1.27 1.27))))
        )
        (pin passive line (at 0 -63.5 0) (length 3.81)
          (name "C26" (effects (font (size 1.27 1.27))))
          (number "C26" (effects (font (size 1.27 1.27))))
        )
        (pin passive line (at 0 -66.04 0) (length 3.81)
          (name "C27" (effects (font (size 1.27 1.27))))
          (number "C27" (effects (font (size 1.27 1.27))))
        )
        (pin passive line (at 0 -68.58 0) (length 3.81)
          (name "C28" (effects (font (size 1.27 1.27))))
          (number "C28" (effects (font (size 1.27 1.27))))
        )
        (pin passive line (at 0 -71.12 0) (length 3.81)
          (name "C29" (effects (font (size 1.27 1.27))))
          (number "C29" (effects (font (size 1.27 1.27))))
        )
        (pin passive line (at 0 -73.66 0) (length 3.81)
          (name "C30" (effects (font (size 1.27 1.27))))
          (number "C30" (effects (font (size 1.27 1.27))))
        )
        (pin passive line (at 0 -76.2 0) (length 3.81)
          (name "C31" (effects (font (size 1.27 1.27))))
          (number "C31" (effects (font (size 1.27 1.27))))
        )
        (pin passive line (at 0 -78.74 0) (length 3.81)
          (name "C32" (effects (font (size 1.27 1.27))))
          (number "C32" (effects (font (size 1.27 1.27))))
        )
        (pin passive line (at 0 -81.28 0) (length 3.81)
          (name "C33" (effects (font (size 1.27 1.27))))
          (number "C33" (effects (font (size 1.27 1.27))))
        )
        (pin passive line (at 0 -83.82 0) (length 3.81)
          (name "C34" (effects (font (size 1.27 1.27))))
          (number "C34" (effects (font (size 1.27 1.27))))
        )
        (pin passive line (at 0 -86.36 0) (length 3.81)
          (name "C35" (effects (font (size 1.27 1.27))))
          (number "C35" (effects (font (size 1.27 1.27))))
        )
        (pin passive line (at 0 -88.9 0) (length 3.81)
          (name "C36" (effects (font (size 1.27 1.27))))
          (number "C36" (effects (font (size 1.27 1.27))))
        )
        (pin passive line (at 0 -91.44 0) (length 3.81)
          (name "C37" (effects (font (size 1.27 1.27))))
          (number "C37" (effects (font (size 1.27 1.27))))
        )
        (pin passive line (at 0 -93.98 0) (length 3.81)
          (name "C38" (effects (font (size 1.27 1.27))))
          (number "C38" (effects (font (size 1.27 1.27))))
        )
        (pin passive line (at 0 -96.52 0) (length 3.81)
          (name "C39" (effects (font (size 1.27 1.27))))
          (number "C39" (effects (font (size 1.27 1.27))))
        )
        (pin passive line (at 0 -99.06 0) (length 3.81)
          (name "C40" (effects (font (size 1.27 1.27))))
          (number "C40" (effects (font (size 1.27 1.27))))
        )
        (pin passive line (at 0 -101.6 0) (length 3.81)
          (name "C41" (effects (font (size 1.27 1.27))))
          (number "C41" (effects (font (size 1.27 1.27))))
        )
        (pin passive line (at 0 -104.14 0) (length 3.81)
          (name "C42" (effects (font (size 1.27 1.27))))
          (number "C42" (effects (font (size 1.27 1.27))))
        )
        (pin passive line (at 0 -106.68 0) (length 3.81)
          (name "C43" (effects (font (size 1.27 1.27))))
          (number "C43" (effects (font (size 1.27 1.27))))
        )
        (pin passive line (at 0 -109.22 0) (length 3.81)
          (name "C44" (effects (font (size 1.27 1.27))))
          (number "C44" (effects (font (size 1.27 1.27))))
        )
        (pin passive line (at 0 -111.76 0) (length 3.81)
          (name "C45" (effects (font (size 1.27 1.27))))
          (number "C45" (effects (font (size 1.27 1.27))))
        )
        (pin passive line (at 0 -114.3 0) (length 3.81)
          (name "C46" (effects (font (size 1.27 1.27))))
          (number "C46" (effects (font (size 1.27 1.27))))
        )
        (pin passive line (at 0 -116.84 0) (length 3.81)
          (name "C47" (effects (font (size 1.27 1.27))))
          (number "C47" (effects (font (size 1.27 1.27))))
        )
        (pin passive line (at 0 -119.38 0) (length 3.81)
          (name "C48" (effects (font (size 1.27 1.27))))
          (number "C48" (effects (font (size 1.27 1.27))))
        )
        (pin passive line (at 0 -121.92 0) (length 3.81)
          (name "C49" (effects (font (size 1.27 1.27))))
          (number "C49" (effects (font (size 1.27 1.27))))
        )
        (pin passive line (at 0 -124.46 0) (length 3.81)
          (name "C50" (effects (font (size 1.27 1.27))))
          (number "C50" (effects (font (size 1.27 1.27))))
        )
        (pin passive line (at 0 -127 0) (length 3.81)
          (name "C51" (effects (font (size 1.27 1.27))))
          (number "C51" (effects (font (size 1.27 1.27))))
        )
        (pin passive line (at 0 -129.54 0) (length 3.81)
          (name "C52" (effects (font (size 1.27 1.27))))
          (number "C52" (effects (font (size 1.27 1.27))))
        )
        (pin passive line (at 0 -132.08 0) (length 3.81)
          (name "C53" (effects (font (size 1.27 1.27))))
          (number "C53" (effects (font (size 1.27 1.27))))
        )
        (pin passive line (at 0 -134.62 0) (length 3.81)
          (name "C54" (effects (font (size 1.27 1.27))))
          (number "C54" (effects (font (size 1.27 1.27))))
        )
        (pin passive line (at 0 -137.16 0) (length 3.81)
          (name "C55" (effects (font (size 1.27 1.27))))
          (number "C55" (effects (font (size 1.27 1.27))))
        )
        (pin passive line (at 0 -139.7 0) (length 3.81)
          (name "C56" (effects (font (size 1.27 1.27))))
          (number "C56" (effects (font (size 1.27 1.27))))
        )
        (pin passive line (at 0 -142.24 0) (length 3.81)
          (name "C57" (effects (font (size 1.27 1.27))))
          (number "C57" (effects (font (size 1.27 1.27))))
        )
        (pin passive line (at 0 -144.78 0) (length 3.81)
          (name "C58" (effects (font (size 1.27 1.27))))
          (number "C58" (effects (font (size 1.27 1.27))))
        )
        (pin passive line (at 0 -147.32 0) (length 3.81)
          (name "C59" (effects (font (size 1.27 1.27))))
          (number "C59" (effects (font (size 1.27 1.27))))
        )
        (pin passive line (at 0 -149.86 0) (length 3.81)
          (name "C60" (effects (font (size 1.27 1.27))))
          (number "C60" (effects (font (size 1.27 1.27))))
        )
        (pin passive line (at 27.94 0 180) (length 3.81)
          (name "D01" (effects (font (size 1.27 1.27))))
          (number "D01" (effects (font (size 1.27 1.27))))
        )
        (pin passive line (at 27.94 -2.54 180) (length 3.81)
          (name "D02" (effects (font (size 1.27 1.27))))
          (number "D02" (effects (font (size 1.27 1.27))))
        )
        (pin passive line (at 27.94 -5.08 180) (length 3.81)
          (name "D03" (effects (font (size 1.27 1.27))))
          (number "D03" (effects (font (size 1.27 1.27))))
        )
        (pin passive line (at 27.94 -7.62 180) (length 3.81)
          (name "D04" (effects (font (size 1.27 1.27))))
          (number "D04" (effects (font (size 1.27 1.27))))
        )
        (pin passive line (at 27.94 -10.16 180) (length 3.81)
          (name "D05" (effects (font (size 1.27 1.27))))
          (number "D05" (effects (font (size 1.27 1.27))))
        )
        (pin passive line (at 27.94 -12.7 180) (length 3.81)
          (name "D06" (effects (font (size 1.27 1.27))))
          (number "D06" (effects (font (size 1.27 1.27))))
        )
        (pin passive line (at 27.94 -15.24 180) (length 3.81)
          (name "D07" (effects (font (size 1.27 1.27))))
          (number "D07" (effects (font (size 1.27 1.27))))
        )
        (pin passive line (at 27.94 -17.78 180) (length 3.81)
          (name "D08" (effects (font (size 1.27 1.27))))
          (number "D08" (effects (font (size 1.27 1.27))))
        )
        (pin passive line (at 27.94 -20.32 180) (length 3.81)
          (name "D09" (effects (font (size 1.27 1.27))))
          (number "D09" (effects (font (size 1.27 1.27))))
        )
        (pin passive line (at 27.94 -22.86 180) (length 3.81)
          (name "D10" (effects (font (size 1.27 1.27))))
          (number "D10" (effects (font (size 1.27 1.27))))
        )
        (pin passive line (at 27.94 -25.4 180) (length 3.81)
          (name "D11" (effects (font (size 1.27 1.27))))
          (number "D11" (effects (font (size 1.27 1.27))))
        )
        (pin passive line (at 27.94 -27.94 180) (length 3.81)
          (name "D12" (effects (font (size 1.27 1.27))))
          (number "D12" (effects (font (size 1.27 1.27))))
        )
        (pin passive line (at 27.94 -30.48 180) (length 3.81)
          (name "D13" (effects (font (size 1.27 1.27))))
          (number "D13" (effects (font (size 1.27 1.27))))
        )
        (pin passive line (at 27.94 -33.02 180) (length 3.81)
          (name "D14" (effects (font (size 1.27 1.27))))
          (number "D14" (effects (font (size 1.27 1.27))))
        )
        (pin passive line (at 27.94 -35.56 180) (length 3.81)
          (name "D15" (effects (font (size 1.27 1.27))))
          (number "D15" (effects (font (size 1.27 1.27))))
        )
        (pin passive line (at 27.94 -38.1 180) (length 3.81)
          (name "D16" (effects (font (size 1.27 1.27))))
          (number "D16" (effects (font (size 1.27 1.27))))
        )
        (pin passive line (at 27.94 -40.64 180) (length 3.81)
          (name "D17" (effects (font (size 1.27 1.27))))
          (number "D17" (effects (font (size 1.27 1.27))))
        )
        (pin passive line (at 27.94 -43.18 180) (length 3.81)
          (name "D18" (effects (font (size 1.27 1.27))))
          (number "D18" (effects (font (size 1.27 1.27))))
        )
        (pin passive line (at 27.94 -45.72 180) (length 3.81)
          (name "D19" (effects (font (size 1.27 1.27))))
          (number "D19" (effects (font (size 1.27 1.27))))
        )
        (pin passive line (at 27.94 -48.26 180) (length 3.81)
          (name "D20" (effects (font (size 1.27 1.27))))
          (number "D20" (effects (font (size 1.27 1.27))))
        )
        (pin passive line (at 27.94 -50.8 180) (length 3.81)
          (name "D21" (effects (font (size 1.27 1.27))))
          (number "D21" (effects (font (size 1.27 1.27))))
        )
        (pin passive line (at 27.94 -53.34 180) (length 3.81)
          (name "D22" (effects (font (size 1.27 1.27))))
          (number "D22" (effects (font (size 1.27 1.27))))
        )
        (pin passive line (at 27.94 -55.88 180) (length 3.81)
          (name "D23" (effects (font (size 1.27 1.27))))
          (number "D23" (effects (font (size 1.27 1.27))))
        )
        (pin passive line (at 27.94 -58.42 180) (length 3.81)
          (name "D24" (effects (font (size 1.27 1.27))))
          (number "D24" (effects (font (size 1.27 1.27))))
        )
        (pin passive line (at 27.94 -60.96 180) (length 3.81)
          (name "D25" (effects (font (size 1.27 1.27))))
          (number "D25" (effects (font (size 1.27 1.27))))
        )
        (pin passive line (at 27.94 -63.5 180) (length 3.81)
          (name "D26" (effects (font (size 1.27 1.27))))
          (number "D26" (effects (font (size 1.27 1.27))))
        )
        (pin passive line (at 27.94 -66.04 180) (length 3.81)
          (name "D27" (effects (font (size 1.27 1.27))))
          (number "D27" (effects (font (size 1.27 1.27))))
        )
        (pin passive line (at 27.94 -68.58 180) (length 3.81)
          (name "D28" (effects (font (size 1.27 1.27))))
          (number "D28" (effects (font (size 1.27 1.27))))
        )
        (pin passive line (at 27.94 -71.12 180) (length 3.81)
          (name "D29" (effects (font (size 1.27 1.27))))
          (number "D29" (effects (font (size 1.27 1.27))))
        )
        (pin passive line (at 27.94 -73.66 180) (length 3.81)
          (name "D30" (effects (font (size 1.27 1.27))))
          (number "D30" (effects (font (size 1.27 1.27))))
        )
        (pin passive line (at 27.94 -76.2 180) (length 3.81)
          (name "D31" (effects (font (size 1.27 1.27))))
          (number "D31" (effects (font (size 1.27 1.27))))
        )
        (pin passive line (at 27.94 -78.74 180) (length 3.81)
          (name "D32" (effects (font (size 1.27 1.27))))
          (number "D32" (effects (font (size 1.27 1.27))))
        )
        (pin passive line (at 27.94 -81.28 180) (length 3.81)
          (name "D33" (effects (font (size 1.27 1.27))))
          (number "D33" (effects (font (size 1.27 1.27))))
        )
        (pin passive line (at 27.94 -83.82 180) (length 3.81)
          (name "D34" (effects (font (size 1.27 1.27))))
          (number "D34" (effects (font (size 1.27 1.27))))
        )
        (pin passive line (at 27.94 -86.36 180) (length 3.81)
          (name "D35" (effects (font (size 1.27 1.27))))
          (number "D35" (effects (font (size 1.27 1.27))))
        )
        (pin passive line (at 27.94 -88.9 180) (length 3.81)
          (name "D36" (effects (font (size 1.27 1.27))))
          (number "D36" (effects (font (size 1.27 1.27))))
        )
        (pin passive line (at 27.94 -91.44 180) (length 3.81)
          (name "D37" (effects (font (size 1.27 1.27))))
          (number "D37" (effects (font (size 1.27 1.27))))
        )
        (pin passive line (at 27.94 -93.98 180) (length 3.81)
          (name "D38" (effects (font (size 1.27 1.27))))
          (number "D38" (effects (font (size 1.27 1.27))))
        )
        (pin passive line (at 27.94 -96.52 180) (length 3.81)
          (name "D39" (effects (font (size 1.27 1.27))))
          (number "D39" (effects (font (size 1.27 1.27))))
        )
        (pin passive line (at 27.94 -99.06 180) (length 3.81)
          (name "D40" (effects (font (size 1.27 1.27))))
          (number "D40" (effects (font (size 1.27 1.27))))
        )
        (pin passive line (at 27.94 -101.6 180) (length 3.81)
          (name "D41" (effects (font (size 1.27 1.27))))
          (number "D41" (effects (font (size 1.27 1.27))))
        )
        (pin passive line (at 27.94 -104.14 180) (length 3.81)
          (name "D42" (effects (font (size 1.27 1.27))))
          (number "D42" (effects (font (size 1.27 1.27))))
        )
        (pin passive line (at 27.94 -106.68 180) (length 3.81)
          (name "D43" (effects (font (size 1.27 1.27))))
          (number "D43" (effects (font (size 1.27 1.27))))
        )
        (pin passive line (at 27.94 -109.22 180) (length 3.81)
          (name "D44" (effects (font (size 1.27 1.27))))
          (number "D44" (effects (font (size 1.27 1.27))))
        )
        (pin passive line (at 27.94 -111.76 180) (length 3.81)
          (name "D45" (effects (font (size 1.27 1.27))))
          (number "D45" (effects (font (size 1.27 1.27))))
        )
        (pin passive line (at 27.94 -114.3 180) (length 3.81)
          (name "D46" (effects (font (size 1.27 1.27))))
          (number "D46" (effects (font (size 1.27 1.27))))
        )
        (pin passive line (at 27.94 -116.84 180) (length 3.81)
          (name "D47" (effects (font (size 1.27 1.27))))
          (number "D47" (effects (font (size 1.27 1.27))))
        )
        (pin passive line (at 27.94 -119.38 180) (length 3.81)
          (name "D48" (effects (font (size 1.27 1.27))))
          (number "D48" (effects (font (size 1.27 1.27))))
        )
        (pin passive line (at 27.94 -121.92 180) (length 3.81)
          (name "D49" (effects (font (size 1.27 1.27))))
          (number "D49" (effects (font (size 1.27 1.27))))
        )
        (pin passive line (at 27.94 -124.46 180) (length 3.81)
          (name "D50" (effects (font (size 1.27 1.27))))
          (number "D50" (effects (font (size 1.27 1.27))))
        )
        (pin passive line (at 27.94 -127 180) (length 3.81)
          (name "D51" (effects (font (size 1.27 1.27))))
          (number "D51" (effects (font (size 1.27 1.27))))
        )
        (pin passive line (at 27.94 -129.54 180) (length 3.81)
          (name "D52" (effects (font (size 1.27 1.27))))
          (number "D52" (effects (font (size 1.27 1.27))))
        )
        (pin passive line (at 27.94 -132.08 180) (length 3.81)
          (name "D53" (effects (font (size 1.27 1.27))))
          (number "D53" (effects (font (size 1.27 1.27))))
        )
        (pin passive line (at 27.94 -134.62 180) (length 3.81)
          (name "D54" (effects (font (size 1.27 1.27))))
          (number "D54" (effects (font (size 1.27 1.27))))
        )
        (pin passive line (at 27.94 -137.16 180) (length 3.81)
          (name "D55" (effects (font (size 1.27 1.27))))
          (number "D55" (effects (font (size 1.27 1.27))))
        )
        (pin passive line (at 27.94 -139.7 180) (length 3.81)
          (name "D56" (effects (font (size 1.27 1.27))))
          (number "D56" (effects (font (size 1.27 1.27))))
        )
        (pin passive line (at 27.94 -142.24 180) (length 3.81)
          (name "D57" (effects (font (size 1.27 1.27))))
          (number "D57" (effects (font (size 1.27 1.27))))
        )
        (pin passive line (at 27.94 -144.78 180) (length 3.81)
          (name "D58" (effects (font (size 1.27 1.27))))
          (number "D58" (effects (font (size 1.27 1.27))))
        )
        (pin passive line (at 27.94 -147.32 180) (length 3.81)
          (name "D59" (effects (font (size 1.27 1.27))))
          (number "D59" (effects (font (size 1.27 1.27))))
        )
        (pin passive line (at 27.94 -149.86 180) (length 3.81)
          (name "D60" (effects (font (size 1.27 1.27))))
          (number "D60" (effects (font (size 1.27 1.27))))
        )
      )
    )
	(symbol "kria-k26-devboard:RT6236AHGQUF" (in_bom yes) (on_board yes)
      (property "Reference" "U" (at 33.02 -2.54 0)
        (effects (font (size 1.27 1.27) (thickness 0.15)) (justify left bottom))
      )
      (property "Value" "RT6236AHGQUF" (at 33.02 -5.08 0)
        (effects (font (size 1.27 1.27) (thickness 0.15)) (justify left bottom))
      )
      (property "Footprint" "kria-k26-devboard-footprints:UQFN-13_2x3mm_P0.5mm" (at 33.02 -7.62 0)
        (effects (font (size 1.27 1.27) (thickness 0.15)) (justify left bottom) hide)
      )
      (property "Datasheet" "https://www.richtek.com/assets/product_file/RT6236A=RT6236B/DS6236AB-02.pdf" (at 33.02 -10.16 0)
        (effects (font (size 1.27 1.27) (thickness 0.15)) (justify left bottom) hide)
      )
      (property "MPN" "RT6236AHGQUF" (at 33.02 -12.7 0)
        (effects (font (size 1.27 1.27) (thickness 0.15)) (justify left bottom) hide)
      )
      (property "Manufacturer" "Richtek" (at 33.02 -15.24 0)
        (effects (font (size 1.27 1.27) (thickness 0.15)) (justify left bottom) hide)
      )
      (property "Author" "Antmicro" (at 33.02 -17.78 0)
        (effects (font (size 1.27 1.27) (thickness 0.15)) (justify left bottom) hide)
      )
      (property "License" "Apache-2.0" (at 33.02 -20.32 0)
        (effects (font (size 1.27 1.27) (thickness 0.15)) (justify left bottom) hide)
      )
      (property "ki_keywords" "SMT, PMIC, IC, SWITCHING, VOLTAGE, REGULATOR, DC-DC" (at 0 0 0)
        (effects (font (size 1.27 1.27)) hide)
      )
      (property "ki_description" "DC-DC Switching Buck Step Down Regulator, Adjustable, 4.5V-18Vin, 700mV-8V/6A out, 650kHz, UQFN-13" (at 0 0 0)
        (effects (font (size 1.27 1.27)) hide)
      )
      (symbol "RT6236AHGQUF_1_1"
        (rectangle (start 2.54 2.54) (end 15.24 -17.78)
          (stroke (width 0.254) (type default))
          (fill (type background))
        )
        (pin power_in line (at 0 -15.24 0) (length 2.54)
          (name "GND" (effects (font (size 1.27 1.27))))
          (number "1" (effects (font (size 1.27 1.27))))
        )
        (pin power_in line (at 0 0 0) (length 2.54)
          (name "VIN" (effects (font (size 1.27 1.27))))
          (number "10" (effects (font (size 1.27 1.27))))
        )
        (pin output line (at 17.78 -7.62 180) (length 2.54)
          (name "BOOT" (effects (font (size 1.27 1.27))))
          (number "11" (effects (font (size 1.27 1.27))))
        )
        (pin power_out line (at 17.78 -3.81 180) (length 2.54)
          (name "SW" (effects (font (size 1.27 1.27))))
          (number "12" (effects (font (size 1.27 1.27))))
        )
        (pin passive line (at 0 -15.24 0) (length 2.54) hide
          (name "GND" (effects (font (size 1.27 1.27))))
          (number "13" (effects (font (size 1.27 1.27))))
        )
        (pin input line (at 0 -3.81 0) (length 2.54)
          (name "EN" (effects (font (size 1.27 1.27))))
          (number "2" (effects (font (size 1.27 1.27))))
        )
        (pin input line (at 17.78 -15.24 180) (length 2.54)
          (name "FB" (effects (font (size 1.27 1.27))))
          (number "3" (effects (font (size 1.27 1.27))))
        )
        (pin no_connect line (at 15.24 -12.7 180) (length 2.54) hide
          (name "NC" (effects (font (size 1.27 1.27))))
          (number "4" (effects (font (size 1.27 1.27))))
        )
        (pin input line (at 0 -11.43 0) (length 2.54)
          (name "SS" (effects (font (size 1.27 1.27))))
          (number "5" (effects (font (size 1.27 1.27))))
        )
        (pin output line (at 0 -7.62 0) (length 2.54)
          (name "PVCC" (effects (font (size 1.27 1.27))))
          (number "6" (effects (font (size 1.27 1.27))))
        )
        (pin no_connect line (at 15.24 -10.16 180) (length 2.54) hide
          (name "NC" (effects (font (size 1.27 1.27))))
          (number "7" (effects (font (size 1.27 1.27))))
        )
        (pin output line (at 17.78 0 180) (length 2.54)
          (name "PG" (effects (font (size 1.27 1.27))))
          (number "8" (effects (font (size 1.27 1.27))))
        )
        (pin passive line (at 0 0 0) (length 2.54) hide
          (name "VIN" (effects (font (size 1.27 1.27))))
          (number "9" (effects (font (size 1.27 1.27))))
        )
      )
    )
	(symbol "kria-k26-devboard:R_0R_0402" (pin_numbers hide) (pin_names hide) (in_bom yes) (on_board yes)
      (property "Reference" "R" (at 20.32 -5.08 0)
        (effects (font (size 1.27 1.27) (thickness 0.15)) (justify left bottom))
      )
      (property "Value" "R_0R_0402" (at 20.32 -12.7 0)
        (effects (font (size 1.27 1.27) (thickness 0.15)) (justify left bottom) hide)
      )
      (property "Footprint" "kria-k26-devboard-footprints:R_0402_1005Metric" (at 20.32 -15.24 0)
        (effects (font (size 1.27 1.27) (thickness 0.15)) (justify left bottom) hide)
      )
      (property "Datasheet" "https://industrial.panasonic.com/cdbs/www-data/pdf/RDA0000/AOA0000C301.pdf" (at 20.32 -17.78 0)
        (effects (font (size 1.27 1.27) (thickness 0.15)) (justify left bottom) hide)
      )
      (property "MPN" "ERJ2GE0R00X" (at 20.32 -20.32 0)
        (effects (font (size 1.27 1.27) (thickness 0.15)) (justify left bottom) hide)
      )
      (property "Manufacturer" "Panasonic" (at 20.32 -22.86 0)
        (effects (font (size 1.27 1.27) (thickness 0.15)) (justify left bottom) hide)
      )
      (property "License" "Apache-2.0" (at 20.32 -25.4 0)
        (effects (font (size 1.27 1.27) (thickness 0.15)) (justify left bottom) hide)
      )
      (property "Author" "Antmicro" (at 20.32 -27.94 0)
        (effects (font (size 1.27 1.27) (thickness 0.15)) (justify left bottom) hide)
      )
      (property "Val" "0R" (at 20.32 -7.62 0)
        (effects (font (size 1.27 1.27) (thickness 0.15)) (justify left bottom))
      )
      (property "Tolerance" "~" (at 20.32 -10.16 0)
        (effects (font (size 1.27 1.27)) (justify left bottom) hide)
      )
      (property "Current" "1A" (at 20.32 -30.48 0)
        (effects (font (size 1.27 1.27) (thickness 0.15)) (justify left bottom) hide)
      )
      (property "ki_description" "0R resistor in 0402 package with unspecified tolerance" (at 0 0 0)
        (effects (font (size 1.27 1.27)) hide)
      )
      (symbol "R_0R_0402_0_1"
        (rectangle (start 0.635 0.889) (end 4.445 -0.889)
          (stroke (width 0.254) (type default))
          (fill (type none))
        )
      )
      (symbol "R_0R_0402_1_1"
        (pin passive line (at 0 0 0) (length 0.635)
          (name "~" (effects (font (size 1.27 1.27))))
          (number "1" (effects (font (size 1.27 1.27))))
        )
        (pin passive line (at 5.08 0 180) (length 0.635)
          (name "~" (effects (font (size 1.27 1.27))))
          (number "2" (effects (font (size 1.27 1.27))))
        )
      )
    )
	(symbol "kria-k26-devboard:R_0R_22.4A_0603" (pin_numbers hide) (pin_names hide) (in_bom yes) (on_board yes)
      (property "Reference" "R" (at 15.24 -2.54 0)
        (effects (font (size 1.27 1.27) (thickness 0.15)) (justify left bottom))
      )
      (property "Value" "R_0R_22.4A_0603" (at 15.24 -5.08 0)
        (effects (font (size 1.27 1.27) (thickness 0.15)) (justify left bottom))
      )
      (property "Footprint" "kria-k26-devboard-footprints:R_0603_1608Metric" (at 15.24 -10.16 0)
        (effects (font (size 1.27 1.27) (thickness 0.15)) (justify left bottom) hide)
      )
      (property "Datasheet" "https://fscdn.rohm.com/en/products/databook/datasheet/passive/resistor/chip_resistor/pmr-jpw-e.pdf" (at 15.24 -12.7 0)
        (effects (font (size 1.27 1.27) (thickness 0.15)) (justify left bottom) hide)
      )
      (property "MPN" "PMR03EZPJ000" (at 15.24 -15.24 0)
        (effects (font (size 1.27 1.27) (thickness 0.15)) (justify left bottom) hide)
      )
      (property "Manufacturer" "ROHM Semiconductor" (at 15.24 -17.78 0)
        (effects (font (size 1.27 1.27) (thickness 0.15)) (justify left bottom) hide)
      )
      (property "Val" "0R" (at 15.24 -7.62 0)
        (effects (font (size 1.27 1.27) (thickness 0.15)) (justify left bottom))
      )
      (property "Max. Curr." "22.4A" (at 15.24 -20.32 0)
        (effects (font (size 1.27 1.27) (thickness 0.15)) (justify left bottom))
      )
      (property "Author" "Antmicro" (at 15.24 -22.86 0)
        (effects (font (size 1.27 1.27) (thickness 0.15)) (justify left bottom) hide)
      )
      (property "License" "Apache-2.0" (at 15.24 -25.4 0)
        (effects (font (size 1.27 1.27) (thickness 0.15)) (justify left bottom) hide)
      )
      (property "Tolerance" "template_tolerance" (at 20.32 -10.16 0)
        (effects (font (size 1.27 1.27)) (justify left bottom) hide)
      )
      (property "ki_keywords" "Metal strip 0Ohm jumper 22.4A high power hpwr current" (at 0 0 0)
        (effects (font (size 1.27 1.27)) hide)
      )
      (property "ki_description" "Metal strip 0Ohm jumper 22.4A" (at 0 0 0)
        (effects (font (size 1.27 1.27)) hide)
      )
      (symbol "R_0R_22.4A_0603_0_1"
        (rectangle (start 0.635 0.889) (end 4.445 -0.889)
          (stroke (width 0.254) (type default))
          (fill (type none))
        )
      )
      (symbol "R_0R_22.4A_0603_1_1"
        (pin passive line (at 0 0 0) (length 0.635)
          (name "~" (effects (font (size 1.27 1.27))))
          (number "1" (effects (font (size 1.27 1.27))))
        )
        (pin passive line (at 5.08 0 180) (length 0.635)
          (name "~" (effects (font (size 1.27 1.27))))
          (number "2" (effects (font (size 1.27 1.27))))
        )
      )
    )
	(symbol "kria-k26-devboard:R_100R_0402" (pin_numbers hide) (pin_names hide) (in_bom yes) (on_board yes)
      (property "Reference" "R" (at 20.32 -5.08 0)
        (effects (font (size 1.27 1.27) (thickness 0.15)) (justify left bottom))
      )
      (property "Value" "R_100R_0402" (at 20.32 -12.7 0)
        (effects (font (size 1.27 1.27) (thickness 0.15)) (justify left bottom) hide)
      )
      (property "Footprint" "kria-k26-devboard-footprints:R_0402_1005Metric" (at 20.32 -15.24 0)
        (effects (font (size 1.27 1.27) (thickness 0.15)) (justify left bottom) hide)
      )
      (property "Datasheet" "https://www.bourns.com/docs/product-datasheets/cr.pdf" (at 20.32 -17.78 0)
        (effects (font (size 1.27 1.27) (thickness 0.15)) (justify left bottom) hide)
      )
      (property "MPN" "CR0402-FX-1000GLF" (at 20.32 -20.32 0)
        (effects (font (size 1.27 1.27) (thickness 0.15)) (justify left bottom) hide)
      )
      (property "Manufacturer" "Bourns" (at 20.32 -22.86 0)
        (effects (font (size 1.27 1.27) (thickness 0.15)) (justify left bottom) hide)
      )
      (property "License" "Apache-2.0" (at 20.32 -25.4 0)
        (effects (font (size 1.27 1.27) (thickness 0.15)) (justify left bottom) hide)
      )
      (property "Author" "Antmicro" (at 20.32 -27.94 0)
        (effects (font (size 1.27 1.27) (thickness 0.15)) (justify left bottom) hide)
      )
      (property "Val" "100R" (at 20.32 -7.62 0)
        (effects (font (size 1.27 1.27) (thickness 0.15)) (justify left bottom))
      )
      (property "Tolerance" "1%" (at 20.32 -10.16 0)
        (effects (font (size 1.27 1.27)) (justify left bottom) hide)
      )
      (property "ki_description" "100R resistor in 0402 package with 1% tolerance" (at 0 0 0)
        (effects (font (size 1.27 1.27)) hide)
      )
      (symbol "R_100R_0402_0_1"
        (rectangle (start 0.635 0.889) (end 4.445 -0.889)
          (stroke (width 0.254) (type default))
          (fill (type none))
        )
      )
      (symbol "R_100R_0402_1_1"
        (pin passive line (at 0 0 0) (length 0.635)
          (name "~" (effects (font (size 1.27 1.27))))
          (number "1" (effects (font (size 1.27 1.27))))
        )
        (pin passive line (at 5.08 0 180) (length 0.635)
          (name "~" (effects (font (size 1.27 1.27))))
          (number "2" (effects (font (size 1.27 1.27))))
        )
      )
    )
	(symbol "kria-k26-devboard:R_100k_0402" (pin_numbers hide) (pin_names hide) (in_bom yes) (on_board yes)
      (property "Reference" "R" (at 20.32 -5.08 0)
        (effects (font (size 1.27 1.27) (thickness 0.15)) (justify left bottom))
      )
      (property "Value" "R_100k_0402" (at 20.32 -12.7 0)
        (effects (font (size 1.27 1.27) (thickness 0.15)) (justify left bottom) hide)
      )
      (property "Footprint" "kria-k26-devboard-footprints:R_0402_1005Metric" (at 20.32 -15.24 0)
        (effects (font (size 1.27 1.27) (thickness 0.15)) (justify left bottom) hide)
      )
      (property "Datasheet" "https://www.bourns.com/docs/product-datasheets/cr.pdf" (at 20.32 -17.78 0)
        (effects (font (size 1.27 1.27) (thickness 0.15)) (justify left bottom) hide)
      )
      (property "MPN" "CR0402-FX-1003GLF" (at 20.32 -20.32 0)
        (effects (font (size 1.27 1.27) (thickness 0.15)) (justify left bottom) hide)
      )
      (property "Manufacturer" "Bourns" (at 20.32 -22.86 0)
        (effects (font (size 1.27 1.27) (thickness 0.15)) (justify left bottom) hide)
      )
      (property "License" "Apache-2.0" (at 20.32 -25.4 0)
        (effects (font (size 1.27 1.27) (thickness 0.15)) (justify left bottom) hide)
      )
      (property "Author" "Antmicro" (at 20.32 -27.94 0)
        (effects (font (size 1.27 1.27) (thickness 0.15)) (justify left bottom) hide)
      )
      (property "Val" "100k" (at 20.32 -7.62 0)
        (effects (font (size 1.27 1.27) (thickness 0.15)) (justify left bottom))
      )
      (property "Tolerance" "1%" (at 20.32 -10.16 0)
        (effects (font (size 1.27 1.27)) (justify left bottom) hide)
      )
      (property "ki_description" "100k resistor in 0402 package with 1% tolerance" (at 0 0 0)
        (effects (font (size 1.27 1.27)) hide)
      )
      (symbol "R_100k_0402_0_1"
        (rectangle (start 0.635 0.889) (end 4.445 -0.889)
          (stroke (width 0.254) (type default))
          (fill (type none))
        )
      )
      (symbol "R_100k_0402_1_1"
        (pin passive line (at 0 0 0) (length 0.635)
          (name "~" (effects (font (size 1.27 1.27))))
          (number "1" (effects (font (size 1.27 1.27))))
        )
        (pin passive line (at 5.08 0 180) (length 0.635)
          (name "~" (effects (font (size 1.27 1.27))))
          (number "2" (effects (font (size 1.27 1.27))))
        )
      )
    )
	(symbol "kria-k26-devboard:R_10k_0402" (pin_numbers hide) (pin_names hide) (in_bom yes) (on_board yes)
      (property "Reference" "R" (at 20.32 -5.08 0)
        (effects (font (size 1.27 1.27) (thickness 0.15)) (justify left bottom))
      )
      (property "Value" "R_10k_0402" (at 20.32 -12.7 0)
        (effects (font (size 1.27 1.27) (thickness 0.15)) (justify left bottom) hide)
      )
      (property "Footprint" "kria-k26-devboard-footprints:R_0402_1005Metric" (at 20.32 -15.24 0)
        (effects (font (size 1.27 1.27) (thickness 0.15)) (justify left bottom) hide)
      )
      (property "Datasheet" "https://www.bourns.com/docs/product-datasheets/cr.pdf" (at 20.32 -17.78 0)
        (effects (font (size 1.27 1.27) (thickness 0.15)) (justify left bottom) hide)
      )
      (property "MPN" "CR0402-FX-1002GLF" (at 20.32 -20.32 0)
        (effects (font (size 1.27 1.27) (thickness 0.15)) (justify left bottom) hide)
      )
      (property "Manufacturer" "Bourns" (at 20.32 -22.86 0)
        (effects (font (size 1.27 1.27) (thickness 0.15)) (justify left bottom) hide)
      )
      (property "License" "Apache-2.0" (at 20.32 -25.4 0)
        (effects (font (size 1.27 1.27) (thickness 0.15)) (justify left bottom) hide)
      )
      (property "Author" "Antmicro" (at 20.32 -27.94 0)
        (effects (font (size 1.27 1.27) (thickness 0.15)) (justify left bottom) hide)
      )
      (property "Val" "10k" (at 20.32 -7.62 0)
        (effects (font (size 1.27 1.27) (thickness 0.15)) (justify left bottom))
      )
      (property "Tolerance" "1%" (at 20.32 -10.16 0)
        (effects (font (size 1.27 1.27)) (justify left bottom) hide)
      )
      (property "ki_description" "10k resistor in 0402 package with 1% tolerance" (at 0 0 0)
        (effects (font (size 1.27 1.27)) hide)
      )
      (symbol "R_10k_0402_0_1"
        (rectangle (start 0.635 0.889) (end 4.445 -0.889)
          (stroke (width 0.254) (type default))
          (fill (type none))
        )
      )
      (symbol "R_10k_0402_1_1"
        (pin passive line (at 0 0 0) (length 0.635)
          (name "~" (effects (font (size 1.27 1.27))))
          (number "1" (effects (font (size 1.27 1.27))))
        )
        (pin passive line (at 5.08 0 180) (length 0.635)
          (name "~" (effects (font (size 1.27 1.27))))
          (number "2" (effects (font (size 1.27 1.27))))
        )
      )
    )
	(symbol "kria-k26-devboard:R_11k_0402" (pin_numbers hide) (pin_names hide) (in_bom yes) (on_board yes)
      (property "Reference" "R" (at 20.32 -5.08 0)
        (effects (font (size 1.27 1.27) (thickness 0.15)) (justify left bottom))
      )
      (property "Value" "R_11k_0402" (at 20.32 -12.7 0)
        (effects (font (size 1.27 1.27) (thickness 0.15)) (justify left bottom) hide)
      )
      (property "Footprint" "kria-k26-devboard-footprints:R_0402_1005Metric" (at 20.32 -15.24 0)
        (effects (font (size 1.27 1.27) (thickness 0.15)) (justify left bottom) hide)
      )
      (property "Datasheet" "https://www.bourns.com/docs/product-datasheets/cr.pdf" (at 20.32 -17.78 0)
        (effects (font (size 1.27 1.27) (thickness 0.15)) (justify left bottom) hide)
      )
      (property "MPN" "CR0402-FX-1102GLF" (at 20.32 -20.32 0)
        (effects (font (size 1.27 1.27) (thickness 0.15)) (justify left bottom) hide)
      )
      (property "Manufacturer" "Bourns" (at 20.32 -22.86 0)
        (effects (font (size 1.27 1.27) (thickness 0.15)) (justify left bottom) hide)
      )
      (property "License" "Apache-2.0" (at 20.32 -25.4 0)
        (effects (font (size 1.27 1.27) (thickness 0.15)) (justify left bottom) hide)
      )
      (property "Author" "Antmicro" (at 20.32 -27.94 0)
        (effects (font (size 1.27 1.27) (thickness 0.15)) (justify left bottom) hide)
      )
      (property "Val" "11k" (at 20.32 -7.62 0)
        (effects (font (size 1.27 1.27) (thickness 0.15)) (justify left bottom))
      )
      (property "Tolerance" "1%" (at 20.32 -10.16 0)
        (effects (font (size 1.27 1.27)) (justify left bottom) hide)
      )
      (property "ki_description" "11k resistor in 0402 package with 1% tolerance" (at 0 0 0)
        (effects (font (size 1.27 1.27)) hide)
      )
      (symbol "R_11k_0402_0_1"
        (rectangle (start 0.635 0.889) (end 4.445 -0.889)
          (stroke (width 0.254) (type default))
          (fill (type none))
        )
      )
      (symbol "R_11k_0402_1_1"
        (pin passive line (at 0 0 0) (length 0.635)
          (name "~" (effects (font (size 1.27 1.27))))
          (number "1" (effects (font (size 1.27 1.27))))
        )
        (pin passive line (at 5.08 0 180) (length 0.635)
          (name "~" (effects (font (size 1.27 1.27))))
          (number "2" (effects (font (size 1.27 1.27))))
        )
      )
    )
	(symbol "kria-k26-devboard:R_12k4_0402" (pin_numbers hide) (pin_names hide) (in_bom yes) (on_board yes)
      (property "Reference" "R" (at 20.32 -5.08 0)
        (effects (font (size 1.27 1.27) (thickness 0.15)) (justify left bottom))
      )
      (property "Value" "R_12k4_0402" (at 20.32 -12.7 0)
        (effects (font (size 1.27 1.27) (thickness 0.15)) (justify left bottom) hide)
      )
      (property "Footprint" "kria-k26-devboard-footprints:R_0402_1005Metric" (at 20.32 -15.24 0)
        (effects (font (size 1.27 1.27) (thickness 0.15)) (justify left bottom) hide)
      )
      (property "Datasheet" "https://www.bourns.com/docs/product-datasheets/cr.pdf" (at 20.32 -17.78 0)
        (effects (font (size 1.27 1.27) (thickness 0.15)) (justify left bottom) hide)
      )
      (property "MPN" "CR0402-FX-1242GLF" (at 20.32 -20.32 0)
        (effects (font (size 1.27 1.27) (thickness 0.15)) (justify left bottom) hide)
      )
      (property "Manufacturer" "Bourns" (at 20.32 -22.86 0)
        (effects (font (size 1.27 1.27) (thickness 0.15)) (justify left bottom) hide)
      )
      (property "License" "Apache-2.0" (at 20.32 -25.4 0)
        (effects (font (size 1.27 1.27) (thickness 0.15)) (justify left bottom) hide)
      )
      (property "Author" "Antmicro" (at 20.32 -27.94 0)
        (effects (font (size 1.27 1.27) (thickness 0.15)) (justify left bottom) hide)
      )
      (property "Val" "12k4" (at 20.32 -7.62 0)
        (effects (font (size 1.27 1.27) (thickness 0.15)) (justify left bottom))
      )
      (property "Tolerance" "1%" (at 20.32 -10.16 0)
        (effects (font (size 1.27 1.27)) (justify left bottom) hide)
      )
      (property "ki_description" "12k4 resistor in 0402 package with 1% tolerance" (at 0 0 0)
        (effects (font (size 1.27 1.27)) hide)
      )
      (symbol "R_12k4_0402_0_1"
        (rectangle (start 0.635 0.889) (end 4.445 -0.889)
          (stroke (width 0.254) (type default))
          (fill (type none))
        )
      )
      (symbol "R_12k4_0402_1_1"
        (pin passive line (at 0 0 0) (length 0.635)
          (name "~" (effects (font (size 1.27 1.27))))
          (number "1" (effects (font (size 1.27 1.27))))
        )
        (pin passive line (at 5.08 0 180) (length 0.635)
          (name "~" (effects (font (size 1.27 1.27))))
          (number "2" (effects (font (size 1.27 1.27))))
        )
      )
    )
	(symbol "kria-k26-devboard:R_12k_0402" (pin_numbers hide) (pin_names hide) (in_bom yes) (on_board yes)
      (property "Reference" "R" (at 20.32 -5.08 0)
        (effects (font (size 1.27 1.27) (thickness 0.15)) (justify left bottom))
      )
      (property "Value" "R_12k_0402" (at 20.32 -12.7 0)
        (effects (font (size 1.27 1.27) (thickness 0.15)) (justify left bottom) hide)
      )
      (property "Footprint" "kria-k26-devboard-footprints:R_0402_1005Metric" (at 20.32 -15.24 0)
        (effects (font (size 1.27 1.27) (thickness 0.15)) (justify left bottom) hide)
      )
      (property "Datasheet" "https://www.bourns.com/docs/product-datasheets/cr.pdf" (at 20.32 -17.78 0)
        (effects (font (size 1.27 1.27) (thickness 0.15)) (justify left bottom) hide)
      )
      (property "MPN" "CR0402-FX-1202GLF" (at 20.32 -20.32 0)
        (effects (font (size 1.27 1.27) (thickness 0.15)) (justify left bottom) hide)
      )
      (property "Manufacturer" "Bourns" (at 20.32 -22.86 0)
        (effects (font (size 1.27 1.27) (thickness 0.15)) (justify left bottom) hide)
      )
      (property "License" "Apache-2.0" (at 20.32 -25.4 0)
        (effects (font (size 1.27 1.27) (thickness 0.15)) (justify left bottom) hide)
      )
      (property "Author" "Antmicro" (at 20.32 -27.94 0)
        (effects (font (size 1.27 1.27) (thickness 0.15)) (justify left bottom) hide)
      )
      (property "Val" "12k" (at 20.32 -7.62 0)
        (effects (font (size 1.27 1.27) (thickness 0.15)) (justify left bottom))
      )
      (property "Tolerance" "1%" (at 20.32 -10.16 0)
        (effects (font (size 1.27 1.27)) (justify left bottom) hide)
      )
      (property "ki_description" "12k resistor in 0402 package with 1% tolerance" (at 0 0 0)
        (effects (font (size 1.27 1.27)) hide)
      )
      (symbol "R_12k_0402_0_1"
        (rectangle (start 0.635 0.889) (end 4.445 -0.889)
          (stroke (width 0.254) (type default))
          (fill (type none))
        )
      )
      (symbol "R_12k_0402_1_1"
        (pin passive line (at 0 0 0) (length 0.635)
          (name "~" (effects (font (size 1.27 1.27))))
          (number "1" (effects (font (size 1.27 1.27))))
        )
        (pin passive line (at 5.08 0 180) (length 0.635)
          (name "~" (effects (font (size 1.27 1.27))))
          (number "2" (effects (font (size 1.27 1.27))))
        )
      )
    )
	(symbol "kria-k26-devboard:R_147k_0402" (pin_numbers hide) (pin_names hide) (in_bom yes) (on_board yes)
      (property "Reference" "R" (at 20.32 -5.08 0)
        (effects (font (size 1.27 1.27) (thickness 0.15)) (justify left bottom))
      )
      (property "Value" "R_147k_0402" (at 20.32 -12.7 0)
        (effects (font (size 1.27 1.27) (thickness 0.15)) (justify left bottom) hide)
      )
      (property "Footprint" "kria-k26-devboard-footprints:R_0402_1005Metric" (at 20.32 -15.24 0)
        (effects (font (size 1.27 1.27) (thickness 0.15)) (justify left bottom) hide)
      )
      (property "Datasheet" "https://www.bourns.com/docs/product-datasheets/cr.pdf" (at 20.32 -17.78 0)
        (effects (font (size 1.27 1.27) (thickness 0.15)) (justify left bottom) hide)
      )
      (property "MPN" "CR0402-FX-1473GLF" (at 20.32 -20.32 0)
        (effects (font (size 1.27 1.27) (thickness 0.15)) (justify left bottom) hide)
      )
      (property "Manufacturer" "Bourns" (at 20.32 -22.86 0)
        (effects (font (size 1.27 1.27) (thickness 0.15)) (justify left bottom) hide)
      )
      (property "License" "Apache-2.0" (at 20.32 -25.4 0)
        (effects (font (size 1.27 1.27) (thickness 0.15)) (justify left bottom) hide)
      )
      (property "Author" "Antmicro" (at 20.32 -27.94 0)
        (effects (font (size 1.27 1.27) (thickness 0.15)) (justify left bottom) hide)
      )
      (property "Val" "147k" (at 20.32 -7.62 0)
        (effects (font (size 1.27 1.27) (thickness 0.15)) (justify left bottom))
      )
      (property "Tolerance" "1%" (at 20.32 -10.16 0)
        (effects (font (size 1.27 1.27)) (justify left bottom) hide)
      )
      (property "ki_description" "147k resistor in 0402 package with 1% tolerance" (at 0 0 0)
        (effects (font (size 1.27 1.27)) hide)
      )
      (symbol "R_147k_0402_0_1"
        (rectangle (start 0.635 0.889) (end 4.445 -0.889)
          (stroke (width 0.254) (type default))
          (fill (type none))
        )
      )
      (symbol "R_147k_0402_1_1"
        (pin passive line (at 0 0 0) (length 0.635)
          (name "~" (effects (font (size 1.27 1.27))))
          (number "1" (effects (font (size 1.27 1.27))))
        )
        (pin passive line (at 5.08 0 180) (length 0.635)
          (name "~" (effects (font (size 1.27 1.27))))
          (number "2" (effects (font (size 1.27 1.27))))
        )
      )
    )
	(symbol "kria-k26-devboard:R_15k_0603" (pin_numbers hide) (pin_names hide) (in_bom yes) (on_board yes)
      (property "Reference" "R" (at 20.32 -5.08 0)
        (effects (font (size 1.27 1.27) (thickness 0.15)) (justify left bottom))
      )
      (property "Value" "R_15k_0603" (at 20.32 -12.7 0)
        (effects (font (size 1.27 1.27) (thickness 0.15)) (justify left bottom) hide)
      )
      (property "Footprint" "kria-k26-devboard-footprints:R_0603_1608Metric" (at 20.32 -15.24 0)
        (effects (font (size 1.27 1.27) (thickness 0.15)) (justify left bottom) hide)
      )
      (property "Datasheet" "https://www.bourns.com/docs/product-datasheets/cr.pdf" (at 20.32 -17.78 0)
        (effects (font (size 1.27 1.27) (thickness 0.15)) (justify left bottom) hide)
      )
      (property "MPN" "CR0603-FX-1502ELF" (at 20.32 -20.32 0)
        (effects (font (size 1.27 1.27) (thickness 0.15)) (justify left bottom) hide)
      )
      (property "Manufacturer" "Bourns" (at 20.32 -22.86 0)
        (effects (font (size 1.27 1.27) (thickness 0.15)) (justify left bottom) hide)
      )
      (property "License" "Apache-2.0" (at 20.32 -25.4 0)
        (effects (font (size 1.27 1.27) (thickness 0.15)) (justify left bottom) hide)
      )
      (property "Author" "Antmicro" (at 20.32 -27.94 0)
        (effects (font (size 1.27 1.27) (thickness 0.15)) (justify left bottom) hide)
      )
      (property "Val" "15k" (at 20.32 -7.62 0)
        (effects (font (size 1.27 1.27) (thickness 0.15)) (justify left bottom))
      )
      (property "Tolerance" "1%" (at 20.32 -10.16 0)
        (effects (font (size 1.27 1.27)) (justify left bottom) hide)
      )
      (property "ki_description" "15k resistor in 0603 package with 1% tolerance" (at 0 0 0)
        (effects (font (size 1.27 1.27)) hide)
      )
      (symbol "R_15k_0603_0_1"
        (rectangle (start 0.635 0.889) (end 4.445 -0.889)
          (stroke (width 0.254) (type default))
          (fill (type none))
        )
      )
      (symbol "R_15k_0603_1_1"
        (pin passive line (at 0 0 0) (length 0.635)
          (name "~" (effects (font (size 1.27 1.27))))
          (number "1" (effects (font (size 1.27 1.27))))
        )
        (pin passive line (at 5.08 0 180) (length 0.635)
          (name "~" (effects (font (size 1.27 1.27))))
          (number "2" (effects (font (size 1.27 1.27))))
        )
      )
    )
	(symbol "kria-k26-devboard:R_15k_2010" (pin_numbers hide) (pin_names hide) (in_bom yes) (on_board yes)
      (property "Reference" "R" (at 20.32 -5.08 0)
        (effects (font (size 1.27 1.27) (thickness 0.15)) (justify left bottom))
      )
      (property "Value" "R_15k_2010" (at 20.32 -12.7 0)
        (effects (font (size 1.27 1.27) (thickness 0.15)) (justify left bottom) hide)
      )
      (property "Footprint" "kria-k26-devboard-footprints:R_2010_5025Metric" (at 20.32 -15.24 0)
        (effects (font (size 1.27 1.27) (thickness 0.15)) (justify left bottom) hide)
      )
      (property "Datasheet" "https://www.bourns.com/docs/product-datasheets/cr.pdf" (at 20.32 -17.78 0)
        (effects (font (size 1.27 1.27) (thickness 0.15)) (justify left bottom) hide)
      )
      (property "MPN" "CR2010-FX-1502ELF" (at 20.32 -20.32 0)
        (effects (font (size 1.27 1.27) (thickness 0.15)) (justify left bottom) hide)
      )
      (property "Manufacturer" "Bourns" (at 20.32 -22.86 0)
        (effects (font (size 1.27 1.27) (thickness 0.15)) (justify left bottom) hide)
      )
      (property "License" "Apache-2.0" (at 20.32 -25.4 0)
        (effects (font (size 1.27 1.27) (thickness 0.15)) (justify left bottom) hide)
      )
      (property "Author" "Antmicro" (at 20.32 -27.94 0)
        (effects (font (size 1.27 1.27) (thickness 0.15)) (justify left bottom) hide)
      )
      (property "Val" "15k" (at 20.32 -7.62 0)
        (effects (font (size 1.27 1.27) (thickness 0.15)) (justify left bottom))
      )
      (property "Tolerance" "1%" (at 20.32 -10.16 0)
        (effects (font (size 1.27 1.27)) (justify left bottom) hide)
      )
      (property "ki_description" "15k resistor in 2010 package with 1% tolerance" (at 0 0 0)
        (effects (font (size 1.27 1.27)) hide)
      )
      (symbol "R_15k_2010_0_1"
        (rectangle (start 0.635 0.889) (end 4.445 -0.889)
          (stroke (width 0.254) (type default))
          (fill (type none))
        )
      )
      (symbol "R_15k_2010_1_1"
        (pin passive line (at 0 0 0) (length 0.635)
          (name "~" (effects (font (size 1.27 1.27))))
          (number "1" (effects (font (size 1.27 1.27))))
        )
        (pin passive line (at 5.08 0 180) (length 0.635)
          (name "~" (effects (font (size 1.27 1.27))))
          (number "2" (effects (font (size 1.27 1.27))))
        )
      )
    )
	(symbol "kria-k26-devboard:R_1M_0402" (pin_numbers hide) (pin_names hide) (in_bom yes) (on_board yes)
      (property "Reference" "R" (at 20.32 -5.08 0)
        (effects (font (size 1.27 1.27) (thickness 0.15)) (justify left bottom))
      )
      (property "Value" "R_1M_0402" (at 20.32 -12.7 0)
        (effects (font (size 1.27 1.27) (thickness 0.15)) (justify left bottom) hide)
      )
      (property "Footprint" "kria-k26-devboard-footprints:R_0402_1005Metric" (at 20.32 -15.24 0)
        (effects (font (size 1.27 1.27) (thickness 0.15)) (justify left bottom) hide)
      )
      (property "Datasheet" "https://www.bourns.com/docs/product-datasheets/cr.pdf" (at 20.32 -17.78 0)
        (effects (font (size 1.27 1.27) (thickness 0.15)) (justify left bottom) hide)
      )
      (property "MPN" "CR0402-FX-1004GLF" (at 20.32 -20.32 0)
        (effects (font (size 1.27 1.27) (thickness 0.15)) (justify left bottom) hide)
      )
      (property "Manufacturer" "Bourns" (at 20.32 -22.86 0)
        (effects (font (size 1.27 1.27) (thickness 0.15)) (justify left bottom) hide)
      )
      (property "License" "Apache-2.0" (at 20.32 -25.4 0)
        (effects (font (size 1.27 1.27) (thickness 0.15)) (justify left bottom) hide)
      )
      (property "Author" "Antmicro" (at 20.32 -27.94 0)
        (effects (font (size 1.27 1.27) (thickness 0.15)) (justify left bottom) hide)
      )
      (property "Val" "1M" (at 20.32 -7.62 0)
        (effects (font (size 1.27 1.27) (thickness 0.15)) (justify left bottom))
      )
      (property "Tolerance" "1%" (at 20.32 -10.16 0)
        (effects (font (size 1.27 1.27)) (justify left bottom) hide)
      )
      (property "ki_description" "1M resistor in 0402 package with 1% tolerance" (at 0 0 0)
        (effects (font (size 1.27 1.27)) hide)
      )
      (symbol "R_1M_0402_0_1"
        (rectangle (start 0.635 0.889) (end 4.445 -0.889)
          (stroke (width 0.254) (type default))
          (fill (type none))
        )
      )
      (symbol "R_1M_0402_1_1"
        (pin passive line (at 0 0 0) (length 0.635)
          (name "~" (effects (font (size 1.27 1.27))))
          (number "1" (effects (font (size 1.27 1.27))))
        )
        (pin passive line (at 5.08 0 180) (length 0.635)
          (name "~" (effects (font (size 1.27 1.27))))
          (number "2" (effects (font (size 1.27 1.27))))
        )
      )
    )
	(symbol "kria-k26-devboard:R_1k5_0402" (pin_numbers hide) (pin_names hide) (in_bom yes) (on_board yes)
      (property "Reference" "R" (at 20.32 -5.08 0)
        (effects (font (size 1.27 1.27) (thickness 0.15)) (justify left bottom))
      )
      (property "Value" "R_1k5_0402" (at 20.32 -12.7 0)
        (effects (font (size 1.27 1.27) (thickness 0.15)) (justify left bottom) hide)
      )
      (property "Footprint" "kria-k26-devboard-footprints:R_0402_1005Metric" (at 20.32 -15.24 0)
        (effects (font (size 1.27 1.27) (thickness 0.15)) (justify left bottom) hide)
      )
      (property "Datasheet" "https://www.bourns.com/docs/product-datasheets/cr.pdf" (at 20.32 -17.78 0)
        (effects (font (size 1.27 1.27) (thickness 0.15)) (justify left bottom) hide)
      )
      (property "MPN" "CR0402-FX-1501GLF" (at 20.32 -20.32 0)
        (effects (font (size 1.27 1.27) (thickness 0.15)) (justify left bottom) hide)
      )
      (property "Manufacturer" "Bourns" (at 20.32 -22.86 0)
        (effects (font (size 1.27 1.27) (thickness 0.15)) (justify left bottom) hide)
      )
      (property "License" "Apache-2.0" (at 20.32 -25.4 0)
        (effects (font (size 1.27 1.27) (thickness 0.15)) (justify left bottom) hide)
      )
      (property "Author" "Antmicro" (at 20.32 -27.94 0)
        (effects (font (size 1.27 1.27) (thickness 0.15)) (justify left bottom) hide)
      )
      (property "Val" "1k5" (at 20.32 -7.62 0)
        (effects (font (size 1.27 1.27) (thickness 0.15)) (justify left bottom))
      )
      (property "Tolerance" "1%" (at 20.32 -10.16 0)
        (effects (font (size 1.27 1.27)) (justify left bottom) hide)
      )
      (property "ki_description" "1k5 resistor in 0402 package with 1% tolerance" (at 0 0 0)
        (effects (font (size 1.27 1.27)) hide)
      )
      (symbol "R_1k5_0402_0_1"
        (rectangle (start 0.635 0.889) (end 4.445 -0.889)
          (stroke (width 0.254) (type default))
          (fill (type none))
        )
      )
      (symbol "R_1k5_0402_1_1"
        (pin passive line (at 0 0 0) (length 0.635)
          (name "~" (effects (font (size 1.27 1.27))))
          (number "1" (effects (font (size 1.27 1.27))))
        )
        (pin passive line (at 5.08 0 180) (length 0.635)
          (name "~" (effects (font (size 1.27 1.27))))
          (number "2" (effects (font (size 1.27 1.27))))
        )
      )
    )
	(symbol "kria-k26-devboard:R_1k_0402" (pin_numbers hide) (pin_names hide) (in_bom yes) (on_board yes)
      (property "Reference" "R" (at 20.32 -5.08 0)
        (effects (font (size 1.27 1.27) (thickness 0.15)) (justify left bottom))
      )
      (property "Value" "R_1k_0402" (at 20.32 -12.7 0)
        (effects (font (size 1.27 1.27) (thickness 0.15)) (justify left bottom) hide)
      )
      (property "Footprint" "kria-k26-devboard-footprints:R_0402_1005Metric" (at 20.32 -15.24 0)
        (effects (font (size 1.27 1.27) (thickness 0.15)) (justify left bottom) hide)
      )
      (property "Datasheet" "https://www.bourns.com/docs/product-datasheets/cr.pdf" (at 20.32 -17.78 0)
        (effects (font (size 1.27 1.27) (thickness 0.15)) (justify left bottom) hide)
      )
      (property "MPN" "CR0402-FX-1001GLF" (at 20.32 -20.32 0)
        (effects (font (size 1.27 1.27) (thickness 0.15)) (justify left bottom) hide)
      )
      (property "Manufacturer" "Bourns" (at 20.32 -22.86 0)
        (effects (font (size 1.27 1.27) (thickness 0.15)) (justify left bottom) hide)
      )
      (property "License" "Apache-2.0" (at 20.32 -25.4 0)
        (effects (font (size 1.27 1.27) (thickness 0.15)) (justify left bottom) hide)
      )
      (property "Author" "Antmicro" (at 20.32 -27.94 0)
        (effects (font (size 1.27 1.27) (thickness 0.15)) (justify left bottom) hide)
      )
      (property "Val" "1k" (at 20.32 -7.62 0)
        (effects (font (size 1.27 1.27) (thickness 0.15)) (justify left bottom))
      )
      (property "Tolerance" "1%" (at 20.32 -10.16 0)
        (effects (font (size 1.27 1.27)) (justify left bottom) hide)
      )
      (property "ki_description" "1k resistor in 0402 package with 1% tolerance" (at 0 0 0)
        (effects (font (size 1.27 1.27)) hide)
      )
      (symbol "R_1k_0402_0_1"
        (rectangle (start 0.635 0.889) (end 4.445 -0.889)
          (stroke (width 0.254) (type default))
          (fill (type none))
        )
      )
      (symbol "R_1k_0402_1_1"
        (pin passive line (at 0 0 0) (length 0.635)
          (name "~" (effects (font (size 1.27 1.27))))
          (number "1" (effects (font (size 1.27 1.27))))
        )
        (pin passive line (at 5.08 0 180) (length 0.635)
          (name "~" (effects (font (size 1.27 1.27))))
          (number "2" (effects (font (size 1.27 1.27))))
        )
      )
    )
	(symbol "kria-k26-devboard:R_200k_0402" (pin_numbers hide) (pin_names hide) (in_bom yes) (on_board yes)
      (property "Reference" "R" (at 20.32 -5.08 0)
        (effects (font (size 1.27 1.27) (thickness 0.15)) (justify left bottom))
      )
      (property "Value" "R_200k_0402" (at 20.32 -12.7 0)
        (effects (font (size 1.27 1.27) (thickness 0.15)) (justify left bottom) hide)
      )
      (property "Footprint" "kria-k26-devboard-footprints:R_0402_1005Metric" (at 20.32 -15.24 0)
        (effects (font (size 1.27 1.27) (thickness 0.15)) (justify left bottom) hide)
      )
      (property "Datasheet" "https://www.bourns.com/docs/product-datasheets/cr.pdf" (at 20.32 -17.78 0)
        (effects (font (size 1.27 1.27) (thickness 0.15)) (justify left bottom) hide)
      )
      (property "MPN" "CR0402-FX-2003GLF" (at 20.32 -20.32 0)
        (effects (font (size 1.27 1.27) (thickness 0.15)) (justify left bottom) hide)
      )
      (property "Manufacturer" "Bourns" (at 20.32 -22.86 0)
        (effects (font (size 1.27 1.27) (thickness 0.15)) (justify left bottom) hide)
      )
      (property "License" "Apache-2.0" (at 20.32 -25.4 0)
        (effects (font (size 1.27 1.27) (thickness 0.15)) (justify left bottom) hide)
      )
      (property "Author" "Antmicro" (at 20.32 -27.94 0)
        (effects (font (size 1.27 1.27) (thickness 0.15)) (justify left bottom) hide)
      )
      (property "Val" "200k" (at 20.32 -7.62 0)
        (effects (font (size 1.27 1.27) (thickness 0.15)) (justify left bottom))
      )
      (property "Tolerance" "1%" (at 20.32 -10.16 0)
        (effects (font (size 1.27 1.27)) (justify left bottom) hide)
      )
      (property "ki_description" "200k resistor in 0402 package with 1% tolerance" (at 0 0 0)
        (effects (font (size 1.27 1.27)) hide)
      )
      (symbol "R_200k_0402_0_1"
        (rectangle (start 0.635 0.889) (end 4.445 -0.889)
          (stroke (width 0.254) (type default))
          (fill (type none))
        )
      )
      (symbol "R_200k_0402_1_1"
        (pin passive line (at 0 0 0) (length 0.635)
          (name "~" (effects (font (size 1.27 1.27))))
          (number "1" (effects (font (size 1.27 1.27))))
        )
        (pin passive line (at 5.08 0 180) (length 0.635)
          (name "~" (effects (font (size 1.27 1.27))))
          (number "2" (effects (font (size 1.27 1.27))))
        )
      )
    )
	(symbol "kria-k26-devboard:R_200k_0402_10" (pin_numbers hide) (pin_names hide) (in_bom yes) (on_board yes)
      (property "Reference" "R" (at 20.32 -5.08 0)
        (effects (font (size 1.27 1.27) (thickness 0.15)) (justify left bottom))
      )
      (property "Value" "R_200k_0402_10" (at 20.32 -12.7 0)
        (effects (font (size 1.27 1.27) (thickness 0.15)) (justify left bottom) hide)
      )
      (property "Footprint" "kria-k26-devboard-footprints:R_0402_1005Metric" (at 20.32 -15.24 0)
        (effects (font (size 1.27 1.27) (thickness 0.15)) (justify left bottom) hide)
      )
      (property "Datasheet" "https://www.bourns.com/docs/product-datasheets/cr.pdf" (at 20.32 -17.78 0)
        (effects (font (size 1.27 1.27) (thickness 0.15)) (justify left bottom) hide)
      )
      (property "MPN" "CR0402-FX-2003GLF" (at 20.32 -20.32 0)
        (effects (font (size 1.27 1.27) (thickness 0.15)) (justify left bottom) hide)
      )
      (property "Manufacturer" "Bourns" (at 20.32 -22.86 0)
        (effects (font (size 1.27 1.27) (thickness 0.15)) (justify left bottom) hide)
      )
      (property "License" "Apache-2.0" (at 20.32 -25.4 0)
        (effects (font (size 1.27 1.27) (thickness 0.15)) (justify left bottom) hide)
      )
      (property "Author" "Antmicro" (at 20.32 -27.94 0)
        (effects (font (size 1.27 1.27) (thickness 0.15)) (justify left bottom) hide)
      )
      (property "Val" "200k" (at 20.32 -7.62 0)
        (effects (font (size 1.27 1.27) (thickness 0.15)) (justify left bottom))
      )
      (property "Tolerance" "1%" (at 20.32 -10.16 0)
        (effects (font (size 1.27 1.27)) (justify left bottom) hide)
      )
      (property "ki_description" "200k resistor in 0402 package with 1% tolerance" (at 0 0 0)
        (effects (font (size 1.27 1.27)) hide)
      )
      (symbol "R_200k_0402_10_0_1"
        (rectangle (start 0.635 0.889) (end 4.445 -0.889)
          (stroke (width 0.254) (type default))
          (fill (type none))
        )
      )
      (symbol "R_200k_0402_10_1_1"
        (pin passive line (at 0 0 0) (length 0.635)
          (name "~" (effects (font (size 1.27 1.27))))
          (number "1" (effects (font (size 1.27 1.27))))
        )
        (pin passive line (at 5.08 0 180) (length 0.635)
          (name "~" (effects (font (size 1.27 1.27))))
          (number "2" (effects (font (size 1.27 1.27))))
        )
      )
    )
	(symbol "kria-k26-devboard:R_200k_0402_11" (pin_numbers hide) (pin_names hide) (in_bom yes) (on_board yes)
      (property "Reference" "R" (at 20.32 -5.08 0)
        (effects (font (size 1.27 1.27) (thickness 0.15)) (justify left bottom))
      )
      (property "Value" "R_200k_0402_11" (at 20.32 -12.7 0)
        (effects (font (size 1.27 1.27) (thickness 0.15)) (justify left bottom) hide)
      )
      (property "Footprint" "kria-k26-devboard-footprints:R_0402_1005Metric" (at 20.32 -15.24 0)
        (effects (font (size 1.27 1.27) (thickness 0.15)) (justify left bottom) hide)
      )
      (property "Datasheet" "https://www.bourns.com/docs/product-datasheets/cr.pdf" (at 20.32 -17.78 0)
        (effects (font (size 1.27 1.27) (thickness 0.15)) (justify left bottom) hide)
      )
      (property "MPN" "CR0402-FX-2003GLF" (at 20.32 -20.32 0)
        (effects (font (size 1.27 1.27) (thickness 0.15)) (justify left bottom) hide)
      )
      (property "Manufacturer" "Bourns" (at 20.32 -22.86 0)
        (effects (font (size 1.27 1.27) (thickness 0.15)) (justify left bottom) hide)
      )
      (property "License" "Apache-2.0" (at 20.32 -25.4 0)
        (effects (font (size 1.27 1.27) (thickness 0.15)) (justify left bottom) hide)
      )
      (property "Author" "Antmicro" (at 20.32 -27.94 0)
        (effects (font (size 1.27 1.27) (thickness 0.15)) (justify left bottom) hide)
      )
      (property "Val" "200k" (at 20.32 -7.62 0)
        (effects (font (size 1.27 1.27) (thickness 0.15)) (justify left bottom))
      )
      (property "Tolerance" "1%" (at 20.32 -10.16 0)
        (effects (font (size 1.27 1.27)) (justify left bottom) hide)
      )
      (property "ki_description" "200k resistor in 0402 package with 1% tolerance" (at 0 0 0)
        (effects (font (size 1.27 1.27)) hide)
      )
      (symbol "R_200k_0402_11_0_1"
        (rectangle (start 0.635 0.889) (end 4.445 -0.889)
          (stroke (width 0.254) (type default))
          (fill (type none))
        )
      )
      (symbol "R_200k_0402_11_1_1"
        (pin passive line (at 0 0 0) (length 0.635)
          (name "~" (effects (font (size 1.27 1.27))))
          (number "1" (effects (font (size 1.27 1.27))))
        )
        (pin passive line (at 5.08 0 180) (length 0.635)
          (name "~" (effects (font (size 1.27 1.27))))
          (number "2" (effects (font (size 1.27 1.27))))
        )
      )
    )
	(symbol "kria-k26-devboard:R_200k_0402_12" (pin_numbers hide) (pin_names hide) (in_bom yes) (on_board yes)
      (property "Reference" "R" (at 20.32 -5.08 0)
        (effects (font (size 1.27 1.27) (thickness 0.15)) (justify left bottom))
      )
      (property "Value" "R_200k_0402_12" (at 20.32 -12.7 0)
        (effects (font (size 1.27 1.27) (thickness 0.15)) (justify left bottom) hide)
      )
      (property "Footprint" "kria-k26-devboard-footprints:R_0402_1005Metric" (at 20.32 -15.24 0)
        (effects (font (size 1.27 1.27) (thickness 0.15)) (justify left bottom) hide)
      )
      (property "Datasheet" "https://www.bourns.com/docs/product-datasheets/cr.pdf" (at 20.32 -17.78 0)
        (effects (font (size 1.27 1.27) (thickness 0.15)) (justify left bottom) hide)
      )
      (property "MPN" "CR0402-FX-2003GLF" (at 20.32 -20.32 0)
        (effects (font (size 1.27 1.27) (thickness 0.15)) (justify left bottom) hide)
      )
      (property "Manufacturer" "Bourns" (at 20.32 -22.86 0)
        (effects (font (size 1.27 1.27) (thickness 0.15)) (justify left bottom) hide)
      )
      (property "License" "Apache-2.0" (at 20.32 -25.4 0)
        (effects (font (size 1.27 1.27) (thickness 0.15)) (justify left bottom) hide)
      )
      (property "Author" "Antmicro" (at 20.32 -27.94 0)
        (effects (font (size 1.27 1.27) (thickness 0.15)) (justify left bottom) hide)
      )
      (property "Val" "200k" (at 20.32 -7.62 0)
        (effects (font (size 1.27 1.27) (thickness 0.15)) (justify left bottom))
      )
      (property "Tolerance" "1%" (at 20.32 -10.16 0)
        (effects (font (size 1.27 1.27)) (justify left bottom) hide)
      )
      (property "ki_description" "200k resistor in 0402 package with 1% tolerance" (at 0 0 0)
        (effects (font (size 1.27 1.27)) hide)
      )
      (symbol "R_200k_0402_12_0_1"
        (rectangle (start 0.635 0.889) (end 4.445 -0.889)
          (stroke (width 0.254) (type default))
          (fill (type none))
        )
      )
      (symbol "R_200k_0402_12_1_1"
        (pin passive line (at 0 0 0) (length 0.635)
          (name "~" (effects (font (size 1.27 1.27))))
          (number "1" (effects (font (size 1.27 1.27))))
        )
        (pin passive line (at 5.08 0 180) (length 0.635)
          (name "~" (effects (font (size 1.27 1.27))))
          (number "2" (effects (font (size 1.27 1.27))))
        )
      )
    )
	(symbol "kria-k26-devboard:R_200k_0402_13" (pin_numbers hide) (pin_names hide) (in_bom yes) (on_board yes)
      (property "Reference" "R" (at 20.32 -5.08 0)
        (effects (font (size 1.27 1.27) (thickness 0.15)) (justify left bottom))
      )
      (property "Value" "R_200k_0402_13" (at 20.32 -12.7 0)
        (effects (font (size 1.27 1.27) (thickness 0.15)) (justify left bottom) hide)
      )
      (property "Footprint" "kria-k26-devboard-footprints:R_0402_1005Metric" (at 20.32 -15.24 0)
        (effects (font (size 1.27 1.27) (thickness 0.15)) (justify left bottom) hide)
      )
      (property "Datasheet" "https://www.bourns.com/docs/product-datasheets/cr.pdf" (at 20.32 -17.78 0)
        (effects (font (size 1.27 1.27) (thickness 0.15)) (justify left bottom) hide)
      )
      (property "MPN" "CR0402-FX-2003GLF" (at 20.32 -20.32 0)
        (effects (font (size 1.27 1.27) (thickness 0.15)) (justify left bottom) hide)
      )
      (property "Manufacturer" "Bourns" (at 20.32 -22.86 0)
        (effects (font (size 1.27 1.27) (thickness 0.15)) (justify left bottom) hide)
      )
      (property "License" "Apache-2.0" (at 20.32 -25.4 0)
        (effects (font (size 1.27 1.27) (thickness 0.15)) (justify left bottom) hide)
      )
      (property "Author" "Antmicro" (at 20.32 -27.94 0)
        (effects (font (size 1.27 1.27) (thickness 0.15)) (justify left bottom) hide)
      )
      (property "Val" "200k" (at 20.32 -7.62 0)
        (effects (font (size 1.27 1.27) (thickness 0.15)) (justify left bottom))
      )
      (property "Tolerance" "1%" (at 20.32 -10.16 0)
        (effects (font (size 1.27 1.27)) (justify left bottom) hide)
      )
      (property "ki_description" "200k resistor in 0402 package with 1% tolerance" (at 0 0 0)
        (effects (font (size 1.27 1.27)) hide)
      )
      (symbol "R_200k_0402_13_0_1"
        (rectangle (start 0.635 0.889) (end 4.445 -0.889)
          (stroke (width 0.254) (type default))
          (fill (type none))
        )
      )
      (symbol "R_200k_0402_13_1_1"
        (pin passive line (at 0 0 0) (length 0.635)
          (name "~" (effects (font (size 1.27 1.27))))
          (number "1" (effects (font (size 1.27 1.27))))
        )
        (pin passive line (at 5.08 0 180) (length 0.635)
          (name "~" (effects (font (size 1.27 1.27))))
          (number "2" (effects (font (size 1.27 1.27))))
        )
      )
    )
	(symbol "kria-k26-devboard:R_200k_0402_14" (pin_numbers hide) (pin_names hide) (in_bom yes) (on_board yes)
      (property "Reference" "R" (at 20.32 -5.08 0)
        (effects (font (size 1.27 1.27) (thickness 0.15)) (justify left bottom))
      )
      (property "Value" "R_200k_0402_14" (at 20.32 -12.7 0)
        (effects (font (size 1.27 1.27) (thickness 0.15)) (justify left bottom) hide)
      )
      (property "Footprint" "kria-k26-devboard-footprints:R_0402_1005Metric" (at 20.32 -15.24 0)
        (effects (font (size 1.27 1.27) (thickness 0.15)) (justify left bottom) hide)
      )
      (property "Datasheet" "https://www.bourns.com/docs/product-datasheets/cr.pdf" (at 20.32 -17.78 0)
        (effects (font (size 1.27 1.27) (thickness 0.15)) (justify left bottom) hide)
      )
      (property "MPN" "CR0402-FX-2003GLF" (at 20.32 -20.32 0)
        (effects (font (size 1.27 1.27) (thickness 0.15)) (justify left bottom) hide)
      )
      (property "Manufacturer" "Bourns" (at 20.32 -22.86 0)
        (effects (font (size 1.27 1.27) (thickness 0.15)) (justify left bottom) hide)
      )
      (property "License" "Apache-2.0" (at 20.32 -25.4 0)
        (effects (font (size 1.27 1.27) (thickness 0.15)) (justify left bottom) hide)
      )
      (property "Author" "Antmicro" (at 20.32 -27.94 0)
        (effects (font (size 1.27 1.27) (thickness 0.15)) (justify left bottom) hide)
      )
      (property "Val" "200k" (at 20.32 -7.62 0)
        (effects (font (size 1.27 1.27) (thickness 0.15)) (justify left bottom))
      )
      (property "Tolerance" "1%" (at 20.32 -10.16 0)
        (effects (font (size 1.27 1.27)) (justify left bottom) hide)
      )
      (property "ki_description" "200k resistor in 0402 package with 1% tolerance" (at 0 0 0)
        (effects (font (size 1.27 1.27)) hide)
      )
      (symbol "R_200k_0402_14_0_1"
        (rectangle (start 0.635 0.889) (end 4.445 -0.889)
          (stroke (width 0.254) (type default))
          (fill (type none))
        )
      )
      (symbol "R_200k_0402_14_1_1"
        (pin passive line (at 0 0 0) (length 0.635)
          (name "~" (effects (font (size 1.27 1.27))))
          (number "1" (effects (font (size 1.27 1.27))))
        )
        (pin passive line (at 5.08 0 180) (length 0.635)
          (name "~" (effects (font (size 1.27 1.27))))
          (number "2" (effects (font (size 1.27 1.27))))
        )
      )
    )
	(symbol "kria-k26-devboard:R_200k_0402_15" (pin_numbers hide) (pin_names hide) (in_bom yes) (on_board yes)
      (property "Reference" "R" (at 20.32 -5.08 0)
        (effects (font (size 1.27 1.27) (thickness 0.15)) (justify left bottom))
      )
      (property "Value" "R_200k_0402_15" (at 20.32 -12.7 0)
        (effects (font (size 1.27 1.27) (thickness 0.15)) (justify left bottom) hide)
      )
      (property "Footprint" "kria-k26-devboard-footprints:R_0402_1005Metric" (at 20.32 -15.24 0)
        (effects (font (size 1.27 1.27) (thickness 0.15)) (justify left bottom) hide)
      )
      (property "Datasheet" "https://www.bourns.com/docs/product-datasheets/cr.pdf" (at 20.32 -17.78 0)
        (effects (font (size 1.27 1.27) (thickness 0.15)) (justify left bottom) hide)
      )
      (property "MPN" "CR0402-FX-2003GLF" (at 20.32 -20.32 0)
        (effects (font (size 1.27 1.27) (thickness 0.15)) (justify left bottom) hide)
      )
      (property "Manufacturer" "Bourns" (at 20.32 -22.86 0)
        (effects (font (size 1.27 1.27) (thickness 0.15)) (justify left bottom) hide)
      )
      (property "License" "Apache-2.0" (at 20.32 -25.4 0)
        (effects (font (size 1.27 1.27) (thickness 0.15)) (justify left bottom) hide)
      )
      (property "Author" "Antmicro" (at 20.32 -27.94 0)
        (effects (font (size 1.27 1.27) (thickness 0.15)) (justify left bottom) hide)
      )
      (property "Val" "200k" (at 20.32 -7.62 0)
        (effects (font (size 1.27 1.27) (thickness 0.15)) (justify left bottom))
      )
      (property "Tolerance" "1%" (at 20.32 -10.16 0)
        (effects (font (size 1.27 1.27)) (justify left bottom) hide)
      )
      (property "ki_description" "200k resistor in 0402 package with 1% tolerance" (at 0 0 0)
        (effects (font (size 1.27 1.27)) hide)
      )
      (symbol "R_200k_0402_15_0_1"
        (rectangle (start 0.635 0.889) (end 4.445 -0.889)
          (stroke (width 0.254) (type default))
          (fill (type none))
        )
      )
      (symbol "R_200k_0402_15_1_1"
        (pin passive line (at 0 0 0) (length 0.635)
          (name "~" (effects (font (size 1.27 1.27))))
          (number "1" (effects (font (size 1.27 1.27))))
        )
        (pin passive line (at 5.08 0 180) (length 0.635)
          (name "~" (effects (font (size 1.27 1.27))))
          (number "2" (effects (font (size 1.27 1.27))))
        )
      )
    )
	(symbol "kria-k26-devboard:R_200k_0402_16" (pin_numbers hide) (pin_names hide) (in_bom yes) (on_board yes)
      (property "Reference" "R" (at 20.32 -5.08 0)
        (effects (font (size 1.27 1.27) (thickness 0.15)) (justify left bottom))
      )
      (property "Value" "R_200k_0402_16" (at 20.32 -12.7 0)
        (effects (font (size 1.27 1.27) (thickness 0.15)) (justify left bottom) hide)
      )
      (property "Footprint" "kria-k26-devboard-footprints:R_0402_1005Metric" (at 20.32 -15.24 0)
        (effects (font (size 1.27 1.27) (thickness 0.15)) (justify left bottom) hide)
      )
      (property "Datasheet" "https://www.bourns.com/docs/product-datasheets/cr.pdf" (at 20.32 -17.78 0)
        (effects (font (size 1.27 1.27) (thickness 0.15)) (justify left bottom) hide)
      )
      (property "MPN" "CR0402-FX-2003GLF" (at 20.32 -20.32 0)
        (effects (font (size 1.27 1.27) (thickness 0.15)) (justify left bottom) hide)
      )
      (property "Manufacturer" "Bourns" (at 20.32 -22.86 0)
        (effects (font (size 1.27 1.27) (thickness 0.15)) (justify left bottom) hide)
      )
      (property "License" "Apache-2.0" (at 20.32 -25.4 0)
        (effects (font (size 1.27 1.27) (thickness 0.15)) (justify left bottom) hide)
      )
      (property "Author" "Antmicro" (at 20.32 -27.94 0)
        (effects (font (size 1.27 1.27) (thickness 0.15)) (justify left bottom) hide)
      )
      (property "Val" "200k" (at 20.32 -7.62 0)
        (effects (font (size 1.27 1.27) (thickness 0.15)) (justify left bottom))
      )
      (property "Tolerance" "1%" (at 20.32 -10.16 0)
        (effects (font (size 1.27 1.27)) (justify left bottom) hide)
      )
      (property "ki_description" "200k resistor in 0402 package with 1% tolerance" (at 0 0 0)
        (effects (font (size 1.27 1.27)) hide)
      )
      (symbol "R_200k_0402_16_0_1"
        (rectangle (start 0.635 0.889) (end 4.445 -0.889)
          (stroke (width 0.254) (type default))
          (fill (type none))
        )
      )
      (symbol "R_200k_0402_16_1_1"
        (pin passive line (at 0 0 0) (length 0.635)
          (name "~" (effects (font (size 1.27 1.27))))
          (number "1" (effects (font (size 1.27 1.27))))
        )
        (pin passive line (at 5.08 0 180) (length 0.635)
          (name "~" (effects (font (size 1.27 1.27))))
          (number "2" (effects (font (size 1.27 1.27))))
        )
      )
    )
	(symbol "kria-k26-devboard:R_200k_0402_17" (pin_numbers hide) (pin_names hide) (in_bom yes) (on_board yes)
      (property "Reference" "R" (at 20.32 -5.08 0)
        (effects (font (size 1.27 1.27) (thickness 0.15)) (justify left bottom))
      )
      (property "Value" "R_200k_0402_17" (at 20.32 -12.7 0)
        (effects (font (size 1.27 1.27) (thickness 0.15)) (justify left bottom) hide)
      )
      (property "Footprint" "kria-k26-devboard-footprints:R_0402_1005Metric" (at 20.32 -15.24 0)
        (effects (font (size 1.27 1.27) (thickness 0.15)) (justify left bottom) hide)
      )
      (property "Datasheet" "https://www.bourns.com/docs/product-datasheets/cr.pdf" (at 20.32 -17.78 0)
        (effects (font (size 1.27 1.27) (thickness 0.15)) (justify left bottom) hide)
      )
      (property "MPN" "CR0402-FX-2003GLF" (at 20.32 -20.32 0)
        (effects (font (size 1.27 1.27) (thickness 0.15)) (justify left bottom) hide)
      )
      (property "Manufacturer" "Bourns" (at 20.32 -22.86 0)
        (effects (font (size 1.27 1.27) (thickness 0.15)) (justify left bottom) hide)
      )
      (property "License" "Apache-2.0" (at 20.32 -25.4 0)
        (effects (font (size 1.27 1.27) (thickness 0.15)) (justify left bottom) hide)
      )
      (property "Author" "Antmicro" (at 20.32 -27.94 0)
        (effects (font (size 1.27 1.27) (thickness 0.15)) (justify left bottom) hide)
      )
      (property "Val" "200k" (at 20.32 -7.62 0)
        (effects (font (size 1.27 1.27) (thickness 0.15)) (justify left bottom))
      )
      (property "Tolerance" "1%" (at 20.32 -10.16 0)
        (effects (font (size 1.27 1.27)) (justify left bottom) hide)
      )
      (property "ki_description" "200k resistor in 0402 package with 1% tolerance" (at 0 0 0)
        (effects (font (size 1.27 1.27)) hide)
      )
      (symbol "R_200k_0402_17_0_1"
        (rectangle (start 0.635 0.889) (end 4.445 -0.889)
          (stroke (width 0.254) (type default))
          (fill (type none))
        )
      )
      (symbol "R_200k_0402_17_1_1"
        (pin passive line (at 0 0 0) (length 0.635)
          (name "~" (effects (font (size 1.27 1.27))))
          (number "1" (effects (font (size 1.27 1.27))))
        )
        (pin passive line (at 5.08 0 180) (length 0.635)
          (name "~" (effects (font (size 1.27 1.27))))
          (number "2" (effects (font (size 1.27 1.27))))
        )
      )
    )
	(symbol "kria-k26-devboard:R_200k_0402_18" (pin_numbers hide) (pin_names hide) (in_bom yes) (on_board yes)
      (property "Reference" "R" (at 20.32 -5.08 0)
        (effects (font (size 1.27 1.27) (thickness 0.15)) (justify left bottom))
      )
      (property "Value" "R_200k_0402_18" (at 20.32 -12.7 0)
        (effects (font (size 1.27 1.27) (thickness 0.15)) (justify left bottom) hide)
      )
      (property "Footprint" "kria-k26-devboard-footprints:R_0402_1005Metric" (at 20.32 -15.24 0)
        (effects (font (size 1.27 1.27) (thickness 0.15)) (justify left bottom) hide)
      )
      (property "Datasheet" "https://www.bourns.com/docs/product-datasheets/cr.pdf" (at 20.32 -17.78 0)
        (effects (font (size 1.27 1.27) (thickness 0.15)) (justify left bottom) hide)
      )
      (property "MPN" "CR0402-FX-2003GLF" (at 20.32 -20.32 0)
        (effects (font (size 1.27 1.27) (thickness 0.15)) (justify left bottom) hide)
      )
      (property "Manufacturer" "Bourns" (at 20.32 -22.86 0)
        (effects (font (size 1.27 1.27) (thickness 0.15)) (justify left bottom) hide)
      )
      (property "License" "Apache-2.0" (at 20.32 -25.4 0)
        (effects (font (size 1.27 1.27) (thickness 0.15)) (justify left bottom) hide)
      )
      (property "Author" "Antmicro" (at 20.32 -27.94 0)
        (effects (font (size 1.27 1.27) (thickness 0.15)) (justify left bottom) hide)
      )
      (property "Val" "200k" (at 20.32 -7.62 0)
        (effects (font (size 1.27 1.27) (thickness 0.15)) (justify left bottom))
      )
      (property "Tolerance" "1%" (at 20.32 -10.16 0)
        (effects (font (size 1.27 1.27)) (justify left bottom) hide)
      )
      (property "ki_description" "200k resistor in 0402 package with 1% tolerance" (at 0 0 0)
        (effects (font (size 1.27 1.27)) hide)
      )
      (symbol "R_200k_0402_18_0_1"
        (rectangle (start 0.635 0.889) (end 4.445 -0.889)
          (stroke (width 0.254) (type default))
          (fill (type none))
        )
      )
      (symbol "R_200k_0402_18_1_1"
        (pin passive line (at 0 0 0) (length 0.635)
          (name "~" (effects (font (size 1.27 1.27))))
          (number "1" (effects (font (size 1.27 1.27))))
        )
        (pin passive line (at 5.08 0 180) (length 0.635)
          (name "~" (effects (font (size 1.27 1.27))))
          (number "2" (effects (font (size 1.27 1.27))))
        )
      )
    )
	(symbol "kria-k26-devboard:R_200k_0402_19" (pin_numbers hide) (pin_names hide) (in_bom yes) (on_board yes)
      (property "Reference" "R" (at 20.32 -5.08 0)
        (effects (font (size 1.27 1.27) (thickness 0.15)) (justify left bottom))
      )
      (property "Value" "R_200k_0402_19" (at 20.32 -12.7 0)
        (effects (font (size 1.27 1.27) (thickness 0.15)) (justify left bottom) hide)
      )
      (property "Footprint" "kria-k26-devboard-footprints:R_0402_1005Metric" (at 20.32 -15.24 0)
        (effects (font (size 1.27 1.27) (thickness 0.15)) (justify left bottom) hide)
      )
      (property "Datasheet" "https://www.bourns.com/docs/product-datasheets/cr.pdf" (at 20.32 -17.78 0)
        (effects (font (size 1.27 1.27) (thickness 0.15)) (justify left bottom) hide)
      )
      (property "MPN" "CR0402-FX-2003GLF" (at 20.32 -20.32 0)
        (effects (font (size 1.27 1.27) (thickness 0.15)) (justify left bottom) hide)
      )
      (property "Manufacturer" "Bourns" (at 20.32 -22.86 0)
        (effects (font (size 1.27 1.27) (thickness 0.15)) (justify left bottom) hide)
      )
      (property "License" "Apache-2.0" (at 20.32 -25.4 0)
        (effects (font (size 1.27 1.27) (thickness 0.15)) (justify left bottom) hide)
      )
      (property "Author" "Antmicro" (at 20.32 -27.94 0)
        (effects (font (size 1.27 1.27) (thickness 0.15)) (justify left bottom) hide)
      )
      (property "Val" "200k" (at 20.32 -7.62 0)
        (effects (font (size 1.27 1.27) (thickness 0.15)) (justify left bottom))
      )
      (property "Tolerance" "1%" (at 20.32 -10.16 0)
        (effects (font (size 1.27 1.27)) (justify left bottom) hide)
      )
      (property "ki_description" "200k resistor in 0402 package with 1% tolerance" (at 0 0 0)
        (effects (font (size 1.27 1.27)) hide)
      )
      (symbol "R_200k_0402_19_0_1"
        (rectangle (start 0.635 0.889) (end 4.445 -0.889)
          (stroke (width 0.254) (type default))
          (fill (type none))
        )
      )
      (symbol "R_200k_0402_19_1_1"
        (pin passive line (at 0 0 0) (length 0.635)
          (name "~" (effects (font (size 1.27 1.27))))
          (number "1" (effects (font (size 1.27 1.27))))
        )
        (pin passive line (at 5.08 0 180) (length 0.635)
          (name "~" (effects (font (size 1.27 1.27))))
          (number "2" (effects (font (size 1.27 1.27))))
        )
      )
    )
	(symbol "kria-k26-devboard:R_21k5_0402" (pin_numbers hide) (pin_names hide) (in_bom yes) (on_board yes)
      (property "Reference" "R" (at 20.32 -5.08 0)
        (effects (font (size 1.27 1.27) (thickness 0.15)) (justify left bottom))
      )
      (property "Value" "R_21k5_0402" (at 20.32 -12.7 0)
        (effects (font (size 1.27 1.27) (thickness 0.15)) (justify left bottom) hide)
      )
      (property "Footprint" "kria-k26-devboard-footprints:R_0402_1005Metric" (at 20.32 -15.24 0)
        (effects (font (size 1.27 1.27) (thickness 0.15)) (justify left bottom) hide)
      )
      (property "Datasheet" "https://www.bourns.com/docs/product-datasheets/cr.pdf" (at 20.32 -17.78 0)
        (effects (font (size 1.27 1.27) (thickness 0.15)) (justify left bottom) hide)
      )
      (property "MPN" "CR0402-FX-2152GLF" (at 20.32 -20.32 0)
        (effects (font (size 1.27 1.27) (thickness 0.15)) (justify left bottom) hide)
      )
      (property "Manufacturer" "Bourns" (at 20.32 -22.86 0)
        (effects (font (size 1.27 1.27) (thickness 0.15)) (justify left bottom) hide)
      )
      (property "License" "Apache-2.0" (at 20.32 -25.4 0)
        (effects (font (size 1.27 1.27) (thickness 0.15)) (justify left bottom) hide)
      )
      (property "Author" "Antmicro" (at 20.32 -27.94 0)
        (effects (font (size 1.27 1.27) (thickness 0.15)) (justify left bottom) hide)
      )
      (property "Val" "21k5" (at 20.32 -7.62 0)
        (effects (font (size 1.27 1.27) (thickness 0.15)) (justify left bottom))
      )
      (property "Tolerance" "1%" (at 20.32 -10.16 0)
        (effects (font (size 1.27 1.27)) (justify left bottom) hide)
      )
      (property "ki_description" "21k5 resistor in 0402 package with 1% tolerance" (at 0 0 0)
        (effects (font (size 1.27 1.27)) hide)
      )
      (symbol "R_21k5_0402_0_1"
        (rectangle (start 0.635 0.889) (end 4.445 -0.889)
          (stroke (width 0.254) (type default))
          (fill (type none))
        )
      )
      (symbol "R_21k5_0402_1_1"
        (pin passive line (at 0 0 0) (length 0.635)
          (name "~" (effects (font (size 1.27 1.27))))
          (number "1" (effects (font (size 1.27 1.27))))
        )
        (pin passive line (at 5.08 0 180) (length 0.635)
          (name "~" (effects (font (size 1.27 1.27))))
          (number "2" (effects (font (size 1.27 1.27))))
        )
      )
    )
	(symbol "kria-k26-devboard:R_24k9_0402" (pin_numbers hide) (pin_names hide) (in_bom yes) (on_board yes)
      (property "Reference" "R" (at 20.32 -5.08 0)
        (effects (font (size 1.27 1.27) (thickness 0.15)) (justify left bottom))
      )
      (property "Value" "R_24k9_0402" (at 20.32 -12.7 0)
        (effects (font (size 1.27 1.27) (thickness 0.15)) (justify left bottom) hide)
      )
      (property "Footprint" "kria-k26-devboard-footprints:R_0402_1005Metric" (at 20.32 -15.24 0)
        (effects (font (size 1.27 1.27) (thickness 0.15)) (justify left bottom) hide)
      )
      (property "Datasheet" "https://www.bourns.com/docs/product-datasheets/cr.pdf" (at 20.32 -17.78 0)
        (effects (font (size 1.27 1.27) (thickness 0.15)) (justify left bottom) hide)
      )
      (property "MPN" "CR0402-FX-2492GLF" (at 20.32 -20.32 0)
        (effects (font (size 1.27 1.27) (thickness 0.15)) (justify left bottom) hide)
      )
      (property "Manufacturer" "Bourns" (at 20.32 -22.86 0)
        (effects (font (size 1.27 1.27) (thickness 0.15)) (justify left bottom) hide)
      )
      (property "License" "Apache-2.0" (at 20.32 -25.4 0)
        (effects (font (size 1.27 1.27) (thickness 0.15)) (justify left bottom) hide)
      )
      (property "Author" "Antmicro" (at 20.32 -27.94 0)
        (effects (font (size 1.27 1.27) (thickness 0.15)) (justify left bottom) hide)
      )
      (property "Val" "24k9" (at 20.32 -7.62 0)
        (effects (font (size 1.27 1.27) (thickness 0.15)) (justify left bottom))
      )
      (property "Tolerance" "1%" (at 20.32 -10.16 0)
        (effects (font (size 1.27 1.27)) (justify left bottom) hide)
      )
      (property "ki_description" "24k9 resistor in 0402 package with 1% tolerance" (at 0 0 0)
        (effects (font (size 1.27 1.27)) hide)
      )
      (symbol "R_24k9_0402_0_1"
        (rectangle (start 0.635 0.889) (end 4.445 -0.889)
          (stroke (width 0.254) (type default))
          (fill (type none))
        )
      )
      (symbol "R_24k9_0402_1_1"
        (pin passive line (at 0 0 0) (length 0.635)
          (name "~" (effects (font (size 1.27 1.27))))
          (number "1" (effects (font (size 1.27 1.27))))
        )
        (pin passive line (at 5.08 0 180) (length 0.635)
          (name "~" (effects (font (size 1.27 1.27))))
          (number "2" (effects (font (size 1.27 1.27))))
        )
      )
    )
	(symbol "kria-k26-devboard:R_24k_0402" (pin_numbers hide) (pin_names hide) (in_bom yes) (on_board yes)
      (property "Reference" "R" (at 20.32 -5.08 0)
        (effects (font (size 1.27 1.27) (thickness 0.15)) (justify left bottom))
      )
      (property "Value" "R_24k_0402" (at 20.32 -12.7 0)
        (effects (font (size 1.27 1.27) (thickness 0.15)) (justify left bottom) hide)
      )
      (property "Footprint" "kria-k26-devboard-footprints:R_0402_1005Metric" (at 20.32 -15.24 0)
        (effects (font (size 1.27 1.27) (thickness 0.15)) (justify left bottom) hide)
      )
      (property "Datasheet" "https://www.bourns.com/docs/product-datasheets/cr.pdf" (at 20.32 -17.78 0)
        (effects (font (size 1.27 1.27) (thickness 0.15)) (justify left bottom) hide)
      )
      (property "MPN" "CR0402-FX-2402GLF" (at 20.32 -20.32 0)
        (effects (font (size 1.27 1.27) (thickness 0.15)) (justify left bottom) hide)
      )
      (property "Manufacturer" "Bourns" (at 20.32 -22.86 0)
        (effects (font (size 1.27 1.27) (thickness 0.15)) (justify left bottom) hide)
      )
      (property "License" "Apache-2.0" (at 20.32 -25.4 0)
        (effects (font (size 1.27 1.27) (thickness 0.15)) (justify left bottom) hide)
      )
      (property "Author" "Antmicro" (at 20.32 -27.94 0)
        (effects (font (size 1.27 1.27) (thickness 0.15)) (justify left bottom) hide)
      )
      (property "Val" "24k" (at 20.32 -7.62 0)
        (effects (font (size 1.27 1.27) (thickness 0.15)) (justify left bottom))
      )
      (property "Tolerance" "1%" (at 20.32 -10.16 0)
        (effects (font (size 1.27 1.27)) (justify left bottom) hide)
      )
      (property "ki_description" "24k resistor in 0402 package with 1% tolerance" (at 0 0 0)
        (effects (font (size 1.27 1.27)) hide)
      )
      (symbol "R_24k_0402_0_1"
        (rectangle (start 0.635 0.889) (end 4.445 -0.889)
          (stroke (width 0.254) (type default))
          (fill (type none))
        )
      )
      (symbol "R_24k_0402_1_1"
        (pin passive line (at 0 0 0) (length 0.635)
          (name "~" (effects (font (size 1.27 1.27))))
          (number "1" (effects (font (size 1.27 1.27))))
        )
        (pin passive line (at 5.08 0 180) (length 0.635)
          (name "~" (effects (font (size 1.27 1.27))))
          (number "2" (effects (font (size 1.27 1.27))))
        )
      )
    )
	(symbol "kria-k26-devboard:R_2k2_0402" (pin_numbers hide) (pin_names hide) (in_bom yes) (on_board yes)
      (property "Reference" "R" (at 20.32 -5.08 0)
        (effects (font (size 1.27 1.27) (thickness 0.15)) (justify left bottom))
      )
      (property "Value" "R_2k2_0402" (at 20.32 -12.7 0)
        (effects (font (size 1.27 1.27) (thickness 0.15)) (justify left bottom) hide)
      )
      (property "Footprint" "kria-k26-devboard-footprints:R_0402_1005Metric" (at 20.32 -15.24 0)
        (effects (font (size 1.27 1.27) (thickness 0.15)) (justify left bottom) hide)
      )
      (property "Datasheet" "https://www.bourns.com/docs/product-datasheets/cr.pdf" (at 20.32 -17.78 0)
        (effects (font (size 1.27 1.27) (thickness 0.15)) (justify left bottom) hide)
      )
      (property "MPN" "CR0402-FX-2201GLF" (at 20.32 -20.32 0)
        (effects (font (size 1.27 1.27) (thickness 0.15)) (justify left bottom) hide)
      )
      (property "Manufacturer" "Bourns" (at 20.32 -22.86 0)
        (effects (font (size 1.27 1.27) (thickness 0.15)) (justify left bottom) hide)
      )
      (property "License" "Apache-2.0" (at 20.32 -25.4 0)
        (effects (font (size 1.27 1.27) (thickness 0.15)) (justify left bottom) hide)
      )
      (property "Author" "Antmicro" (at 20.32 -27.94 0)
        (effects (font (size 1.27 1.27) (thickness 0.15)) (justify left bottom) hide)
      )
      (property "Val" "2k2" (at 20.32 -7.62 0)
        (effects (font (size 1.27 1.27) (thickness 0.15)) (justify left bottom))
      )
      (property "Tolerance" "1%" (at 20.32 -10.16 0)
        (effects (font (size 1.27 1.27)) (justify left bottom) hide)
      )
      (property "ki_description" "2k2 resistor in 0402 package with 1% tolerance" (at 0 0 0)
        (effects (font (size 1.27 1.27)) hide)
      )
      (symbol "R_2k2_0402_0_1"
        (rectangle (start 0.635 0.889) (end 4.445 -0.889)
          (stroke (width 0.254) (type default))
          (fill (type none))
        )
      )
      (symbol "R_2k2_0402_1_1"
        (pin passive line (at 0 0 0) (length 0.635)
          (name "~" (effects (font (size 1.27 1.27))))
          (number "1" (effects (font (size 1.27 1.27))))
        )
        (pin passive line (at 5.08 0 180) (length 0.635)
          (name "~" (effects (font (size 1.27 1.27))))
          (number "2" (effects (font (size 1.27 1.27))))
        )
      )
    )
	(symbol "kria-k26-devboard:R_2k49_0402" (pin_numbers hide) (pin_names hide) (in_bom yes) (on_board yes)
      (property "Reference" "R" (at 20.32 -5.08 0)
        (effects (font (size 1.27 1.27) (thickness 0.15)) (justify left bottom))
      )
      (property "Value" "R_2k49_0402" (at 20.32 -12.7 0)
        (effects (font (size 1.27 1.27) (thickness 0.15)) (justify left bottom) hide)
      )
      (property "Footprint" "kria-k26-devboard-footprints:R_0402_1005Metric" (at 20.32 -15.24 0)
        (effects (font (size 1.27 1.27) (thickness 0.15)) (justify left bottom) hide)
      )
      (property "Datasheet" "https://www.bourns.com/docs/product-datasheets/cr.pdf" (at 20.32 -17.78 0)
        (effects (font (size 1.27 1.27) (thickness 0.15)) (justify left bottom) hide)
      )
      (property "MPN" "CR0402-FX-2491GLF" (at 20.32 -20.32 0)
        (effects (font (size 1.27 1.27) (thickness 0.15)) (justify left bottom) hide)
      )
      (property "Manufacturer" "Bourns" (at 20.32 -22.86 0)
        (effects (font (size 1.27 1.27) (thickness 0.15)) (justify left bottom) hide)
      )
      (property "License" "Apache-2.0" (at 20.32 -25.4 0)
        (effects (font (size 1.27 1.27) (thickness 0.15)) (justify left bottom) hide)
      )
      (property "Author" "Antmicro" (at 20.32 -27.94 0)
        (effects (font (size 1.27 1.27) (thickness 0.15)) (justify left bottom) hide)
      )
      (property "Val" "2k49" (at 20.32 -7.62 0)
        (effects (font (size 1.27 1.27) (thickness 0.15)) (justify left bottom))
      )
      (property "Tolerance" "1%" (at 20.32 -10.16 0)
        (effects (font (size 1.27 1.27)) (justify left bottom) hide)
      )
      (property "ki_description" "2k49 resistor in 0402 package with 1% tolerance" (at 0 0 0)
        (effects (font (size 1.27 1.27)) hide)
      )
      (symbol "R_2k49_0402_0_1"
        (rectangle (start 0.635 0.889) (end 4.445 -0.889)
          (stroke (width 0.254) (type default))
          (fill (type none))
        )
      )
      (symbol "R_2k49_0402_1_1"
        (pin passive line (at 0 0 0) (length 0.635)
          (name "~" (effects (font (size 1.27 1.27))))
          (number "1" (effects (font (size 1.27 1.27))))
        )
        (pin passive line (at 5.08 0 180) (length 0.635)
          (name "~" (effects (font (size 1.27 1.27))))
          (number "2" (effects (font (size 1.27 1.27))))
        )
      )
    )
	(symbol "kria-k26-devboard:R_31k6_0402" (pin_numbers hide) (pin_names hide) (in_bom yes) (on_board yes)
      (property "Reference" "R" (at 20.32 -5.08 0)
        (effects (font (size 1.27 1.27) (thickness 0.15)) (justify left bottom))
      )
      (property "Value" "R_31k6_0402" (at 20.32 -12.7 0)
        (effects (font (size 1.27 1.27) (thickness 0.15)) (justify left bottom) hide)
      )
      (property "Footprint" "kria-k26-devboard-footprints:R_0402_1005Metric" (at 20.32 -15.24 0)
        (effects (font (size 1.27 1.27) (thickness 0.15)) (justify left bottom) hide)
      )
      (property "Datasheet" "https://www.bourns.com/docs/product-datasheets/cr.pdf" (at 20.32 -17.78 0)
        (effects (font (size 1.27 1.27) (thickness 0.15)) (justify left bottom) hide)
      )
      (property "MPN" "CR0402-FX-3162GLF" (at 20.32 -20.32 0)
        (effects (font (size 1.27 1.27) (thickness 0.15)) (justify left bottom) hide)
      )
      (property "Manufacturer" "Bourns" (at 20.32 -22.86 0)
        (effects (font (size 1.27 1.27) (thickness 0.15)) (justify left bottom) hide)
      )
      (property "License" "Apache-2.0" (at 20.32 -25.4 0)
        (effects (font (size 1.27 1.27) (thickness 0.15)) (justify left bottom) hide)
      )
      (property "Author" "Antmicro" (at 20.32 -27.94 0)
        (effects (font (size 1.27 1.27) (thickness 0.15)) (justify left bottom) hide)
      )
      (property "Val" "31k6" (at 20.32 -7.62 0)
        (effects (font (size 1.27 1.27) (thickness 0.15)) (justify left bottom))
      )
      (property "Tolerance" "1%" (at 20.32 -10.16 0)
        (effects (font (size 1.27 1.27)) (justify left bottom) hide)
      )
      (property "ki_description" "31k6 resistor in 0402 package with 1% tolerance" (at 0 0 0)
        (effects (font (size 1.27 1.27)) hide)
      )
      (symbol "R_31k6_0402_0_1"
        (rectangle (start 0.635 0.889) (end 4.445 -0.889)
          (stroke (width 0.254) (type default))
          (fill (type none))
        )
      )
      (symbol "R_31k6_0402_1_1"
        (pin passive line (at 0 0 0) (length 0.635)
          (name "~" (effects (font (size 1.27 1.27))))
          (number "1" (effects (font (size 1.27 1.27))))
        )
        (pin passive line (at 5.08 0 180) (length 0.635)
          (name "~" (effects (font (size 1.27 1.27))))
          (number "2" (effects (font (size 1.27 1.27))))
        )
      )
    )
	(symbol "kria-k26-devboard:R_32k4_0805" (pin_numbers hide) (pin_names hide) (in_bom yes) (on_board yes)
      (property "Reference" "R" (at 20.32 -5.08 0)
        (effects (font (size 1.27 1.27) (thickness 0.15)) (justify left bottom))
      )
      (property "Value" "R_32k4_0805" (at 20.32 -12.7 0)
        (effects (font (size 1.27 1.27) (thickness 0.15)) (justify left bottom) hide)
      )
      (property "Footprint" "kria-k26-devboard-footprints:R_0805_2012Metric" (at 20.32 -15.24 0)
        (effects (font (size 1.27 1.27) (thickness 0.15)) (justify left bottom) hide)
      )
      (property "Datasheet" "https://www.bourns.com/docs/product-datasheets/cr.pdf" (at 20.32 -17.78 0)
        (effects (font (size 1.27 1.27) (thickness 0.15)) (justify left bottom) hide)
      )
      (property "MPN" "CR0805-FX-3242ELF" (at 20.32 -20.32 0)
        (effects (font (size 1.27 1.27) (thickness 0.15)) (justify left bottom) hide)
      )
      (property "Manufacturer" "Bourns" (at 20.32 -22.86 0)
        (effects (font (size 1.27 1.27) (thickness 0.15)) (justify left bottom) hide)
      )
      (property "License" "Apache-2.0" (at 20.32 -25.4 0)
        (effects (font (size 1.27 1.27) (thickness 0.15)) (justify left bottom) hide)
      )
      (property "Author" "Antmicro" (at 20.32 -27.94 0)
        (effects (font (size 1.27 1.27) (thickness 0.15)) (justify left bottom) hide)
      )
      (property "Val" "32k4" (at 20.32 -7.62 0)
        (effects (font (size 1.27 1.27) (thickness 0.15)) (justify left bottom))
      )
      (property "Tolerance" "1%" (at 20.32 -10.16 0)
        (effects (font (size 1.27 1.27)) (justify left bottom) hide)
      )
      (property "ki_description" "32k4 resistor in 0805 package with 1% tolerance" (at 0 0 0)
        (effects (font (size 1.27 1.27)) hide)
      )
      (symbol "R_32k4_0805_0_1"
        (rectangle (start 0.635 0.889) (end 4.445 -0.889)
          (stroke (width 0.254) (type default))
          (fill (type none))
        )
      )
      (symbol "R_32k4_0805_1_1"
        (pin passive line (at 0 0 0) (length 0.635)
          (name "~" (effects (font (size 1.27 1.27))))
          (number "1" (effects (font (size 1.27 1.27))))
        )
        (pin passive line (at 5.08 0 180) (length 0.635)
          (name "~" (effects (font (size 1.27 1.27))))
          (number "2" (effects (font (size 1.27 1.27))))
        )
      )
    )
	(symbol "kria-k26-devboard:R_330R_0402" (pin_numbers hide) (pin_names hide) (in_bom yes) (on_board yes)
      (property "Reference" "R" (at 20.32 -5.08 0)
        (effects (font (size 1.27 1.27) (thickness 0.15)) (justify left bottom))
      )
      (property "Value" "R_330R_0402" (at 20.32 -12.7 0)
        (effects (font (size 1.27 1.27) (thickness 0.15)) (justify left bottom) hide)
      )
      (property "Footprint" "kria-k26-devboard-footprints:R_0402_1005Metric" (at 20.32 -15.24 0)
        (effects (font (size 1.27 1.27) (thickness 0.15)) (justify left bottom) hide)
      )
      (property "Datasheet" "https://www.bourns.com/docs/product-datasheets/cr.pdf" (at 20.32 -17.78 0)
        (effects (font (size 1.27 1.27) (thickness 0.15)) (justify left bottom) hide)
      )
      (property "MPN" "CR0402-FX-3300GLF" (at 20.32 -20.32 0)
        (effects (font (size 1.27 1.27) (thickness 0.15)) (justify left bottom) hide)
      )
      (property "Manufacturer" "Bourns" (at 20.32 -22.86 0)
        (effects (font (size 1.27 1.27) (thickness 0.15)) (justify left bottom) hide)
      )
      (property "License" "Apache-2.0" (at 20.32 -25.4 0)
        (effects (font (size 1.27 1.27) (thickness 0.15)) (justify left bottom) hide)
      )
      (property "Author" "Antmicro" (at 20.32 -27.94 0)
        (effects (font (size 1.27 1.27) (thickness 0.15)) (justify left bottom) hide)
      )
      (property "Val" "330R" (at 20.32 -7.62 0)
        (effects (font (size 1.27 1.27) (thickness 0.15)) (justify left bottom))
      )
      (property "Tolerance" "1%" (at 20.32 -10.16 0)
        (effects (font (size 1.27 1.27)) (justify left bottom) hide)
      )
      (property "ki_description" "330R resistor in 0402 package with 1% tolerance" (at 0 0 0)
        (effects (font (size 1.27 1.27)) hide)
      )
      (symbol "R_330R_0402_0_1"
        (rectangle (start 0.635 0.889) (end 4.445 -0.889)
          (stroke (width 0.254) (type default))
          (fill (type none))
        )
      )
      (symbol "R_330R_0402_1_1"
        (pin passive line (at 0 0 0) (length 0.635)
          (name "~" (effects (font (size 1.27 1.27))))
          (number "1" (effects (font (size 1.27 1.27))))
        )
        (pin passive line (at 5.08 0 180) (length 0.635)
          (name "~" (effects (font (size 1.27 1.27))))
          (number "2" (effects (font (size 1.27 1.27))))
        )
      )
    )
	(symbol "kria-k26-devboard:R_33R_0402" (pin_numbers hide) (pin_names hide) (in_bom yes) (on_board yes)
      (property "Reference" "R" (at 20.32 -5.08 0)
        (effects (font (size 1.27 1.27) (thickness 0.15)) (justify left bottom))
      )
      (property "Value" "R_33R_0402" (at 20.32 -12.7 0)
        (effects (font (size 1.27 1.27) (thickness 0.15)) (justify left bottom) hide)
      )
      (property "Footprint" "kria-k26-devboard-footprints:R_0402_1005Metric" (at 20.32 -15.24 0)
        (effects (font (size 1.27 1.27) (thickness 0.15)) (justify left bottom) hide)
      )
      (property "Datasheet" "https://www.bourns.com/docs/product-datasheets/cr.pdf" (at 20.32 -17.78 0)
        (effects (font (size 1.27 1.27) (thickness 0.15)) (justify left bottom) hide)
      )
      (property "MPN" "CR0402-FX-33R0GLF" (at 20.32 -20.32 0)
        (effects (font (size 1.27 1.27) (thickness 0.15)) (justify left bottom) hide)
      )
      (property "Manufacturer" "Bourns" (at 20.32 -22.86 0)
        (effects (font (size 1.27 1.27) (thickness 0.15)) (justify left bottom) hide)
      )
      (property "License" "Apache-2.0" (at 20.32 -25.4 0)
        (effects (font (size 1.27 1.27) (thickness 0.15)) (justify left bottom) hide)
      )
      (property "Author" "Antmicro" (at 20.32 -27.94 0)
        (effects (font (size 1.27 1.27) (thickness 0.15)) (justify left bottom) hide)
      )
      (property "Val" "33R" (at 20.32 -7.62 0)
        (effects (font (size 1.27 1.27) (thickness 0.15)) (justify left bottom))
      )
      (property "Tolerance" "1%" (at 20.32 -10.16 0)
        (effects (font (size 1.27 1.27)) (justify left bottom) hide)
      )
      (property "ki_description" "33R resistor in 0402 package with 1% tolerance" (at 0 0 0)
        (effects (font (size 1.27 1.27)) hide)
      )
      (symbol "R_33R_0402_0_1"
        (rectangle (start 0.635 0.889) (end 4.445 -0.889)
          (stroke (width 0.254) (type default))
          (fill (type none))
        )
      )
      (symbol "R_33R_0402_1_1"
        (pin passive line (at 0 0 0) (length 0.635)
          (name "~" (effects (font (size 1.27 1.27))))
          (number "1" (effects (font (size 1.27 1.27))))
        )
        (pin passive line (at 5.08 0 180) (length 0.635)
          (name "~" (effects (font (size 1.27 1.27))))
          (number "2" (effects (font (size 1.27 1.27))))
        )
      )
    )
	(symbol "kria-k26-devboard:R_43k_0402" (pin_numbers hide) (pin_names hide) (in_bom yes) (on_board yes)
      (property "Reference" "R" (at 20.32 -5.08 0)
        (effects (font (size 1.27 1.27) (thickness 0.15)) (justify left bottom))
      )
      (property "Value" "R_43k_0402" (at 20.32 -12.7 0)
        (effects (font (size 1.27 1.27) (thickness 0.15)) (justify left bottom) hide)
      )
      (property "Footprint" "kria-k26-devboard-footprints:R_0402_1005Metric" (at 20.32 -15.24 0)
        (effects (font (size 1.27 1.27) (thickness 0.15)) (justify left bottom) hide)
      )
      (property "Datasheet" "https://www.bourns.com/docs/product-datasheets/cr.pdf" (at 20.32 -17.78 0)
        (effects (font (size 1.27 1.27) (thickness 0.15)) (justify left bottom) hide)
      )
      (property "MPN" "CR0402-FX-4302GLF" (at 20.32 -20.32 0)
        (effects (font (size 1.27 1.27) (thickness 0.15)) (justify left bottom) hide)
      )
      (property "Manufacturer" "Bourns" (at 20.32 -22.86 0)
        (effects (font (size 1.27 1.27) (thickness 0.15)) (justify left bottom) hide)
      )
      (property "License" "Apache-2.0" (at 20.32 -25.4 0)
        (effects (font (size 1.27 1.27) (thickness 0.15)) (justify left bottom) hide)
      )
      (property "Author" "Antmicro" (at 20.32 -27.94 0)
        (effects (font (size 1.27 1.27) (thickness 0.15)) (justify left bottom) hide)
      )
      (property "Val" "43k" (at 20.32 -7.62 0)
        (effects (font (size 1.27 1.27) (thickness 0.15)) (justify left bottom))
      )
      (property "Tolerance" "1%" (at 20.32 -10.16 0)
        (effects (font (size 1.27 1.27)) (justify left bottom) hide)
      )
      (property "ki_description" "43k resistor in 0402 package with 1% tolerance" (at 0 0 0)
        (effects (font (size 1.27 1.27)) hide)
      )
      (symbol "R_43k_0402_0_1"
        (rectangle (start 0.635 0.889) (end 4.445 -0.889)
          (stroke (width 0.254) (type default))
          (fill (type none))
        )
      )
      (symbol "R_43k_0402_1_1"
        (pin passive line (at 0 0 0) (length 0.635)
          (name "~" (effects (font (size 1.27 1.27))))
          (number "1" (effects (font (size 1.27 1.27))))
        )
        (pin passive line (at 5.08 0 180) (length 0.635)
          (name "~" (effects (font (size 1.27 1.27))))
          (number "2" (effects (font (size 1.27 1.27))))
        )
      )
    )
	(symbol "kria-k26-devboard:R_470R_0402" (pin_numbers hide) (pin_names hide) (in_bom yes) (on_board yes)
      (property "Reference" "R" (at 20.32 -5.08 0)
        (effects (font (size 1.27 1.27) (thickness 0.15)) (justify left bottom))
      )
      (property "Value" "R_470R_0402" (at 20.32 -12.7 0)
        (effects (font (size 1.27 1.27) (thickness 0.15)) (justify left bottom) hide)
      )
      (property "Footprint" "kria-k26-devboard-footprints:R_0402_1005Metric" (at 20.32 -15.24 0)
        (effects (font (size 1.27 1.27) (thickness 0.15)) (justify left bottom) hide)
      )
      (property "Datasheet" "https://www.bourns.com/docs/product-datasheets/cr.pdf" (at 20.32 -17.78 0)
        (effects (font (size 1.27 1.27) (thickness 0.15)) (justify left bottom) hide)
      )
      (property "MPN" "CR0402-FX-4700GLF" (at 20.32 -20.32 0)
        (effects (font (size 1.27 1.27) (thickness 0.15)) (justify left bottom) hide)
      )
      (property "Manufacturer" "Bourns" (at 20.32 -22.86 0)
        (effects (font (size 1.27 1.27) (thickness 0.15)) (justify left bottom) hide)
      )
      (property "License" "Apache-2.0" (at 20.32 -25.4 0)
        (effects (font (size 1.27 1.27) (thickness 0.15)) (justify left bottom) hide)
      )
      (property "Author" "Antmicro" (at 20.32 -27.94 0)
        (effects (font (size 1.27 1.27) (thickness 0.15)) (justify left bottom) hide)
      )
      (property "Val" "470R" (at 20.32 -7.62 0)
        (effects (font (size 1.27 1.27) (thickness 0.15)) (justify left bottom))
      )
      (property "Tolerance" "1%" (at 20.32 -10.16 0)
        (effects (font (size 1.27 1.27)) (justify left bottom) hide)
      )
      (property "ki_description" "470R resistor in 0402 package with 1% tolerance" (at 0 0 0)
        (effects (font (size 1.27 1.27)) hide)
      )
      (symbol "R_470R_0402_0_1"
        (rectangle (start 0.635 0.889) (end 4.445 -0.889)
          (stroke (width 0.254) (type default))
          (fill (type none))
        )
      )
      (symbol "R_470R_0402_1_1"
        (pin passive line (at 0 0 0) (length 0.635)
          (name "~" (effects (font (size 1.27 1.27))))
          (number "1" (effects (font (size 1.27 1.27))))
        )
        (pin passive line (at 5.08 0 180) (length 0.635)
          (name "~" (effects (font (size 1.27 1.27))))
          (number "2" (effects (font (size 1.27 1.27))))
        )
      )
    )
	(symbol "kria-k26-devboard:R_475R_0402" (pin_numbers hide) (pin_names hide) (in_bom yes) (on_board yes)
      (property "Reference" "R" (at 20.32 -5.08 0)
        (effects (font (size 1.27 1.27) (thickness 0.15)) (justify left bottom))
      )
      (property "Value" "R_475R_0402" (at 20.32 -12.7 0)
        (effects (font (size 1.27 1.27) (thickness 0.15)) (justify left bottom) hide)
      )
      (property "Footprint" "kria-k26-devboard-footprints:R_0402_1005Metric" (at 20.32 -15.24 0)
        (effects (font (size 1.27 1.27) (thickness 0.15)) (justify left bottom) hide)
      )
      (property "Datasheet" "https://www.bourns.com/docs/product-datasheets/cr.pdf" (at 20.32 -17.78 0)
        (effects (font (size 1.27 1.27) (thickness 0.15)) (justify left bottom) hide)
      )
      (property "MPN" "CR0402-FX-4750GLF" (at 20.32 -20.32 0)
        (effects (font (size 1.27 1.27) (thickness 0.15)) (justify left bottom) hide)
      )
      (property "Manufacturer" "Bourns" (at 20.32 -22.86 0)
        (effects (font (size 1.27 1.27) (thickness 0.15)) (justify left bottom) hide)
      )
      (property "License" "Apache-2.0" (at 20.32 -25.4 0)
        (effects (font (size 1.27 1.27) (thickness 0.15)) (justify left bottom) hide)
      )
      (property "Author" "Antmicro" (at 20.32 -27.94 0)
        (effects (font (size 1.27 1.27) (thickness 0.15)) (justify left bottom) hide)
      )
      (property "Val" "475R" (at 20.32 -7.62 0)
        (effects (font (size 1.27 1.27) (thickness 0.15)) (justify left bottom))
      )
      (property "Tolerance" "1%" (at 20.32 -10.16 0)
        (effects (font (size 1.27 1.27)) (justify left bottom) hide)
      )
      (property "ki_description" "475R resistor in 0402 package with 1% tolerance" (at 0 0 0)
        (effects (font (size 1.27 1.27)) hide)
      )
      (symbol "R_475R_0402_0_1"
        (rectangle (start 0.635 0.889) (end 4.445 -0.889)
          (stroke (width 0.254) (type default))
          (fill (type none))
        )
      )
      (symbol "R_475R_0402_1_1"
        (pin passive line (at 0 0 0) (length 0.635)
          (name "~" (effects (font (size 1.27 1.27))))
          (number "1" (effects (font (size 1.27 1.27))))
        )
        (pin passive line (at 5.08 0 180) (length 0.635)
          (name "~" (effects (font (size 1.27 1.27))))
          (number "2" (effects (font (size 1.27 1.27))))
        )
      )
    )
	(symbol "kria-k26-devboard:R_49R9_0402" (pin_numbers hide) (pin_names hide) (in_bom yes) (on_board yes)
      (property "Reference" "R" (at 20.32 -5.08 0)
        (effects (font (size 1.27 1.27) (thickness 0.15)) (justify left bottom))
      )
      (property "Value" "R_49R9_0402" (at 20.32 -12.7 0)
        (effects (font (size 1.27 1.27) (thickness 0.15)) (justify left bottom) hide)
      )
      (property "Footprint" "kria-k26-devboard-footprints:R_0402_1005Metric" (at 20.32 -15.24 0)
        (effects (font (size 1.27 1.27) (thickness 0.15)) (justify left bottom) hide)
      )
      (property "Datasheet" "https://www.bourns.com/docs/product-datasheets/cr.pdf" (at 20.32 -17.78 0)
        (effects (font (size 1.27 1.27) (thickness 0.15)) (justify left bottom) hide)
      )
      (property "MPN" "CR0402-FX-49R9GLF" (at 20.32 -20.32 0)
        (effects (font (size 1.27 1.27) (thickness 0.15)) (justify left bottom) hide)
      )
      (property "Manufacturer" "Bourns" (at 20.32 -22.86 0)
        (effects (font (size 1.27 1.27) (thickness 0.15)) (justify left bottom) hide)
      )
      (property "License" "Apache-2.0" (at 20.32 -25.4 0)
        (effects (font (size 1.27 1.27) (thickness 0.15)) (justify left bottom) hide)
      )
      (property "Author" "Antmicro" (at 20.32 -27.94 0)
        (effects (font (size 1.27 1.27) (thickness 0.15)) (justify left bottom) hide)
      )
      (property "Val" "49R9" (at 20.32 -7.62 0)
        (effects (font (size 1.27 1.27) (thickness 0.15)) (justify left bottom))
      )
      (property "Tolerance" "1%" (at 20.32 -10.16 0)
        (effects (font (size 1.27 1.27)) (justify left bottom) hide)
      )
      (property "ki_description" "49R9 resistor in 0402 package with 1% tolerance" (at 0 0 0)
        (effects (font (size 1.27 1.27)) hide)
      )
      (symbol "R_49R9_0402_0_1"
        (rectangle (start 0.635 0.889) (end 4.445 -0.889)
          (stroke (width 0.254) (type default))
          (fill (type none))
        )
      )
      (symbol "R_49R9_0402_1_1"
        (pin passive line (at 0 0 0) (length 0.635)
          (name "~" (effects (font (size 1.27 1.27))))
          (number "1" (effects (font (size 1.27 1.27))))
        )
        (pin passive line (at 5.08 0 180) (length 0.635)
          (name "~" (effects (font (size 1.27 1.27))))
          (number "2" (effects (font (size 1.27 1.27))))
        )
      )
    )
	(symbol "kria-k26-devboard:R_49k9_0402" (pin_numbers hide) (pin_names hide) (in_bom yes) (on_board yes)
      (property "Reference" "R" (at 20.32 -5.08 0)
        (effects (font (size 1.27 1.27) (thickness 0.15)) (justify left bottom))
      )
      (property "Value" "R_49k9_0402" (at 20.32 -12.7 0)
        (effects (font (size 1.27 1.27) (thickness 0.15)) (justify left bottom) hide)
      )
      (property "Footprint" "kria-k26-devboard-footprints:R_0402_1005Metric" (at 20.32 -15.24 0)
        (effects (font (size 1.27 1.27) (thickness 0.15)) (justify left bottom) hide)
      )
      (property "Datasheet" "https://www.bourns.com/docs/product-datasheets/cr.pdf" (at 20.32 -17.78 0)
        (effects (font (size 1.27 1.27) (thickness 0.15)) (justify left bottom) hide)
      )
      (property "MPN" "CR0402-FX-4992GLF" (at 20.32 -20.32 0)
        (effects (font (size 1.27 1.27) (thickness 0.15)) (justify left bottom) hide)
      )
      (property "Manufacturer" "Bourns" (at 20.32 -22.86 0)
        (effects (font (size 1.27 1.27) (thickness 0.15)) (justify left bottom) hide)
      )
      (property "License" "Apache-2.0" (at 20.32 -25.4 0)
        (effects (font (size 1.27 1.27) (thickness 0.15)) (justify left bottom) hide)
      )
      (property "Author" "Antmicro" (at 20.32 -27.94 0)
        (effects (font (size 1.27 1.27) (thickness 0.15)) (justify left bottom) hide)
      )
      (property "Val" "49k9" (at 20.32 -7.62 0)
        (effects (font (size 1.27 1.27) (thickness 0.15)) (justify left bottom))
      )
      (property "Tolerance" "1%" (at 20.32 -10.16 0)
        (effects (font (size 1.27 1.27)) (justify left bottom) hide)
      )
      (property "ki_description" "49k9 resistor in 0402 package with 1% tolerance" (at 0 0 0)
        (effects (font (size 1.27 1.27)) hide)
      )
      (symbol "R_49k9_0402_0_1"
        (rectangle (start 0.635 0.889) (end 4.445 -0.889)
          (stroke (width 0.254) (type default))
          (fill (type none))
        )
      )
      (symbol "R_49k9_0402_1_1"
        (pin passive line (at 0 0 0) (length 0.635)
          (name "~" (effects (font (size 1.27 1.27))))
          (number "1" (effects (font (size 1.27 1.27))))
        )
        (pin passive line (at 5.08 0 180) (length 0.635)
          (name "~" (effects (font (size 1.27 1.27))))
          (number "2" (effects (font (size 1.27 1.27))))
        )
      )
    )
	(symbol "kria-k26-devboard:R_4k7_0402" (pin_numbers hide) (pin_names hide) (in_bom yes) (on_board yes)
      (property "Reference" "R" (at 20.32 -5.08 0)
        (effects (font (size 1.27 1.27) (thickness 0.15)) (justify left bottom))
      )
      (property "Value" "R_4k7_0402" (at 20.32 -12.7 0)
        (effects (font (size 1.27 1.27) (thickness 0.15)) (justify left bottom) hide)
      )
      (property "Footprint" "kria-k26-devboard-footprints:R_0402_1005Metric" (at 20.32 -15.24 0)
        (effects (font (size 1.27 1.27) (thickness 0.15)) (justify left bottom) hide)
      )
      (property "Datasheet" "https://www.bourns.com/docs/product-datasheets/cr.pdf" (at 20.32 -17.78 0)
        (effects (font (size 1.27 1.27) (thickness 0.15)) (justify left bottom) hide)
      )
      (property "MPN" "CR0402-FX-4701GLF" (at 20.32 -20.32 0)
        (effects (font (size 1.27 1.27) (thickness 0.15)) (justify left bottom) hide)
      )
      (property "Manufacturer" "Bourns" (at 20.32 -22.86 0)
        (effects (font (size 1.27 1.27) (thickness 0.15)) (justify left bottom) hide)
      )
      (property "License" "Apache-2.0" (at 20.32 -25.4 0)
        (effects (font (size 1.27 1.27) (thickness 0.15)) (justify left bottom) hide)
      )
      (property "Author" "Antmicro" (at 20.32 -27.94 0)
        (effects (font (size 1.27 1.27) (thickness 0.15)) (justify left bottom) hide)
      )
      (property "Val" "4k7" (at 20.32 -7.62 0)
        (effects (font (size 1.27 1.27) (thickness 0.15)) (justify left bottom))
      )
      (property "Tolerance" "1%" (at 20.32 -10.16 0)
        (effects (font (size 1.27 1.27)) (justify left bottom) hide)
      )
      (property "ki_description" "4k7 resistor in 0402 package with 1% tolerance" (at 0 0 0)
        (effects (font (size 1.27 1.27)) hide)
      )
      (symbol "R_4k7_0402_0_1"
        (rectangle (start 0.635 0.889) (end 4.445 -0.889)
          (stroke (width 0.254) (type default))
          (fill (type none))
        )
      )
      (symbol "R_4k7_0402_1_1"
        (pin passive line (at 0 0 0) (length 0.635)
          (name "~" (effects (font (size 1.27 1.27))))
          (number "1" (effects (font (size 1.27 1.27))))
        )
        (pin passive line (at 5.08 0 180) (length 0.635)
          (name "~" (effects (font (size 1.27 1.27))))
          (number "2" (effects (font (size 1.27 1.27))))
        )
      )
    )
	(symbol "kria-k26-devboard:R_4k99_0402" (pin_numbers hide) (pin_names hide) (in_bom yes) (on_board yes)
      (property "Reference" "R" (at 20.32 -5.08 0)
        (effects (font (size 1.27 1.27) (thickness 0.15)) (justify left bottom))
      )
      (property "Value" "R_4k99_0402" (at 20.32 -12.7 0)
        (effects (font (size 1.27 1.27) (thickness 0.15)) (justify left bottom) hide)
      )
      (property "Footprint" "kria-k26-devboard-footprints:R_0402_1005Metric" (at 20.32 -15.24 0)
        (effects (font (size 1.27 1.27) (thickness 0.15)) (justify left bottom) hide)
      )
      (property "Datasheet" "https://www.bourns.com/docs/product-datasheets/cr.pdf" (at 20.32 -17.78 0)
        (effects (font (size 1.27 1.27) (thickness 0.15)) (justify left bottom) hide)
      )
      (property "MPN" "CR0402-FX-4991GLF" (at 20.32 -20.32 0)
        (effects (font (size 1.27 1.27) (thickness 0.15)) (justify left bottom) hide)
      )
      (property "Manufacturer" "Bourns" (at 20.32 -22.86 0)
        (effects (font (size 1.27 1.27) (thickness 0.15)) (justify left bottom) hide)
      )
      (property "License" "Apache-2.0" (at 20.32 -25.4 0)
        (effects (font (size 1.27 1.27) (thickness 0.15)) (justify left bottom) hide)
      )
      (property "Author" "Antmicro" (at 20.32 -27.94 0)
        (effects (font (size 1.27 1.27) (thickness 0.15)) (justify left bottom) hide)
      )
      (property "Val" "4k99" (at 20.32 -7.62 0)
        (effects (font (size 1.27 1.27) (thickness 0.15)) (justify left bottom))
      )
      (property "Tolerance" "1%" (at 20.32 -10.16 0)
        (effects (font (size 1.27 1.27)) (justify left bottom) hide)
      )
      (property "ki_description" "4k99 resistor in 0402 package with 1% tolerance" (at 0 0 0)
        (effects (font (size 1.27 1.27)) hide)
      )
      (symbol "R_4k99_0402_0_1"
        (rectangle (start 0.635 0.889) (end 4.445 -0.889)
          (stroke (width 0.254) (type default))
          (fill (type none))
        )
      )
      (symbol "R_4k99_0402_1_1"
        (pin passive line (at 0 0 0) (length 0.635)
          (name "~" (effects (font (size 1.27 1.27))))
          (number "1" (effects (font (size 1.27 1.27))))
        )
        (pin passive line (at 5.08 0 180) (length 0.635)
          (name "~" (effects (font (size 1.27 1.27))))
          (number "2" (effects (font (size 1.27 1.27))))
        )
      )
    )
	(symbol "kria-k26-devboard:R_4x33R_0201_array" (pin_names hide) (in_bom yes) (on_board yes)
      (property "Reference" "R" (at 26.67 -3.175 0)
        (effects (font (size 1.27 1.27) (thickness 0.15)) (justify left bottom))
      )
      (property "Value" "R_4x33R_0201_array" (at 26.67 -5.715 0)
        (effects (font (size 1.27 1.27) (thickness 0.15)) (justify left bottom))
      )
      (property "Footprint" "kria-k26-devboard-footprints:R_Array_4x0201_Panasonic_EXB18V" (at 26.67 -10.795 0)
        (effects (font (size 1.27 1.27) (thickness 0.15)) (justify left bottom) hide)
      )
      (property "Datasheet" "http://industrial.panasonic.com/cdbs/www-data/pdf/AOC0000/AOC0000C14.pdf" (at 26.67 -13.335 0)
        (effects (font (size 1.27 1.27) (thickness 0.15)) (justify left bottom) hide)
      )
      (property "MPN" "EXB-18V330JX" (at 26.67 -15.875 0)
        (effects (font (size 1.27 1.27) (thickness 0.15)) (justify left bottom) hide)
      )
      (property "Manufacturer" "Panasonic" (at 26.67 -18.415 0)
        (effects (font (size 1.27 1.27) (thickness 0.15)) (justify left bottom) hide)
      )
      (property "Author" "Antmicro" (at 26.67 -20.955 0)
        (effects (font (size 1.27 1.27) (thickness 0.15)) (justify left bottom) hide)
      )
      (property "License" "Apache-2.0" (at 26.67 -23.495 0)
        (effects (font (size 1.27 1.27) (thickness 0.15)) (justify left bottom) hide)
      )
      (property "Val" "R_4x33R_0201" (at 26.67 -8.255 0)
        (effects (font (size 1.27 1.27)) (justify left bottom))
      )
      (symbol "R_4x33R_0201_array_0_1"
        (polyline
          (pts
            (xy 2.54 -7.62)
            (xy 3.175 -7.62)
          )
          (stroke (width 0) (type default))
          (fill (type none))
        )
        (polyline
          (pts
            (xy 2.54 -5.08)
            (xy 3.175 -5.08)
          )
          (stroke (width 0) (type default))
          (fill (type none))
        )
        (polyline
          (pts
            (xy 2.54 -2.54)
            (xy 3.175 -2.54)
          )
          (stroke (width 0) (type default))
          (fill (type none))
        )
        (polyline
          (pts
            (xy 2.54 0)
            (xy 3.175 0)
          )
          (stroke (width 0) (type default))
          (fill (type none))
        )
        (polyline
          (pts
            (xy 6.985 -7.62)
            (xy 7.62 -7.62)
          )
          (stroke (width 0) (type default))
          (fill (type none))
        )
        (polyline
          (pts
            (xy 6.985 -5.08)
            (xy 7.62 -5.08)
          )
          (stroke (width 0) (type default))
          (fill (type none))
        )
        (polyline
          (pts
            (xy 6.985 -2.54)
            (xy 7.62 -2.54)
          )
          (stroke (width 0) (type default))
          (fill (type none))
        )
        (polyline
          (pts
            (xy 6.985 0)
            (xy 7.62 0)
          )
          (stroke (width 0) (type default))
          (fill (type none))
        )
        (rectangle (start 2.667 1.27) (end 7.493 -8.89)
          (stroke (width 0.254) (type default))
          (fill (type background))
        )
        (rectangle (start 6.985 -6.985) (end 3.175 -8.255)
          (stroke (width 0.254) (type default))
          (fill (type none))
        )
        (rectangle (start 6.985 -4.445) (end 3.175 -5.715)
          (stroke (width 0.254) (type default))
          (fill (type none))
        )
        (rectangle (start 6.985 -1.905) (end 3.175 -3.175)
          (stroke (width 0.254) (type default))
          (fill (type none))
        )
        (rectangle (start 6.985 0.635) (end 3.175 -0.635)
          (stroke (width 0.254) (type default))
          (fill (type none))
        )
      )
      (symbol "R_4x33R_0201_array_1_1"
        (pin passive line (at 0 0 0) (length 2.54)
          (name "R1.1" (effects (font (size 1.27 1.27))))
          (number "1" (effects (font (size 1.27 1.27))))
        )
        (pin passive line (at 0 -2.54 0) (length 2.54)
          (name "R2.1" (effects (font (size 1.27 1.27))))
          (number "2" (effects (font (size 1.27 1.27))))
        )
        (pin passive line (at 0 -5.08 0) (length 2.54)
          (name "R3.1" (effects (font (size 1.27 1.27))))
          (number "3" (effects (font (size 1.27 1.27))))
        )
        (pin passive line (at 0 -7.62 0) (length 2.54)
          (name "R4.1" (effects (font (size 1.27 1.27))))
          (number "4" (effects (font (size 1.27 1.27))))
        )
        (pin passive line (at 10.16 -7.62 180) (length 2.54)
          (name "R4.2" (effects (font (size 1.27 1.27))))
          (number "5" (effects (font (size 1.27 1.27))))
        )
        (pin passive line (at 10.16 -5.08 180) (length 2.54)
          (name "R3.2" (effects (font (size 1.27 1.27))))
          (number "6" (effects (font (size 1.27 1.27))))
        )
        (pin passive line (at 10.16 -2.54 180) (length 2.54)
          (name "R2.2" (effects (font (size 1.27 1.27))))
          (number "7" (effects (font (size 1.27 1.27))))
        )
        (pin passive line (at 10.16 0 180) (length 2.54)
          (name "R1.2" (effects (font (size 1.27 1.27))))
          (number "8" (effects (font (size 1.27 1.27))))
        )
      )
    )
	(symbol "kria-k26-devboard:R_510R_0402" (pin_numbers hide) (pin_names hide) (in_bom yes) (on_board yes)
      (property "Reference" "R" (at 20.32 -5.08 0)
        (effects (font (size 1.27 1.27) (thickness 0.15)) (justify left bottom))
      )
      (property "Value" "R_510R_0402" (at 20.32 -12.7 0)
        (effects (font (size 1.27 1.27) (thickness 0.15)) (justify left bottom) hide)
      )
      (property "Footprint" "kria-k26-devboard-footprints:R_0402_1005Metric" (at 20.32 -15.24 0)
        (effects (font (size 1.27 1.27) (thickness 0.15)) (justify left bottom) hide)
      )
      (property "Datasheet" "https://www.bourns.com/docs/product-datasheets/cr.pdf" (at 20.32 -17.78 0)
        (effects (font (size 1.27 1.27) (thickness 0.15)) (justify left bottom) hide)
      )
      (property "MPN" "CR0402-FX-5100GLF" (at 20.32 -20.32 0)
        (effects (font (size 1.27 1.27) (thickness 0.15)) (justify left bottom) hide)
      )
      (property "Manufacturer" "Bourns" (at 20.32 -22.86 0)
        (effects (font (size 1.27 1.27) (thickness 0.15)) (justify left bottom) hide)
      )
      (property "License" "Apache-2.0" (at 20.32 -25.4 0)
        (effects (font (size 1.27 1.27) (thickness 0.15)) (justify left bottom) hide)
      )
      (property "Author" "Antmicro" (at 20.32 -27.94 0)
        (effects (font (size 1.27 1.27) (thickness 0.15)) (justify left bottom) hide)
      )
      (property "Val" "510R" (at 20.32 -7.62 0)
        (effects (font (size 1.27 1.27) (thickness 0.15)) (justify left bottom))
      )
      (property "Tolerance" "1%" (at 20.32 -10.16 0)
        (effects (font (size 1.27 1.27)) (justify left bottom) hide)
      )
      (property "ki_description" "510R resistor in 0402 package with 1% tolerance" (at 0 0 0)
        (effects (font (size 1.27 1.27)) hide)
      )
      (symbol "R_510R_0402_0_1"
        (rectangle (start 0.635 0.889) (end 4.445 -0.889)
          (stroke (width 0.254) (type default))
          (fill (type none))
        )
      )
      (symbol "R_510R_0402_1_1"
        (pin passive line (at 0 0 0) (length 0.635)
          (name "~" (effects (font (size 1.27 1.27))))
          (number "1" (effects (font (size 1.27 1.27))))
        )
        (pin passive line (at 5.08 0 180) (length 0.635)
          (name "~" (effects (font (size 1.27 1.27))))
          (number "2" (effects (font (size 1.27 1.27))))
        )
      )
    )
	(symbol "kria-k26-devboard:R_5k11_0402" (pin_numbers hide) (pin_names hide) (in_bom yes) (on_board yes)
      (property "Reference" "R" (at 20.32 -5.08 0)
        (effects (font (size 1.27 1.27) (thickness 0.15)) (justify left bottom))
      )
      (property "Value" "R_5k11_0402" (at 20.32 -12.7 0)
        (effects (font (size 1.27 1.27) (thickness 0.15)) (justify left bottom) hide)
      )
      (property "Footprint" "kria-k26-devboard-footprints:R_0402_1005Metric" (at 20.32 -15.24 0)
        (effects (font (size 1.27 1.27) (thickness 0.15)) (justify left bottom) hide)
      )
      (property "Datasheet" "https://www.bourns.com/docs/product-datasheets/cr.pdf" (at 20.32 -17.78 0)
        (effects (font (size 1.27 1.27) (thickness 0.15)) (justify left bottom) hide)
      )
      (property "MPN" "CR0402-FX-5111GLF" (at 20.32 -20.32 0)
        (effects (font (size 1.27 1.27) (thickness 0.15)) (justify left bottom) hide)
      )
      (property "Manufacturer" "Bourns" (at 20.32 -22.86 0)
        (effects (font (size 1.27 1.27) (thickness 0.15)) (justify left bottom) hide)
      )
      (property "License" "Apache-2.0" (at 20.32 -25.4 0)
        (effects (font (size 1.27 1.27) (thickness 0.15)) (justify left bottom) hide)
      )
      (property "Author" "Antmicro" (at 20.32 -27.94 0)
        (effects (font (size 1.27 1.27) (thickness 0.15)) (justify left bottom) hide)
      )
      (property "Val" "5k11" (at 20.32 -7.62 0)
        (effects (font (size 1.27 1.27) (thickness 0.15)) (justify left bottom))
      )
      (property "Tolerance" "1%" (at 20.32 -10.16 0)
        (effects (font (size 1.27 1.27)) (justify left bottom) hide)
      )
      (property "ki_description" "5k11 resistor in 0402 package with 1% tolerance" (at 0 0 0)
        (effects (font (size 1.27 1.27)) hide)
      )
      (symbol "R_5k11_0402_0_1"
        (rectangle (start 0.635 0.889) (end 4.445 -0.889)
          (stroke (width 0.254) (type default))
          (fill (type none))
        )
      )
      (symbol "R_5k11_0402_1_1"
        (pin passive line (at 0 0 0) (length 0.635)
          (name "~" (effects (font (size 1.27 1.27))))
          (number "1" (effects (font (size 1.27 1.27))))
        )
        (pin passive line (at 5.08 0 180) (length 0.635)
          (name "~" (effects (font (size 1.27 1.27))))
          (number "2" (effects (font (size 1.27 1.27))))
        )
      )
    )
	(symbol "kria-k26-devboard:R_5k76_0402" (pin_numbers hide) (pin_names hide) (in_bom yes) (on_board yes)
      (property "Reference" "R" (at 20.32 -5.08 0)
        (effects (font (size 1.27 1.27) (thickness 0.15)) (justify left bottom))
      )
      (property "Value" "R_5k76_0402" (at 20.32 -12.7 0)
        (effects (font (size 1.27 1.27) (thickness 0.15)) (justify left bottom) hide)
      )
      (property "Footprint" "kria-k26-devboard-footprints:R_0402_1005Metric" (at 20.32 -15.24 0)
        (effects (font (size 1.27 1.27) (thickness 0.15)) (justify left bottom) hide)
      )
      (property "Datasheet" "https://www.bourns.com/docs/product-datasheets/cr.pdf" (at 20.32 -17.78 0)
        (effects (font (size 1.27 1.27) (thickness 0.15)) (justify left bottom) hide)
      )
      (property "MPN" "CR0402-FX-5761GLF" (at 20.32 -20.32 0)
        (effects (font (size 1.27 1.27) (thickness 0.15)) (justify left bottom) hide)
      )
      (property "Manufacturer" "Bourns" (at 20.32 -22.86 0)
        (effects (font (size 1.27 1.27) (thickness 0.15)) (justify left bottom) hide)
      )
      (property "License" "Apache-2.0" (at 20.32 -25.4 0)
        (effects (font (size 1.27 1.27) (thickness 0.15)) (justify left bottom) hide)
      )
      (property "Author" "Antmicro" (at 20.32 -27.94 0)
        (effects (font (size 1.27 1.27) (thickness 0.15)) (justify left bottom) hide)
      )
      (property "Val" "5k76" (at 20.32 -7.62 0)
        (effects (font (size 1.27 1.27) (thickness 0.15)) (justify left bottom))
      )
      (property "Tolerance" "1%" (at 20.32 -10.16 0)
        (effects (font (size 1.27 1.27)) (justify left bottom) hide)
      )
      (property "ki_description" "5k76 resistor in 0402 package with 1% tolerance" (at 0 0 0)
        (effects (font (size 1.27 1.27)) hide)
      )
      (symbol "R_5k76_0402_0_1"
        (rectangle (start 0.635 0.889) (end 4.445 -0.889)
          (stroke (width 0.254) (type default))
          (fill (type none))
        )
      )
      (symbol "R_5k76_0402_1_1"
        (pin passive line (at 0 0 0) (length 0.635)
          (name "~" (effects (font (size 1.27 1.27))))
          (number "1" (effects (font (size 1.27 1.27))))
        )
        (pin passive line (at 5.08 0 180) (length 0.635)
          (name "~" (effects (font (size 1.27 1.27))))
          (number "2" (effects (font (size 1.27 1.27))))
        )
      )
    )
	(symbol "kria-k26-devboard:R_63R4_0603" (pin_numbers hide) (pin_names hide) (in_bom yes) (on_board yes)
      (property "Reference" "R" (at 20.32 -5.08 0)
        (effects (font (size 1.27 1.27) (thickness 0.15)) (justify left bottom))
      )
      (property "Value" "R_63R4_0603" (at 20.32 -12.7 0)
        (effects (font (size 1.27 1.27) (thickness 0.15)) (justify left bottom) hide)
      )
      (property "Footprint" "kria-k26-devboard-footprints:R_0603_1608Metric" (at 20.32 -15.24 0)
        (effects (font (size 1.27 1.27) (thickness 0.15)) (justify left bottom) hide)
      )
      (property "Datasheet" "https://www.bourns.com/docs/product-datasheets/cr.pdf" (at 20.32 -17.78 0)
        (effects (font (size 1.27 1.27) (thickness 0.15)) (justify left bottom) hide)
      )
      (property "MPN" "CR0603-FX-63R4ELF" (at 20.32 -20.32 0)
        (effects (font (size 1.27 1.27) (thickness 0.15)) (justify left bottom) hide)
      )
      (property "Manufacturer" "Bourns" (at 20.32 -22.86 0)
        (effects (font (size 1.27 1.27) (thickness 0.15)) (justify left bottom) hide)
      )
      (property "License" "Apache-2.0" (at 20.32 -25.4 0)
        (effects (font (size 1.27 1.27) (thickness 0.15)) (justify left bottom) hide)
      )
      (property "Author" "Antmicro" (at 20.32 -27.94 0)
        (effects (font (size 1.27 1.27) (thickness 0.15)) (justify left bottom) hide)
      )
      (property "Val" "63R4" (at 20.32 -7.62 0)
        (effects (font (size 1.27 1.27) (thickness 0.15)) (justify left bottom))
      )
      (property "Tolerance" "1%" (at 20.32 -10.16 0)
        (effects (font (size 1.27 1.27)) (justify left bottom) hide)
      )
      (property "ki_description" "63R4 resistor in 0603 package with 1% tolerance" (at 0 0 0)
        (effects (font (size 1.27 1.27)) hide)
      )
      (symbol "R_63R4_0603_0_1"
        (rectangle (start 0.635 0.889) (end 4.445 -0.889)
          (stroke (width 0.254) (type default))
          (fill (type none))
        )
      )
      (symbol "R_63R4_0603_1_1"
        (pin passive line (at 0 0 0) (length 0.635)
          (name "~" (effects (font (size 1.27 1.27))))
          (number "1" (effects (font (size 1.27 1.27))))
        )
        (pin passive line (at 5.08 0 180) (length 0.635)
          (name "~" (effects (font (size 1.27 1.27))))
          (number "2" (effects (font (size 1.27 1.27))))
        )
      )
    )
	(symbol "kria-k26-devboard:R_8k06_0402" (pin_numbers hide) (pin_names hide) (in_bom yes) (on_board yes)
      (property "Reference" "R" (at 20.32 -5.08 0)
        (effects (font (size 1.27 1.27) (thickness 0.15)) (justify left bottom))
      )
      (property "Value" "R_8k06_0402" (at 20.32 -12.7 0)
        (effects (font (size 1.27 1.27) (thickness 0.15)) (justify left bottom) hide)
      )
      (property "Footprint" "kria-k26-devboard-footprints:R_0402_1005Metric" (at 20.32 -15.24 0)
        (effects (font (size 1.27 1.27) (thickness 0.15)) (justify left bottom) hide)
      )
      (property "Datasheet" "https://www.bourns.com/docs/product-datasheets/cr.pdf" (at 20.32 -17.78 0)
        (effects (font (size 1.27 1.27) (thickness 0.15)) (justify left bottom) hide)
      )
      (property "MPN" "CR0402-FX-8061GLF" (at 20.32 -20.32 0)
        (effects (font (size 1.27 1.27) (thickness 0.15)) (justify left bottom) hide)
      )
      (property "Manufacturer" "Bourns" (at 20.32 -22.86 0)
        (effects (font (size 1.27 1.27) (thickness 0.15)) (justify left bottom) hide)
      )
      (property "License" "Apache-2.0" (at 20.32 -25.4 0)
        (effects (font (size 1.27 1.27) (thickness 0.15)) (justify left bottom) hide)
      )
      (property "Author" "Antmicro" (at 20.32 -27.94 0)
        (effects (font (size 1.27 1.27) (thickness 0.15)) (justify left bottom) hide)
      )
      (property "Val" "8k06" (at 20.32 -7.62 0)
        (effects (font (size 1.27 1.27) (thickness 0.15)) (justify left bottom))
      )
      (property "Tolerance" "1%" (at 20.32 -10.16 0)
        (effects (font (size 1.27 1.27)) (justify left bottom) hide)
      )
      (property "ki_description" "8k06 resistor in 0402 package with 1% tolerance" (at 0 0 0)
        (effects (font (size 1.27 1.27)) hide)
      )
      (symbol "R_8k06_0402_0_1"
        (rectangle (start 0.635 0.889) (end 4.445 -0.889)
          (stroke (width 0.254) (type default))
          (fill (type none))
        )
      )
      (symbol "R_8k06_0402_1_1"
        (pin passive line (at 0 0 0) (length 0.635)
          (name "~" (effects (font (size 1.27 1.27))))
          (number "1" (effects (font (size 1.27 1.27))))
        )
        (pin passive line (at 5.08 0 180) (length 0.635)
          (name "~" (effects (font (size 1.27 1.27))))
          (number "2" (effects (font (size 1.27 1.27))))
        )
      )
    )
	(symbol "kria-k26-devboard:Resonator_12MHz_ABM8G" (pin_names hide) (in_bom yes) (on_board yes)
      (property "Reference" "Y" (at 15.24 -5.08 0)
        (effects (font (size 1.27 1.27) (thickness 0.15)) (justify left bottom))
      )
      (property "Value" "Resonator_12MHz_ABM8G" (at 15.24 -12.7 0)
        (effects (font (size 1.27 1.27) (thickness 0.15)) (justify left bottom) hide)
      )
      (property "Footprint" "kria-k26-devboard-footprints:Oscillator_SMD_Geyer_KX-7-4Pin_3.2x2.5mm" (at 15.24 -15.24 0)
        (effects (font (size 1.27 1.27) (thickness 0.15)) (justify left bottom) hide)
      )
      (property "Datasheet" "https://abracon.com/Resonators/ABM8G.pdf" (at 15.24 -17.78 0)
        (effects (font (size 1.27 1.27) (thickness 0.15)) (justify left bottom) hide)
      )
      (property "MPN" "ABM8G-12.000MHZ-18-D2Y-T" (at 15.24 -7.62 0)
        (effects (font (size 1.27 1.27) (thickness 0.15)) (justify left bottom) hide)
      )
      (property "Manufacturer" "Abracon" (at 15.24 -20.32 0)
        (effects (font (size 1.27 1.27) (thickness 0.15)) (justify left bottom) hide)
      )
      (property "Author" "Antmicro" (at 15.24 -22.86 0)
        (effects (font (size 1.27 1.27) (thickness 0.15)) (justify left bottom) hide)
      )
      (property "License" "Apache-2.0" (at 15.24 -25.4 0)
        (effects (font (size 1.27 1.27) (thickness 0.15)) (justify left bottom) hide)
      )
      (property "Val" "12 MHz" (at 15.24 -10.16 0)
        (effects (font (size 1.27 1.27) (thickness 0.15)) (justify left bottom))
      )
      (property "ki_keywords" "SMT, CERAMIC, OSCILLATOR" (at 0 0 0)
        (effects (font (size 1.27 1.27)) hide)
      )
      (property "ki_description" "Crystal, 12 MHz, SMT, 3.2mm x 2.5mm, 30 ppm, 18 pF, 20 ppm, ABM8G" (at 0 0 0)
        (effects (font (size 1.27 1.27)) hide)
      )
      (symbol "Resonator_12MHz_ABM8G_1_1"
        (polyline
          (pts
            (xy 2.54 1.27)
            (xy 2.54 -1.27)
          )
          (stroke (width 0.254) (type default))
          (fill (type background))
        )
        (polyline
          (pts
            (xy 5.08 1.27)
            (xy 5.08 -1.27)
          )
          (stroke (width 0.254) (type default))
          (fill (type background))
        )
        (polyline
          (pts
            (xy 1.905 -1.905)
            (xy 1.905 -2.54)
            (xy 5.715 -2.54)
            (xy 5.715 -1.905)
          )
          (stroke (width 0.254) (type default))
          (fill (type none))
        )
        (polyline
          (pts
            (xy 1.905 1.905)
            (xy 1.905 2.54)
            (xy 5.715 2.54)
            (xy 5.715 1.905)
          )
          (stroke (width 0.254) (type default))
          (fill (type none))
        )
        (rectangle (start 3.175 1.905) (end 4.445 -1.905)
          (stroke (width 0.254) (type default))
          (fill (type background))
        )
        (pin passive line (at 0 0 0) (length 2.54)
          (name "~" (effects (font (size 1.27 1.27))))
          (number "1" (effects (font (size 1.27 1.27))))
        )
        (pin passive line (at 3.81 -5.08 90) (length 2.54)
          (name "SH" (effects (font (size 1.27 1.27))))
          (number "2" (effects (font (size 1.27 1.27))))
        )
        (pin passive line (at 7.62 0 180) (length 2.54)
          (name "~" (effects (font (size 1.27 1.27))))
          (number "3" (effects (font (size 1.27 1.27))))
        )
        (pin passive line (at 3.81 -5.08 90) (length 2.54) hide
          (name "SH" (effects (font (size 1.27 1.27))))
          (number "4" (effects (font (size 1.27 1.27))))
        )
      )
    )
	(symbol "kria-k26-devboard:SMAJ58A-13-F" (pin_names hide) (in_bom yes) (on_board yes)
      (property "Reference" "D" (at 21.59 -5.08 0)
        (effects (font (size 1.27 1.27) (thickness 0.15)) (justify left bottom))
      )
      (property "Value" "SMAJ58A-13-F" (at 21.59 -7.62 0)
        (effects (font (size 1.27 1.27) (thickness 0.15)) (justify left bottom))
      )
      (property "Footprint" "kria-k26-devboard-footprints:DO-214AC" (at 21.59 -10.16 0)
        (effects (font (size 1.27 1.27) (thickness 0.15)) (justify left bottom) hide)
      )
      (property "Datasheet" "https://4donline.ihs.com/images/VipMasterIC/IC/DIOD/DIOD-S-A0001754755/DIOD-S-A0001754755-1.pdf?hkey=52A5661711E402568146F3353EA87419" (at 21.59 -12.7 0)
        (effects (font (size 1.27 1.27) (thickness 0.15)) (justify left bottom) hide)
      )
      (property "MPN" "SMAJ58A-13-F" (at 21.59 -15.24 0)
        (effects (font (size 1.27 1.27) (thickness 0.15)) (justify left bottom) hide)
      )
      (property "Manufacturer" "Diodes Incorporated" (at 21.59 -17.78 0)
        (effects (font (size 1.27 1.27) (thickness 0.15)) (justify left bottom) hide)
      )
      (property "Author" "Antmicro" (at 21.59 -20.32 0)
        (effects (font (size 1.27 1.27) (thickness 0.15)) (justify left bottom) hide)
      )
      (property "License" "Apache-2.0" (at 21.59 -22.86 0)
        (effects (font (size 1.27 1.27) (thickness 0.15)) (justify left bottom) hide)
      )
      (symbol "SMAJ58A-13-F_0_1"
        (polyline
          (pts
            (xy 6.35 0)
            (xy 5.08 0)
          )
          (stroke (width 0.254) (type default))
          (fill (type none))
        )
      )
      (symbol "SMAJ58A-13-F_1_1"
        (polyline
          (pts
            (xy 5.08 1.27)
            (xy 5.08 -1.27)
          )
          (stroke (width 0.254) (type default))
          (fill (type none))
        )
        (polyline
          (pts
            (xy 2.54 1.27)
            (xy 2.54 -1.27)
            (xy 5.08 0)
            (xy 2.54 1.27)
          )
          (stroke (width 0.254) (type default))
          (fill (type outline))
        )
        (polyline
          (pts
            (xy 5.08 -1.27)
            (xy 5.08 -1.905)
            (xy 5.715 -1.905)
            (xy 5.715 -1.27)
          )
          (stroke (width 0.254) (type default))
          (fill (type none))
        )
        (polyline
          (pts
            (xy 5.08 1.27)
            (xy 5.08 1.905)
            (xy 4.445 1.905)
            (xy 4.445 1.27)
          )
          (stroke (width 0.254) (type default))
          (fill (type none))
        )
        (pin passive line (at 0 0 0) (length 2.54)
          (name "A" (effects (font (size 1.27 1.27))))
          (number "A" (effects (font (size 1.27 1.27))))
        )
        (pin passive line (at 8.89 0 180) (length 2.54)
          (name "K" (effects (font (size 1.27 1.27))))
          (number "K" (effects (font (size 1.27 1.27))))
        )
      )
    )
	(symbol "kria-k26-devboard:SMF4L15CA" (pin_names hide) (in_bom yes) (on_board yes)
      (property "Reference" "D" (at 26.67 -5.08 0)
        (effects (font (size 1.27 1.27) (thickness 0.15)) (justify left bottom))
      )
      (property "Value" "SMF4L15CA" (at 26.67 -7.62 0)
        (effects (font (size 1.27 1.27) (thickness 0.15)) (justify left bottom))
      )
      (property "Footprint" "kria-k26-devboard-footprints:SOD-123FL" (at 26.67 -10.16 0)
        (effects (font (size 1.27 1.27) (thickness 0.15)) (justify left bottom) hide)
      )
      (property "Datasheet" "https://www.mouser.pl/datasheet/2/240/Littelfuse_TVS_Diode_SMF4L_Datasheet_pdf-1665786.pdf" (at 26.67 -12.7 0)
        (effects (font (size 1.27 1.27) (thickness 0.15)) (justify left bottom) hide)
      )
      (property "MPN" "SMF4L15CA" (at 26.67 -15.24 0)
        (effects (font (size 1.27 1.27) (thickness 0.15)) (justify left bottom) hide)
      )
      (property "Manufacturer" "Infineon Technologies" (at 26.67 -17.78 0)
        (effects (font (size 1.27 1.27) (thickness 0.15)) (justify left bottom) hide)
      )
      (property "Author" "Antmicro" (at 26.67 -20.32 0)
        (effects (font (size 1.27 1.27) (thickness 0.15)) (justify left bottom) hide)
      )
      (property "License" "Apache-2.0" (at 26.67 -22.86 0)
        (effects (font (size 1.27 1.27) (thickness 0.15)) (justify left bottom) hide)
      )
      (property "ki_description" "SD Suppressors / TVS Diodes TVS SMF4L 15V Bidirectional" (at 0 0 0)
        (effects (font (size 1.27 1.27)) hide)
      )
      (symbol "SMF4L15CA_1_1"
        (polyline
          (pts
            (xy 3.81 0)
            (xy 2.54 0)
          )
          (stroke (width 0.254) (type default))
          (fill (type none))
        )
        (polyline
          (pts
            (xy 5.08 0)
            (xy 6.35 0)
          )
          (stroke (width 0.254) (type default))
          (fill (type none))
        )
        (polyline
          (pts
            (xy 6.35 -1.27)
            (xy 5.715 -1.27)
          )
          (stroke (width 0.254) (type default))
          (fill (type none))
        )
        (polyline
          (pts
            (xy 6.35 -1.27)
            (xy 5.715 -1.27)
          )
          (stroke (width 0.254) (type default))
          (fill (type none))
        )
        (polyline
          (pts
            (xy 6.35 -1.27)
            (xy 6.35 1.27)
          )
          (stroke (width 0.254) (type default))
          (fill (type none))
        )
        (polyline
          (pts
            (xy 6.35 1.27)
            (xy 6.35 -1.27)
          )
          (stroke (width 0.254) (type default))
          (fill (type none))
        )
        (polyline
          (pts
            (xy 6.35 1.27)
            (xy 6.985 1.27)
          )
          (stroke (width 0.254) (type default))
          (fill (type none))
        )
        (polyline
          (pts
            (xy 6.35 1.27)
            (xy 6.985 1.27)
          )
          (stroke (width 0.254) (type default))
          (fill (type none))
        )
        (polyline
          (pts
            (xy 7.62 0)
            (xy 6.35 0)
          )
          (stroke (width 0.254) (type default))
          (fill (type none))
        )
        (polyline
          (pts
            (xy 8.89 0)
            (xy 10.16 0)
          )
          (stroke (width 0.254) (type default))
          (fill (type none))
        )
        (polyline
          (pts
            (xy 3.81 1.27)
            (xy 3.81 -1.27)
            (xy 6.35 0)
            (xy 3.81 1.27)
          )
          (stroke (width 0.254) (type default))
          (fill (type outline))
        )
        (polyline
          (pts
            (xy 8.89 -1.27)
            (xy 8.89 1.27)
            (xy 6.35 0)
            (xy 8.89 -1.27)
          )
          (stroke (width 0.254) (type default))
          (fill (type outline))
        )
        (pin passive line (at 0 0 0) (length 2.54)
          (name "1" (effects (font (size 1.27 1.27))))
          (number "1" (effects (font (size 1.27 1.27))))
        )
        (pin passive line (at 12.7 0 180) (length 2.54)
          (name "2" (effects (font (size 1.27 1.27))))
          (number "2" (effects (font (size 1.27 1.27))))
        )
      )
    )
	(symbol "kria-k26-devboard:SN65LVDS1_SOIC" (in_bom yes) (on_board yes)
      (property "Reference" "U" (at 31.75 -2.54 0)
        (effects (font (size 1.27 1.27) (thickness 0.15)) (justify left bottom))
      )
      (property "Value" "SN65LVDS1_SOIC" (at 31.75 -5.08 0)
        (effects (font (size 1.27 1.27) (thickness 0.15)) (justify left bottom))
      )
      (property "Footprint" "kria-k26-devboard-footprints:SOIC-8_3.9x4.9x1.75mm_P1.27mm" (at 31.75 -7.62 0)
        (effects (font (size 1.27 1.27) (thickness 0.15)) (justify left bottom) hide)
      )
      (property "Datasheet" "https://www.ti.com/lit/ds/symlink/sn65lvds1.pdf?HQS=dis-mous-null-mousermode-dsf-pf-null-wwe&ts=1679942374500&ref_url=https%253A%252F%252Fwww.ti.com%252Fgeneral%252Fdocs%252Fsuppproductinfo.tsp%253FdistId%253D26%2526gotoUrl%253Dhttps%253A%252F%252Fwww.ti.com%252Flit%252Fgpn%252Fsn65lvds1" (at 31.75 -10.16 0)
        (effects (font (size 1.27 1.27) (thickness 0.15)) (justify left bottom) hide)
      )
      (property "Manufacturer" "Texas Instruments" (at 31.75 -12.7 0)
        (effects (font (size 1.27 1.27) (thickness 0.15)) (justify left bottom) hide)
      )
      (property "MPN" "SN65LVDS1DR" (at 31.75 -15.24 0)
        (effects (font (size 1.27 1.27) (thickness 0.15)) (justify left bottom) hide)
      )
      (property "Author" "Antmicro" (at 31.75 -17.78 0)
        (effects (font (size 1.27 1.27) (thickness 0.15)) (justify left bottom) hide)
      )
      (property "License" "Apache-2.0" (at 31.75 -20.32 0)
        (effects (font (size 1.27 1.27) (thickness 0.15)) (justify left bottom) hide)
      )
      (property "ki_keywords" "SMT, INTERFACE, IC, LVDS" (at 0 0 0)
        (effects (font (size 1.27 1.27)) hide)
      )
      (property "ki_description" "LVDS Interface IC Single LVDS Transmitter" (at 0 0 0)
        (effects (font (size 1.27 1.27)) hide)
      )
      (symbol "SN65LVDS1_SOIC_1_1"
        (polyline
          (pts
            (xy 6.35 -3.81)
            (xy 5.08 -3.81)
          )
          (stroke (width 0.254) (type default))
          (fill (type background))
        )
        (polyline
          (pts
            (xy 10.414 -4.826)
            (xy 10.668 -4.826)
          )
          (stroke (width 0.254) (type default))
          (fill (type background))
        )
        (polyline
          (pts
            (xy 10.668 -2.794)
            (xy 9.398 -2.794)
          )
          (stroke (width 0.254) (type default))
          (fill (type background))
        )
        (polyline
          (pts
            (xy 6.35 -1.27)
            (xy 11.43 -3.81)
            (xy 6.35 -6.35)
            (xy 6.35 -1.27)
          )
          (stroke (width 0.254) (type default))
          (fill (type background))
        )
        (rectangle (start 2.54 2.54) (end 16.51 -10.16)
          (stroke (width 0.254) (type default))
          (fill (type background))
        )
        (circle (center 10.16 -4.826) (radius 0.254)
          (stroke (width 0.254) (type default))
          (fill (type background))
        )
        (pin power_in line (at 0 0 0) (length 2.54)
          (name "VDD" (effects (font (size 1.27 1.27))))
          (number "1" (effects (font (size 1.27 1.27))))
        )
        (pin input line (at 0 -3.81 0) (length 2.54)
          (name "IN" (effects (font (size 1.27 1.27))))
          (number "2" (effects (font (size 1.27 1.27))))
        )
        (pin no_connect line (at 2.54 -6.35 0) (length 2.54) hide
          (name "NC" (effects (font (size 1.27 1.27))))
          (number "3" (effects (font (size 1.27 1.27))))
        )
        (pin power_in line (at 19.05 -7.62 180) (length 2.54)
          (name "GND" (effects (font (size 1.27 1.27))))
          (number "4" (effects (font (size 1.27 1.27))))
        )
        (pin no_connect line (at 2.54 -7.62 0) (length 2.54) hide
          (name "NC" (effects (font (size 1.27 1.27))))
          (number "5" (effects (font (size 1.27 1.27))))
        )
        (pin no_connect line (at 2.54 -8.89 0) (length 2.54) hide
          (name "NC" (effects (font (size 1.27 1.27))))
          (number "6" (effects (font (size 1.27 1.27))))
        )
        (pin output line (at 19.05 -2.54 180) (length 2.54)
          (name "OUT+" (effects (font (size 1.27 1.27))))
          (number "7" (effects (font (size 1.27 1.27))))
        )
        (pin output line (at 19.05 -5.08 180) (length 2.54)
          (name "OUT-" (effects (font (size 1.27 1.27))))
          (number "8" (effects (font (size 1.27 1.27))))
        )
      )
    )
	(symbol "kria-k26-devboard:SN74AVC2T245_UQFN" (in_bom yes) (on_board yes)
      (property "Reference" "U" (at 45.72 -2.54 0)
        (effects (font (size 1.27 1.27) (thickness 0.15)) (justify left bottom))
      )
      (property "Value" "SN74AVC2T245_UQFN" (at 45.72 -7.62 0)
        (effects (font (size 1.27 1.27) (thickness 0.15)) (justify left bottom) hide)
      )
      (property "Footprint" "kria-k26-devboard-footprints:UQFN-10_1.4x1.8x0.5mm_P0.4mm" (at 45.72 -10.16 0)
        (effects (font (size 1.27 1.27) (thickness 0.15)) (justify left bottom) hide)
      )
      (property "Datasheet" "https://www.ti.com/lit/ds/symlink/sn74avc2t245.pdf?ts=1678888074783&ref_url=https%253A%252F%252Fwww.google.com%252F" (at 45.72 -12.7 0)
        (effects (font (size 1.27 1.27) (thickness 0.15)) (justify left bottom) hide)
      )
      (property "Manufacturer" "Texas Instruments" (at 45.72 -15.24 0)
        (effects (font (size 1.27 1.27) (thickness 0.15)) (justify left bottom) hide)
      )
      (property "MPN" "SN74AVC2T245RSWR" (at 45.72 -5.08 0)
        (effects (font (size 1.27 1.27) (thickness 0.15)) (justify left bottom))
      )
      (property "Author" "Antmicro" (at 45.72 -17.78 0)
        (effects (font (size 1.27 1.27) (thickness 0.15)) (justify left bottom) hide)
      )
      (property "License" "Apache-2.0" (at 45.72 -20.32 0)
        (effects (font (size 1.27 1.27) (thickness 0.15)) (justify left bottom) hide)
      )
      (property "ki_keywords" "SMT, LOGIC, IC, LEVEL-SHIFTER, VOLTAGE" (at 0 0 0)
        (effects (font (size 1.27 1.27)) hide)
      )
      (property "ki_description" "Transceiver Non Inverting, AVC Family, 2 Input, 12 mA, 2.4 ns, 1.2 V to 3.6 V, LFCSP-10" (at 0 0 0)
        (effects (font (size 1.27 1.27)) hide)
      )
      (symbol "SN74AVC2T245_UQFN_1_1"
        (rectangle (start 2.54 2.54) (end 15.24 -16.51)
          (stroke (width 0.254) (type default))
          (fill (type background))
        )
        (pin input line (at 0 -11.43 0) (length 2.54)
          (name "DIR_{2}" (effects (font (size 1.27 1.27))))
          (number "1" (effects (font (size 1.27 1.27))))
        )
        (pin input line (at 0 -8.89 0) (length 2.54)
          (name "DIR_{1}" (effects (font (size 1.27 1.27))))
          (number "10" (effects (font (size 1.27 1.27))))
        )
        (pin input line (at 0 -13.97 0) (length 2.54)
          (name "~{OE}" (effects (font (size 1.27 1.27))))
          (number "2" (effects (font (size 1.27 1.27))))
        )
        (pin power_in line (at 17.78 -13.97 180) (length 2.54)
          (name "GND" (effects (font (size 1.27 1.27))))
          (number "3" (effects (font (size 1.27 1.27))))
        )
        (pin bidirectional line (at 17.78 -6.35 180) (length 2.54)
          (name "B_{2}" (effects (font (size 1.27 1.27))))
          (number "4" (effects (font (size 1.27 1.27))))
        )
        (pin bidirectional line (at 17.78 -3.81 180) (length 2.54)
          (name "B_{1}" (effects (font (size 1.27 1.27))))
          (number "5" (effects (font (size 1.27 1.27))))
        )
        (pin power_in line (at 17.78 0 180) (length 2.54)
          (name "V_{CCB}" (effects (font (size 1.27 1.27))))
          (number "6" (effects (font (size 1.27 1.27))))
        )
        (pin power_in line (at 0 0 0) (length 2.54)
          (name "V_{CCA}" (effects (font (size 1.27 1.27))))
          (number "7" (effects (font (size 1.27 1.27))))
        )
        (pin bidirectional line (at 0 -3.81 0) (length 2.54)
          (name "A_{1}" (effects (font (size 1.27 1.27))))
          (number "8" (effects (font (size 1.27 1.27))))
        )
        (pin bidirectional line (at 0 -6.35 0) (length 2.54)
          (name "A_{2}" (effects (font (size 1.27 1.27))))
          (number "9" (effects (font (size 1.27 1.27))))
        )
      )
    )
	(symbol "kria-k26-devboard:SN74LVC1G125_SOT" (in_bom yes) (on_board yes)
      (property "Reference" "U" (at 31.75 -5.08 0)
        (effects (font (size 1.27 1.27) (thickness 0.15)) (justify left bottom))
      )
      (property "Value" "SN74LVC1G125_SOT" (at 31.75 -7.62 0)
        (effects (font (size 1.27 1.27) (thickness 0.15)) (justify left bottom))
      )
      (property "Footprint" "kria-k26-devboard-footprints:SOT-753" (at 31.75 -10.16 0)
        (effects (font (size 1.27 1.27) (thickness 0.15)) (justify left bottom) hide)
      )
      (property "Datasheet" "http://www.ti.com/general/docs/suppproductinfo.tsp?distId=10&gotoUrl=http%3A%2F%2Fwww.ti.com%2Flit%2Fgpn%2Fsn74lvc1g125" (at 31.75 -12.7 0)
        (effects (font (size 1.27 1.27) (thickness 0.15)) (justify left bottom) hide)
      )
      (property "MPN" "SN74LVC1G125DBVR" (at 31.75 -15.24 0)
        (effects (font (size 1.27 1.27) (thickness 0.15)) (justify left bottom) hide)
      )
      (property "Manufacturer" "Texas Instruments" (at 31.75 -17.78 0)
        (effects (font (size 1.27 1.27) (thickness 0.15)) (justify left bottom) hide)
      )
      (property "Author" "Antmicro" (at 31.75 -20.32 0)
        (effects (font (size 1.27 1.27) (thickness 0.15)) (justify left bottom) hide)
      )
      (property "License" "Apache-2.0" (at 31.75 -22.86 0)
        (effects (font (size 1.27 1.27) (thickness 0.15)) (justify left bottom) hide)
      )
      (property "ki_keywords" "SMT, LOGIC, IC, BUFFER, TRANSCEIVER, DRIVER" (at 0 0 0)
        (effects (font (size 1.27 1.27)) hide)
      )
      (property "ki_description" "Buffer, 74LVC1G125, 1.65 V to 5.5 V, SOT-23-5" (at 0 0 0)
        (effects (font (size 1.27 1.27)) hide)
      )
      (symbol "SN74LVC1G125_SOT_1_1"
        (polyline
          (pts
            (xy 6.35 -3.81)
            (xy 4.445 -3.81)
          )
          (stroke (width 0.254) (type default))
          (fill (type background))
        )
        (polyline
          (pts
            (xy 11.43 -3.81)
            (xy 13.335 -3.81)
          )
          (stroke (width 0.254) (type default))
          (fill (type background))
        )
        (polyline
          (pts
            (xy 5.715 -7.62)
            (xy 7.62 -7.62)
            (xy 7.62 -6.35)
          )
          (stroke (width 0.254) (type default))
          (fill (type background))
        )
        (polyline
          (pts
            (xy 6.35 -1.27)
            (xy 11.43 -3.81)
            (xy 6.35 -6.35)
            (xy 6.35 -1.27)
          )
          (stroke (width 0.254) (type default))
          (fill (type background))
        )
        (rectangle (start 2.54 2.54) (end 15.24 -10.16)
          (stroke (width 0.254) (type default))
          (fill (type background))
        )
        (circle (center 7.62 -6.096) (radius 0.284)
          (stroke (width 0.254) (type default))
          (fill (type background))
        )
        (pin input line (at 0 -7.62 0) (length 2.54)
          (name "~{OE}" (effects (font (size 1.27 1.27))))
          (number "1" (effects (font (size 1.27 1.27))))
        )
        (pin input line (at 0 -3.81 0) (length 2.54)
          (name "A" (effects (font (size 1.27 1.27))))
          (number "2" (effects (font (size 1.27 1.27))))
        )
        (pin power_in line (at 17.78 -7.62 180) (length 2.54)
          (name "GND" (effects (font (size 1.27 1.27))))
          (number "3" (effects (font (size 1.27 1.27))))
        )
        (pin output line (at 17.78 -3.81 180) (length 2.54)
          (name "Y" (effects (font (size 1.27 1.27))))
          (number "4" (effects (font (size 1.27 1.27))))
        )
        (pin power_in line (at 0 0 0) (length 2.54)
          (name "V_{CC}" (effects (font (size 1.27 1.27))))
          (number "5" (effects (font (size 1.27 1.27))))
        )
      )
    )
	(symbol "kria-k26-devboard:SW_KMR211NGLFS_SMD" (in_bom yes) (on_board yes)
      (property "Reference" "SW" (at 25.4 -2.54 0)
        (effects (font (size 1.27 1.27) (thickness 0.15)) (justify left bottom))
      )
      (property "Value" "SW_SPST_KMR211NGLFS" (at 25.4 -5.08 0)
        (effects (font (size 1.27 1.27) (thickness 0.15)) (justify left bottom))
      )
      (property "Footprint" "kria-k26-devboard-footprints:SW_KMR211NGLFS_SMD" (at 25.4 -7.62 0)
        (effects (font (size 1.27 1.27) (thickness 0.15)) (justify left bottom) hide)
      )
      (property "Datasheet" "http://www.farnell.com/datasheets/2631211.pdf" (at 25.4 -10.16 0)
        (effects (font (size 1.27 1.27) (thickness 0.15)) (justify left bottom) hide)
      )
      (property "MPN" "KMR211NGLFS" (at 25.4 -12.7 0)
        (effects (font (size 1.27 1.27) (thickness 0.15)) (justify left bottom) hide)
      )
      (property "Manufacturer" "C&K" (at 25.4 -15.24 0)
        (effects (font (size 1.27 1.27) (thickness 0.15)) (justify left bottom) hide)
      )
      (property "Author" "Antmicro" (at 25.4 -17.78 0)
        (effects (font (size 1.27 1.27) (thickness 0.15)) (justify left bottom) hide)
      )
      (property "License" "Apache-2.0" (at 25.4 -20.32 0)
        (effects (font (size 1.27 1.27) (thickness 0.15)) (justify left bottom) hide)
      )
      (symbol "SW_KMR211NGLFS_SMD_1_1"
        (polyline
          (pts
            (xy 2.54 -2.54)
            (xy 3.302 -2.54)
          )
          (stroke (width 0.254) (type default))
          (fill (type background))
        )
        (polyline
          (pts
            (xy 2.54 0)
            (xy 3.302 0)
          )
          (stroke (width 0.254) (type default))
          (fill (type background))
        )
        (polyline
          (pts
            (xy 3.302 1.27)
            (xy 6.858 1.27)
          )
          (stroke (width 0.254) (type default))
          (fill (type background))
        )
        (polyline
          (pts
            (xy 3.556 -0.3048)
            (xy 3.556 -2.1844)
          )
          (stroke (width 0.254) (type default))
          (fill (type background))
        )
        (polyline
          (pts
            (xy 4.064 2.794)
            (xy 6.096 2.794)
          )
          (stroke (width 0.254) (type default))
          (fill (type background))
        )
        (polyline
          (pts
            (xy 5.08 1.27)
            (xy 5.08 2.794)
          )
          (stroke (width 0.254) (type default))
          (fill (type background))
        )
        (polyline
          (pts
            (xy 6.604 -0.254)
            (xy 6.604 -2.1844)
          )
          (stroke (width 0.254) (type default))
          (fill (type background))
        )
        (polyline
          (pts
            (xy 7.62 -2.54)
            (xy 6.858 -2.54)
          )
          (stroke (width 0.254) (type default))
          (fill (type background))
        )
        (polyline
          (pts
            (xy 7.62 0)
            (xy 6.858 0)
          )
          (stroke (width 0.254) (type default))
          (fill (type background))
        )
        (circle (center 3.556 -2.54) (radius 0.254)
          (stroke (width 0.254) (type default))
          (fill (type outline))
        )
        (circle (center 3.556 0) (radius 0.254)
          (stroke (width 0.254) (type default))
          (fill (type outline))
        )
        (circle (center 6.604 -2.54) (radius 0.254)
          (stroke (width 0.254) (type default))
          (fill (type outline))
        )
        (circle (center 6.604 0) (radius 0.254)
          (stroke (width 0.254) (type default))
          (fill (type outline))
        )
        (pin passive line (at 0 0 0) (length 2.54)
          (name "~" (effects (font (size 1.27 1.27))))
          (number "1" (effects (font (size 1.27 1.27))))
        )
        (pin passive line (at 10.16 0 180) (length 2.54)
          (name "~" (effects (font (size 1.27 1.27))))
          (number "2" (effects (font (size 1.27 1.27))))
        )
        (pin passive line (at 0 -2.54 0) (length 2.54)
          (name "~" (effects (font (size 1.27 1.27))))
          (number "3" (effects (font (size 1.27 1.27))))
        )
        (pin passive line (at 10.16 -2.54 180) (length 2.54)
          (name "~" (effects (font (size 1.27 1.27))))
          (number "4" (effects (font (size 1.27 1.27))))
        )
      )
    )
	(symbol "kria-k26-devboard:Spacer_Drill3mm_H1.5mm_9774015243R" (in_bom yes) (on_board yes)
      (property "Reference" "H" (at 22.86 -2.54 0)
        (effects (font (size 1.27 1.27) (thickness 0.15)) (justify left bottom))
      )
      (property "Value" "Spacer_H1.5mm_9774015243R" (at 22.86 -5.08 0)
        (effects (font (size 1.27 1.27) (thickness 0.15)) (justify left bottom))
      )
      (property "Footprint" "kria-k26-devboard-footprints:Spacer_Drill3mm_H1.5mm_9774015243R" (at 22.86 -7.62 0)
        (effects (font (size 1.27 1.27) (thickness 0.15)) (justify left bottom) hide)
      )
      (property "Datasheet" "https://www.we-online.com/catalog/datasheet/9774015243R.pdf" (at 22.86 -10.16 0)
        (effects (font (size 1.27 1.27) (thickness 0.15)) (justify left bottom) hide)
      )
      (property "Manufacturer" "Würth Elektronik" (at 22.86 -12.7 0)
        (effects (font (size 1.27 1.27) (thickness 0.15)) (justify left bottom) hide)
      )
      (property "MPN" "9774015243R" (at 22.86 -15.24 0)
        (effects (font (size 1.27 1.27) (thickness 0.15)) (justify left bottom) hide)
      )
      (property "Author" "Antmicro" (at 22.86 -17.78 0)
        (effects (font (size 1.27 1.27) (thickness 0.15)) (justify left bottom) hide)
      )
      (property "License" "Apache-2.0" (at 22.86 -20.32 0)
        (effects (font (size 1.27 1.27) (thickness 0.15)) (justify left bottom) hide)
      )
      (symbol "Spacer_Drill3mm_H1.5mm_9774015243R_1_1"
        (rectangle (start 2.54 -2.54) (end 7.62 2.54)
          (stroke (width 0.254) (type default))
          (fill (type background))
        )
        (rectangle (start 3.81 -1.27) (end 6.35 1.27)
          (stroke (width 0.254) (type default))
          (fill (type background))
        )
        (pin passive line (at 0 0 0) (length 2.54)
          (name "~" (effects (font (size 1.27 1.27))))
          (number "1" (effects (font (size 1.27 1.27))))
        )
      )
    )
	(symbol "kria-k26-devboard:Spacer_Drill4.45mm_H5mm_9774050960R" (in_bom yes) (on_board yes)
      (property "Reference" "H" (at 22.86 -2.54 0)
        (effects (font (size 1.27 1.27) (thickness 0.15)) (justify left bottom))
      )
      (property "Value" "Spacer_Drill4.45mm_H5mm_9774050960R" (at 22.86 -5.08 0)
        (effects (font (size 1.27 1.27) (thickness 0.15)) (justify left bottom))
      )
      (property "Footprint" "kria-k26-devboard-footprints:Spacer_Drill4.45mm_H5mm_9774050960R" (at 22.86 -7.62 0)
        (effects (font (size 1.27 1.27) (thickness 0.15)) (justify left bottom) hide)
      )
      (property "Datasheet" "https://www.we-online.com/components/products/datasheet/9774050960R.pdf" (at 22.86 -10.16 0)
        (effects (font (size 1.27 1.27) (thickness 0.15)) (justify left bottom) hide)
      )
      (property "Manufacturer" "Würth Elektronik" (at 22.86 -12.7 0)
        (effects (font (size 1.27 1.27) (thickness 0.15)) (justify left bottom) hide)
      )
      (property "MPN" "9774050960R" (at 22.86 -15.24 0)
        (effects (font (size 1.27 1.27) (thickness 0.15)) (justify left bottom) hide)
      )
      (property "Author" "Antmicro" (at 22.86 -17.78 0)
        (effects (font (size 1.27 1.27) (thickness 0.15)) (justify left bottom) hide)
      )
      (property "License" "Apache-2.0" (at 22.86 -20.32 0)
        (effects (font (size 1.27 1.27) (thickness 0.15)) (justify left bottom) hide)
      )
      (property "ki_keywords" "SPACER" (at 0 0 0)
        (effects (font (size 1.27 1.27)) hide)
      )
      (property "ki_description" "Spacer, SMT, Non Stop, Steel, Swage Round, 6 mm x 5 mm, 3.3 mm Internal, WA-SMST Series" (at 0 0 0)
        (effects (font (size 1.27 1.27)) hide)
      )
      (symbol "Spacer_Drill4.45mm_H5mm_9774050960R_1_1"
        (rectangle (start 2.54 -2.54) (end 7.62 2.54)
          (stroke (width 0.254) (type default))
          (fill (type background))
        )
        (rectangle (start 3.81 -1.27) (end 6.35 1.27)
          (stroke (width 0.254) (type default))
          (fill (type background))
        )
        (pin passive line (at 0 0 0) (length 2.54)
          (name "~" (effects (font (size 1.27 1.27))))
          (number "1" (effects (font (size 1.27 1.27))))
        )
      )
    )
	(symbol "kria-k26-devboard:TPD4E05U06QDQARQ1" (in_bom yes) (on_board yes)
      (property "Reference" "U" (at 24.13 0 0)
        (effects (font (size 1.27 1.27) (thickness 0.15)) (justify left bottom))
      )
      (property "Value" "TPD4E05U06QDQARQ1" (at 24.13 -2.54 0)
        (effects (font (size 1.27 1.27) (thickness 0.15)) (justify left bottom))
      )
      (property "Footprint" "kria-k26-devboard-footprints:USON-10_2.5x1mm_P0.5mm" (at 24.13 -5.08 0)
        (effects (font (size 1.27 1.27) (thickness 0.15)) (justify left bottom) hide)
      )
      (property "Datasheet" "https://www.ti.com/lit/ds/symlink/tpd4e05u06-q1.pdf?HQS=dis-mous-null-mousermode-dsf-pf-null-wwe&ts=1663591265741&ref_url=https%253A%252F%252Fwww.mouser.com%252F" (at 24.13 -7.62 0)
        (effects (font (size 1.27 1.27) (thickness 0.15)) (justify left bottom) hide)
      )
      (property "Manufacturer" "Texas Instruments" (at 24.13 -10.16 0)
        (effects (font (size 1.27 1.27) (thickness 0.15)) (justify left bottom) hide)
      )
      (property "MPN" "TPD4E05U06QDQARQ1" (at 24.13 -12.7 0)
        (effects (font (size 1.27 1.27) (thickness 0.15)) (justify left bottom) hide)
      )
      (property "Author" "Antmicro" (at 24.13 -15.24 0)
        (effects (font (size 1.27 1.27) (thickness 0.15)) (justify left bottom) hide)
      )
      (property "License" "Apache-2.0" (at 24.13 -17.78 0)
        (effects (font (size 1.27 1.27) (thickness 0.15)) (justify left bottom) hide)
      )
      (property "ki_keywords" "SMT, DIODE, IC, TVS, ESD" (at 0 0 0)
        (effects (font (size 1.27 1.27)) hide)
      )
      (property "ki_description" "ESD protection" (at 0 0 0)
        (effects (font (size 1.27 1.27)) hide)
      )
      (symbol "TPD4E05U06QDQARQ1_1_1"
        (polyline
          (pts
            (xy 2.54 -7.62)
            (xy 7.62 -7.62)
          )
          (stroke (width 0.254) (type default))
          (fill (type background))
        )
        (polyline
          (pts
            (xy 2.54 -5.08)
            (xy 7.62 -5.08)
          )
          (stroke (width 0.254) (type default))
          (fill (type background))
        )
        (polyline
          (pts
            (xy 2.54 -2.54)
            (xy 7.62 -2.54)
          )
          (stroke (width 0.254) (type default))
          (fill (type background))
        )
        (polyline
          (pts
            (xy 2.54 0)
            (xy 7.62 0)
          )
          (stroke (width 0.254) (type default))
          (fill (type background))
        )
        (polyline
          (pts
            (xy 7.62 -10.16)
            (xy 2.54 -10.16)
          )
          (stroke (width 0.254) (type default))
          (fill (type background))
        )
        (polyline
          (pts
            (xy 7.62 0)
            (xy 7.62 -10.16)
          )
          (stroke (width 0.254) (type default))
          (fill (type background))
        )
        (polyline
          (pts
            (xy 4.826 -8.255)
            (xy 5.08 -8.001)
            (xy 5.08 -7.239)
            (xy 5.334 -6.985)
          )
          (stroke (width 0.254) (type default))
          (fill (type background))
        )
        (polyline
          (pts
            (xy 4.826 -5.715)
            (xy 5.08 -5.461)
            (xy 5.08 -4.699)
            (xy 5.334 -4.445)
          )
          (stroke (width 0.254) (type default))
          (fill (type background))
        )
        (polyline
          (pts
            (xy 4.826 -3.175)
            (xy 5.08 -2.921)
            (xy 5.08 -2.159)
            (xy 5.334 -1.905)
          )
          (stroke (width 0.254) (type default))
          (fill (type background))
        )
        (polyline
          (pts
            (xy 4.826 -0.635)
            (xy 5.08 -0.381)
            (xy 5.08 0.381)
            (xy 5.334 0.635)
          )
          (stroke (width 0.254) (type default))
          (fill (type background))
        )
        (polyline
          (pts
            (xy 5.08 -7.62)
            (xy 3.81 -8.255)
            (xy 3.81 -6.985)
            (xy 5.08 -7.62)
          )
          (stroke (width 0.254) (type default))
          (fill (type background))
        )
        (polyline
          (pts
            (xy 5.08 -5.08)
            (xy 3.81 -5.715)
            (xy 3.81 -4.445)
            (xy 5.08 -5.08)
          )
          (stroke (width 0.254) (type default))
          (fill (type background))
        )
        (polyline
          (pts
            (xy 5.08 -5.08)
            (xy 6.35 -4.445)
            (xy 6.35 -5.715)
            (xy 5.08 -5.08)
          )
          (stroke (width 0.254) (type default))
          (fill (type background))
        )
        (polyline
          (pts
            (xy 5.08 -2.54)
            (xy 3.81 -3.175)
            (xy 3.81 -1.905)
            (xy 5.08 -2.54)
          )
          (stroke (width 0.254) (type default))
          (fill (type background))
        )
        (polyline
          (pts
            (xy 5.08 -2.54)
            (xy 6.35 -3.175)
            (xy 6.35 -1.905)
            (xy 5.08 -2.54)
          )
          (stroke (width 0.254) (type default))
          (fill (type background))
        )
        (polyline
          (pts
            (xy 5.08 0)
            (xy 3.81 -0.635)
            (xy 3.81 0.635)
            (xy 5.08 0)
          )
          (stroke (width 0.254) (type default))
          (fill (type background))
        )
        (polyline
          (pts
            (xy 5.08 0)
            (xy 6.35 -0.635)
            (xy 6.35 0.635)
            (xy 5.08 0)
          )
          (stroke (width 0.254) (type default))
          (fill (type background))
        )
        (polyline
          (pts
            (xy 6.35 -6.985)
            (xy 6.35 -8.255)
            (xy 5.08 -7.62)
            (xy 6.35 -6.985)
          )
          (stroke (width 0.254) (type default))
          (fill (type background))
        )
        (rectangle (start 2.54 2.54) (end 8.89 -11.43)
          (stroke (width 0.254) (type default))
          (fill (type background))
        )
        (circle (center 7.62 -7.62) (radius 0.254)
          (stroke (width 0.254) (type default))
          (fill (type background))
        )
        (circle (center 7.62 -5.08) (radius 0.254)
          (stroke (width 0.254) (type default))
          (fill (type background))
        )
        (circle (center 7.62 -5.08) (radius 0.254)
          (stroke (width 0.254) (type default))
          (fill (type background))
        )
        (circle (center 7.62 -2.54) (radius 0.254)
          (stroke (width 0.254) (type default))
          (fill (type background))
        )
        (pin passive line (at 0 0 0) (length 2.54)
          (name "~" (effects (font (size 1.27 1.27))))
          (number "1" (effects (font (size 1.27 1.27))))
        )
        (pin passive line (at 0 0 0) (length 2.54) hide
          (name "~" (effects (font (size 1.27 1.27))))
          (number "10" (effects (font (size 1.27 1.27))))
        )
        (pin passive line (at 0 -2.54 0) (length 2.54)
          (name "~" (effects (font (size 1.27 1.27))))
          (number "2" (effects (font (size 1.27 1.27))))
        )
        (pin power_in line (at 0 -10.16 0) (length 2.54)
          (name "~" (effects (font (size 1.27 1.27))))
          (number "3" (effects (font (size 1.27 1.27))))
        )
        (pin passive line (at 0 -5.08 0) (length 2.54)
          (name "~" (effects (font (size 1.27 1.27))))
          (number "4" (effects (font (size 1.27 1.27))))
        )
        (pin passive line (at 0 -7.62 0) (length 2.54)
          (name "~" (effects (font (size 1.27 1.27))))
          (number "5" (effects (font (size 1.27 1.27))))
        )
        (pin passive line (at 0 -7.62 0) (length 2.54) hide
          (name "~" (effects (font (size 1.27 1.27))))
          (number "6" (effects (font (size 1.27 1.27))))
        )
        (pin passive line (at 0 -5.08 0) (length 2.54) hide
          (name "~" (effects (font (size 1.27 1.27))))
          (number "7" (effects (font (size 1.27 1.27))))
        )
        (pin passive line (at 0 -10.16 0) (length 2.54) hide
          (name "~" (effects (font (size 1.27 1.27))))
          (number "8" (effects (font (size 1.27 1.27))))
        )
        (pin passive line (at 0 -2.54 0) (length 2.54) hide
          (name "~" (effects (font (size 1.27 1.27))))
          (number "9" (effects (font (size 1.27 1.27))))
        )
      )
    )
	(symbol "kria-k26-devboard:TPS2066TDGNRQ1" (in_bom yes) (on_board yes)
      (property "Reference" "U" (at 33.02 -2.54 0)
        (effects (font (size 1.27 1.27) (thickness 0.15)) (justify left bottom))
      )
      (property "Value" "TPS2066TDGNRQ1" (at 33.02 -5.08 0)
        (effects (font (size 1.27 1.27) (thickness 0.15)) (justify left bottom))
      )
      (property "Footprint" "kria-k26-devboard-footprints:VSSOP-8-1EP_3x3x1.1mm_P0.65mm" (at 33.02 -7.62 0)
        (effects (font (size 1.27 1.27) (thickness 0.15)) (justify left bottom) hide)
      )
      (property "Datasheet" "https://www.ti.com/lit/ds/symlink/tps2066-q1.pdf?ts=1679042803235&ref_url=https%253A%252F%252Fwww.google.com%252F" (at 33.02 -10.16 0)
        (effects (font (size 1.27 1.27) (thickness 0.15)) (justify left bottom) hide)
      )
      (property "MPN" "TPS2066TDGNRQ1" (at 33.02 -12.7 0)
        (effects (font (size 1.27 1.27) (thickness 0.15)) (justify left bottom) hide)
      )
      (property "Manufacturer" "Texas Instruments" (at 33.02 -15.24 0)
        (effects (font (size 1.27 1.27) (thickness 0.15)) (justify left bottom) hide)
      )
      (property "Author" "Antmicro" (at 33.02 -17.78 0)
        (effects (font (size 1.27 1.27) (thickness 0.15)) (justify left bottom) hide)
      )
      (property "License" "Apache-2.0" (at 33.02 -20.32 0)
        (effects (font (size 1.27 1.27) (thickness 0.15)) (justify left bottom) hide)
      )
      (property "ki_keywords" "IC" (at 0 0 0)
        (effects (font (size 1.27 1.27)) hide)
      )
      (property "ki_description" "Power switch" (at 0 0 0)
        (effects (font (size 1.27 1.27)) hide)
      )
      (symbol "TPS2066TDGNRQ1_1_1"
        (rectangle (start 2.54 2.54) (end 15.24 -12.7)
          (stroke (width 0.254) (type default))
          (fill (type background))
        )
        (pin power_in line (at 17.78 -10.16 180) (length 2.54)
          (name "GND" (effects (font (size 1.27 1.27))))
          (number "1" (effects (font (size 1.27 1.27))))
        )
        (pin power_in line (at 0 0 0) (length 2.54)
          (name "IN" (effects (font (size 1.27 1.27))))
          (number "2" (effects (font (size 1.27 1.27))))
        )
        (pin input line (at 0 -5.08 0) (length 2.54)
          (name "EN1" (effects (font (size 1.27 1.27))))
          (number "3" (effects (font (size 1.27 1.27))))
        )
        (pin input line (at 0 -10.16 0) (length 2.54)
          (name "EN2" (effects (font (size 1.27 1.27))))
          (number "4" (effects (font (size 1.27 1.27))))
        )
        (pin output line (at 0 -7.62 0) (length 2.54)
          (name "~{OC2}" (effects (font (size 1.27 1.27))))
          (number "5" (effects (font (size 1.27 1.27))))
        )
        (pin output line (at 17.78 -2.54 180) (length 2.54)
          (name "OUT2" (effects (font (size 1.27 1.27))))
          (number "6" (effects (font (size 1.27 1.27))))
        )
        (pin output line (at 17.78 0 180) (length 2.54)
          (name "OUT1" (effects (font (size 1.27 1.27))))
          (number "7" (effects (font (size 1.27 1.27))))
        )
        (pin output line (at 0 -2.54 0) (length 2.54)
          (name "~{OC1}" (effects (font (size 1.27 1.27))))
          (number "8" (effects (font (size 1.27 1.27))))
        )
        (pin passive line (at 17.78 -7.62 180) (length 2.54)
          (name "EP" (effects (font (size 1.27 1.27))))
          (number "9" (effects (font (size 1.27 1.27))))
        )
      )
    )
	(symbol "kria-k26-devboard:TPS2116DRLR" (in_bom yes) (on_board yes)
      (property "Reference" "U" (at 34.29 0 0)
        (effects (font (size 1.27 1.27) (thickness 0.15)) (justify left bottom))
      )
      (property "Value" "TPS2116DRLR" (at 34.29 -2.54 0)
        (effects (font (size 1.27 1.27) (thickness 0.15)) (justify left bottom))
      )
      (property "Footprint" "kria-k26-devboard-footprints:SOT-583" (at 34.29 -5.08 0)
        (effects (font (size 1.27 1.27) (thickness 0.15)) (justify left bottom) hide)
      )
      (property "Datasheet" "https://www.ti.com/lit/ds/symlink/tps2116.pdf?ts=1647438832100&ref_url=https%253A%252F%252Fwww.ti.com%252Fproduct%252FTPS2116" (at 34.29 -7.62 0)
        (effects (font (size 1.27 1.27) (thickness 0.15)) (justify left bottom) hide)
      )
      (property "Manufacturer" "Texas Instruments" (at 34.29 -10.16 0)
        (effects (font (size 1.27 1.27) (thickness 0.15)) (justify left bottom) hide)
      )
      (property "MPN" "TPS2116DRLR" (at 34.29 -12.7 0)
        (effects (font (size 1.27 1.27) (thickness 0.15)) (justify left bottom) hide)
      )
      (property "Author" "Antmicro" (at 34.29 -15.24 0)
        (effects (font (size 1.27 1.27) (thickness 0.15)) (justify left bottom) hide)
      )
      (property "License" "Apache-2.0" (at 34.29 -17.78 0)
        (effects (font (size 1.27 1.27) (thickness 0.15)) (justify left bottom) hide)
      )
      (property "ki_keywords" "SMT, SWITCH, IC, POWER, DRIVER" (at 0 0 0)
        (effects (font (size 1.27 1.27)) hide)
      )
      (property "ki_description" "Power switch" (at 0 0 0)
        (effects (font (size 1.27 1.27)) hide)
      )
      (property "ki_fp_filters" "DRL0008A-MFG" (at 0 0 0)
        (effects (font (size 1.27 1.27)) hide)
      )
      (symbol "TPS2116DRLR_1_1"
        (rectangle (start 2.54 2.54) (end 15.24 -10.16)
          (stroke (width 0.254) (type default))
          (fill (type background))
        )
        (pin power_in line (at 17.78 -7.62 180) (length 2.54)
          (name "GND" (effects (font (size 1.27 1.27))))
          (number "1" (effects (font (size 1.27 1.27))))
        )
        (pin power_out line (at 17.78 0 180) (length 2.54)
          (name "VOUT" (effects (font (size 1.27 1.27))))
          (number "2" (effects (font (size 1.27 1.27))))
        )
        (pin power_in line (at 0 0 0) (length 2.54)
          (name "VIN1" (effects (font (size 1.27 1.27))))
          (number "3" (effects (font (size 1.27 1.27))))
        )
        (pin input line (at 0 -5.08 0) (length 2.54)
          (name "PR1" (effects (font (size 1.27 1.27))))
          (number "4" (effects (font (size 1.27 1.27))))
        )
        (pin input line (at 0 -2.54 0) (length 2.54)
          (name "MODE" (effects (font (size 1.27 1.27))))
          (number "5" (effects (font (size 1.27 1.27))))
        )
        (pin power_in line (at 0 -7.62 0) (length 2.54)
          (name "VIN2" (effects (font (size 1.27 1.27))))
          (number "6" (effects (font (size 1.27 1.27))))
        )
        (pin passive line (at 17.78 0 180) (length 2.54) hide
          (name "VOUT" (effects (font (size 1.27 1.27))))
          (number "7" (effects (font (size 1.27 1.27))))
        )
        (pin output line (at 17.78 -2.54 180) (length 2.54)
          (name "ST" (effects (font (size 1.27 1.27))))
          (number "8" (effects (font (size 1.27 1.27))))
        )
      )
    )
	(symbol "kria-k26-devboard:TPS2378DDA" (in_bom yes) (on_board yes)
      (property "Reference" "U" (at 35.56 0 0)
        (effects (font (size 1.27 1.27) (thickness 0.15)) (justify left bottom))
      )
      (property "Value" "TPS2378DDA" (at 35.56 -2.54 0)
        (effects (font (size 1.27 1.27) (thickness 0.15)) (justify left bottom) hide)
      )
      (property "Footprint" "kria-k26-devboard-footprints:SOIC-8-1EP_3.9x4.9x1.75mm_P1.27mm" (at 35.56 -5.08 0)
        (effects (font (size 1.27 1.27) (thickness 0.15)) (justify left bottom) hide)
      )
      (property "Datasheet" "http://www.ti.com/lit/ds/symlink/tps2378.pdf" (at 35.56 -7.62 0)
        (effects (font (size 1.27 1.27) (thickness 0.15)) (justify left bottom) hide)
      )
      (property "MPN" "TPS2378DDA" (at 35.56 -12.7 0)
        (effects (font (size 1.27 1.27) (thickness 0.15)) (justify left bottom))
      )
      (property "Manufacturer" "Texas Instruments" (at 35.56 -10.16 0)
        (effects (font (size 1.27 1.27) (thickness 0.15)) (justify left bottom) hide)
      )
      (property "Author" "Antmicro" (at 35.56 -15.24 0)
        (effects (font (size 1.27 1.27) (thickness 0.15)) (justify left bottom) hide)
      )
      (property "License" "Apache-2.0" (at 35.56 -17.78 0)
        (effects (font (size 1.27 1.27) (thickness 0.15)) (justify left bottom) hide)
      )
      (property "ki_keywords" "SMT, POE, IC, INTERFACE" (at 0 0 0)
        (effects (font (size 1.27 1.27)) hide)
      )
      (property "ki_description" "Power Over Ethernet (POE) Controller, 57 V/ 500 µA, 40 V UVLO Threshold, SOIC-8" (at 0 0 0)
        (effects (font (size 1.27 1.27)) hide)
      )
      (symbol "TPS2378DDA_1_1"
        (polyline
          (pts
            (xy 2.54 2.54)
            (xy 17.78 2.54)
            (xy 17.78 -16.51)
            (xy 2.54 -16.51)
            (xy 2.54 2.54)
          )
          (stroke (width 0.254) (type default))
          (fill (type background))
        )
        (pin power_in line (at 0 0 0) (length 2.54)
          (name "VDD" (effects (font (size 1.27 1.27))))
          (number "1" (effects (font (size 1.27 1.27))))
        )
        (pin passive line (at 0 -2.54 0) (length 2.54)
          (name "DEN" (effects (font (size 1.27 1.27))))
          (number "2" (effects (font (size 1.27 1.27))))
        )
        (pin passive line (at 0 -8.89 0) (length 2.54)
          (name "CLS" (effects (font (size 1.27 1.27))))
          (number "3" (effects (font (size 1.27 1.27))))
        )
        (pin power_in line (at 0 -11.43 0) (length 2.54)
          (name "VSS" (effects (font (size 1.27 1.27))))
          (number "4" (effects (font (size 1.27 1.27))))
        )
        (pin passive line (at 20.32 -13.97 180) (length 2.54)
          (name "RTN" (effects (font (size 1.27 1.27))))
          (number "5" (effects (font (size 1.27 1.27))))
        )
        (pin passive line (at 20.32 -5.08 180) (length 2.54)
          (name "CDB" (effects (font (size 1.27 1.27))))
          (number "6" (effects (font (size 1.27 1.27))))
        )
        (pin passive line (at 20.32 -2.54 180) (length 2.54)
          (name "T2P" (effects (font (size 1.27 1.27))))
          (number "7" (effects (font (size 1.27 1.27))))
        )
        (pin passive line (at 20.32 0 180) (length 2.54)
          (name "APD" (effects (font (size 1.27 1.27))))
          (number "8" (effects (font (size 1.27 1.27))))
        )
        (pin power_in line (at 0 -13.97 0) (length 2.54)
          (name "EP" (effects (font (size 1.27 1.27))))
          (number "9" (effects (font (size 1.27 1.27))))
        )
      )
    )
	(symbol "kria-k26-devboard:TPS3840PH30DBVR" (in_bom yes) (on_board yes)
      (property "Reference" "U" (at 38.1 -1.27 0)
        (effects (font (size 1.27 1.27) (thickness 0.15)) (justify left bottom))
      )
      (property "Value" "TPS3840PH30DBVR" (at 38.1 -3.81 0)
        (effects (font (size 1.27 1.27) (thickness 0.15)) (justify left bottom))
      )
      (property "Footprint" "kria-k26-devboard-footprints:SOT-23-5" (at 38.1 -6.35 0)
        (effects (font (size 1.27 1.27) (thickness 0.15)) (justify left bottom) hide)
      )
      (property "Datasheet" "https://www.ti.com/lit/ds/symlink/tps3840.pdf?HQS=dis-mous-null-mousermode-dsf-pf-null-wwe&DCM=yes&ref_url=https%3A%2F%2Fwww.mouser.com%2F&distId=26" (at 38.1 -8.89 0)
        (effects (font (size 1.27 1.27) (thickness 0.15)) (justify left bottom) hide)
      )
      (property "Manufacturer" "Texas Instruments" (at 38.1 -11.43 0)
        (effects (font (size 1.27 1.27) (thickness 0.15)) (justify left bottom) hide)
      )
      (property "MPN" "TPS3840PH30DBVR" (at 38.1 -13.97 0)
        (effects (font (size 1.27 1.27) (thickness 0.15)) (justify left bottom) hide)
      )
      (property "Author" "Antmicro" (at 38.1 -16.51 0)
        (effects (font (size 1.27 1.27) (thickness 0.15)) (justify left bottom) hide)
      )
      (property "License" "Apache-2.0" (at 38.1 -19.05 0)
        (effects (font (size 1.27 1.27) (thickness 0.15)) (justify left bottom) hide)
      )
      (property "ki_keywords" "SMT, PMIC, IC, CONTROLLER" (at 0 0 0)
        (effects (font (size 1.27 1.27)) hide)
      )
      (property "ki_description" "Voltage supervisor" (at 0 0 0)
        (effects (font (size 1.27 1.27)) hide)
      )
      (property "ki_fp_filters" "DBV0005A_N DBV0005A_M DBV0005A_L" (at 0 0 0)
        (effects (font (size 1.27 1.27)) hide)
      )
      (symbol "TPS3840PH30DBVR_1_1"
        (rectangle (start 2.54 2.54) (end 16.51 -10.16)
          (stroke (width 0.254) (type default))
          (fill (type background))
        )
        (pin open_collector line (at 19.05 0 180) (length 2.54)
          (name "RESET" (effects (font (size 1.27 1.27))))
          (number "1" (effects (font (size 1.27 1.27))))
        )
        (pin power_in line (at 0 0 0) (length 2.54)
          (name "VDD" (effects (font (size 1.27 1.27))))
          (number "2" (effects (font (size 1.27 1.27))))
        )
        (pin power_in line (at 19.05 -7.62 180) (length 2.54)
          (name "GND" (effects (font (size 1.27 1.27))))
          (number "3" (effects (font (size 1.27 1.27))))
        )
        (pin input line (at 0 -3.81 0) (length 2.54)
          (name "MR_N" (effects (font (size 1.27 1.27))))
          (number "4" (effects (font (size 1.27 1.27))))
        )
        (pin input line (at 0 -7.62 0) (length 2.54)
          (name "CT" (effects (font (size 1.27 1.27))))
          (number "5" (effects (font (size 1.27 1.27))))
        )
      )
    )
	(symbol "kria-k26-devboard:TP_0.75mm_SMD" (pin_numbers hide) (pin_names hide) (in_bom yes) (on_board yes)
      (property "Reference" "TP" (at 17.78 -5.08 0)
        (effects (font (size 1.27 1.27) (thickness 0.15)) (justify left bottom))
      )
      (property "Value" "TP_0.75mm_SMD" (at 17.78 -7.62 0)
        (effects (font (size 1.27 1.27) (thickness 0.15)) (justify left bottom))
      )
      (property "Footprint" "kria-k26-devboard-footprints:TP_SMD_0.75mm" (at 17.78 -10.16 0)
        (effects (font (size 1.27 1.27) (thickness 0.15)) (justify left bottom) hide)
      )
      (property "Datasheet" "" (at 17.78 -12.7 0)
        (effects (font (size 1.27 1.27) (thickness 0.15)) (justify left bottom) hide)
      )
      (property "MPN" "" (at 17.78 -15.24 0)
        (effects (font (size 1.27 1.27) (thickness 0.15)) (justify left bottom) hide)
      )
      (property "Manufacturer" "" (at 17.78 -17.78 0)
        (effects (font (size 1.27 1.27) (thickness 0.15)) (justify left bottom) hide)
      )
      (property "Author" "Antmicro" (at 17.78 -20.32 0)
        (effects (font (size 1.27 1.27) (thickness 0.15)) (justify left bottom) hide)
      )
      (property "License" "Apache-2.0" (at 17.78 -22.86 0)
        (effects (font (size 1.27 1.27) (thickness 0.15)) (justify left bottom) hide)
      )
      (property "ki_description" "Test Point 0.75mm" (at 0 0 0)
        (effects (font (size 1.27 1.27)) hide)
      )
      (symbol "TP_0.75mm_SMD_1_1"
        (circle (center 3.175 0) (radius 0.635)
          (stroke (width 0.254) (type default))
          (fill (type none))
        )
        (pin passive line (at 0 0 0) (length 2.54)
          (name "1" (effects (font (size 1.27 1.27))))
          (number "1" (effects (font (size 1.27 1.27))))
        )
      )
    )
	(symbol "kria-k26-devboard:USB-A_Amphenol_GSB3112311HR" (in_bom yes) (on_board yes)
      (property "Reference" "J" (at 33.02 -2.54 0)
        (effects (font (size 1.27 1.27) (thickness 0.15)) (justify left bottom))
      )
      (property "Value" "USB-A_Amphenol_GSB3112311HR" (at 33.02 -5.08 0)
        (effects (font (size 1.27 1.27) (thickness 0.15)) (justify left bottom))
      )
      (property "Footprint" "kria-k26-devboard-footprints:USB-A_Receptacle_Amphenol_GSB3112311HR" (at 33.02 -7.62 0)
        (effects (font (size 1.27 1.27) (thickness 0.15)) (justify left bottom) hide)
      )
      (property "Datasheet" "https://cdn.amphenol-cs.com/media/wysiwyg/files/drawing/gsb311231hr.pdf" (at 33.02 -10.16 0)
        (effects (font (size 1.27 1.27) (thickness 0.15)) (justify left bottom) hide)
      )
      (property "MPN" "GSB3112311HR" (at 33.02 -12.7 0)
        (effects (font (size 1.27 1.27) (thickness 0.15)) (justify left bottom) hide)
      )
      (property "Manufacturer" "Amphenol" (at 33.02 -15.24 0)
        (effects (font (size 1.27 1.27) (thickness 0.15)) (justify left bottom) hide)
      )
      (property "License" "Apache-2.0" (at 33.02 -17.78 0)
        (effects (font (size 1.27 1.27) (thickness 0.15)) (justify left bottom) hide)
      )
      (property "Author" "Antmicro" (at 33.02 -20.32 0)
        (effects (font (size 1.27 1.27) (thickness 0.15)) (justify left bottom) hide)
      )
      (property "ki_locked" "" (at 0 0 0)
        (effects (font (size 1.27 1.27)))
      )
      (property "ki_keywords" "USB, CONNECTOR, THT, HORIZONTAL" (at 0 0 0)
        (effects (font (size 1.27 1.27)) hide)
      )
      (property "ki_description" "USB-A (USB TYPE-A) USB 3.2 Gen 1 (USB 3.1 Gen 1, Superspeed (USB 3.0)) Receptacle Connector 5 Position Through Hole, Right Angle" (at 0 0 0)
        (effects (font (size 1.27 1.27)) hide)
      )
      (symbol "USB-A_Amphenol_GSB3112311HR_1_1"
        (rectangle (start -19.05 -26.67) (end -2.54 2.54)
          (stroke (width 0.254) (type default))
          (fill (type background))
        )
        (rectangle (start -16.764 -8.382) (end -14.986 -3.81)
          (stroke (width 0.254) (type default))
          (fill (type background))
        )
        (rectangle (start -16.383 -7.874) (end -15.748 -4.318)
          (stroke (width 0.254) (type default))
          (fill (type outline))
        )
        (rectangle (start -13.716 -4.953) (end -12.954 -4.191)
          (stroke (width 0.254) (type default))
          (fill (type outline))
        )
        (circle (center -12.065 -8.255) (radius 0.635)
          (stroke (width 0.254) (type default))
          (fill (type outline))
        )
        (circle (center -10.795 -5.08) (radius 0.381)
          (stroke (width 0.254) (type default))
          (fill (type outline))
        )
        (polyline
          (pts
            (xy -12.065 -6.35)
            (xy -12.065 -3.81)
          )
          (stroke (width 0.254) (type default))
          (fill (type background))
        )
        (polyline
          (pts
            (xy -12.065 -7.62)
            (xy -12.065 -6.985)
            (xy -10.795 -5.715)
            (xy -10.795 -5.08)
          )
          (stroke (width 0.254) (type default))
          (fill (type background))
        )
        (polyline
          (pts
            (xy -12.065 -6.985)
            (xy -12.065 -6.35)
            (xy -13.335 -5.715)
            (xy -13.335 -4.445)
          )
          (stroke (width 0.254) (type default))
          (fill (type background))
        )
        (polyline
          (pts
            (xy -11.43 -3.81)
            (xy -12.7 -3.81)
            (xy -12.065 -2.54)
            (xy -11.43 -3.81)
          )
          (stroke (width 0.254) (type default))
          (fill (type outline))
        )
        (text "PORT 1" (at -11.43 0 0)
          (effects (font (size 1.27 1.27) (thickness 0.15)) (justify right bottom))
        )
        (pin passive line (at 0 0 180) (length 2.54)
          (name "VBUS" (effects (font (size 1.27 1.27))))
          (number "1" (effects (font (size 1.27 1.27))))
        )
        (pin bidirectional line (at 0 -6.35 180) (length 2.54)
          (name "D-" (effects (font (size 1.27 1.27))))
          (number "2" (effects (font (size 1.27 1.27))))
        )
        (pin bidirectional line (at 0 -3.81 180) (length 2.54)
          (name "D+" (effects (font (size 1.27 1.27))))
          (number "3" (effects (font (size 1.27 1.27))))
        )
        (pin power_in line (at 0 -19.05 180) (length 2.54)
          (name "GND" (effects (font (size 1.27 1.27))))
          (number "4" (effects (font (size 1.27 1.27))))
        )
        (pin bidirectional line (at 0 -11.43 180) (length 2.54)
          (name "SSRX-" (effects (font (size 1.27 1.27))))
          (number "5" (effects (font (size 1.27 1.27))))
        )
        (pin bidirectional line (at 0 -8.89 180) (length 2.54)
          (name "SSRX+" (effects (font (size 1.27 1.27))))
          (number "6" (effects (font (size 1.27 1.27))))
        )
        (pin power_in line (at 0 -21.59 180) (length 2.54)
          (name "GND_DRAIN" (effects (font (size 1.27 1.27))))
          (number "7" (effects (font (size 1.27 1.27))))
        )
        (pin bidirectional line (at 0 -16.51 180) (length 2.54)
          (name "SSTX-" (effects (font (size 1.27 1.27))))
          (number "8" (effects (font (size 1.27 1.27))))
        )
        (pin bidirectional line (at 0 -13.97 180) (length 2.54)
          (name "SSTX+" (effects (font (size 1.27 1.27))))
          (number "9" (effects (font (size 1.27 1.27))))
        )
        (pin passive line (at 0 -24.13 180) (length 2.54)
          (name "SHIELD" (effects (font (size 1.27 1.27))))
          (number "SH" (effects (font (size 1.27 1.27))))
        )
      )
      (symbol "USB-A_Amphenol_GSB3112311HR_2_1"
        (rectangle (start -19.05 -24.13) (end -2.54 2.54)
          (stroke (width 0.254) (type default))
          (fill (type background))
        )
        (rectangle (start -16.764 -8.382) (end -14.986 -3.81)
          (stroke (width 0.254) (type default))
          (fill (type background))
        )
        (rectangle (start -16.383 -7.874) (end -15.748 -4.318)
          (stroke (width 0.254) (type default))
          (fill (type outline))
        )
        (rectangle (start -13.716 -4.953) (end -12.954 -4.191)
          (stroke (width 0.254) (type default))
          (fill (type outline))
        )
        (circle (center -12.065 -8.255) (radius 0.635)
          (stroke (width 0.254) (type default))
          (fill (type outline))
        )
        (circle (center -10.795 -5.08) (radius 0.381)
          (stroke (width 0.254) (type default))
          (fill (type outline))
        )
        (polyline
          (pts
            (xy -12.065 -6.35)
            (xy -12.065 -3.81)
          )
          (stroke (width 0.254) (type default))
          (fill (type background))
        )
        (polyline
          (pts
            (xy -12.065 -7.62)
            (xy -12.065 -6.985)
            (xy -10.795 -5.715)
            (xy -10.795 -5.08)
          )
          (stroke (width 0.254) (type default))
          (fill (type background))
        )
        (polyline
          (pts
            (xy -12.065 -6.985)
            (xy -12.065 -6.35)
            (xy -13.335 -5.715)
            (xy -13.335 -4.445)
          )
          (stroke (width 0.254) (type default))
          (fill (type background))
        )
        (polyline
          (pts
            (xy -11.43 -3.81)
            (xy -12.7 -3.81)
            (xy -12.065 -2.54)
            (xy -11.43 -3.81)
          )
          (stroke (width 0.254) (type default))
          (fill (type outline))
        )
        (text "PORT 2" (at -11.43 0 0)
          (effects (font (size 1.27 1.27) (thickness 0.15)) (justify right bottom))
        )
        (pin power_in line (at 0 0 180) (length 2.54)
          (name "VBUS" (effects (font (size 1.27 1.27))))
          (number "10" (effects (font (size 1.27 1.27))))
        )
        (pin bidirectional line (at 0 -6.35 180) (length 2.54)
          (name "D-" (effects (font (size 1.27 1.27))))
          (number "11" (effects (font (size 1.27 1.27))))
        )
        (pin bidirectional line (at 0 -3.81 180) (length 2.54)
          (name "D+" (effects (font (size 1.27 1.27))))
          (number "12" (effects (font (size 1.27 1.27))))
        )
        (pin power_in line (at 0 -19.05 180) (length 2.54)
          (name "GND" (effects (font (size 1.27 1.27))))
          (number "13" (effects (font (size 1.27 1.27))))
        )
        (pin bidirectional line (at 0 -11.43 180) (length 2.54)
          (name "SSRX-" (effects (font (size 1.27 1.27))))
          (number "14" (effects (font (size 1.27 1.27))))
        )
        (pin bidirectional line (at 0 -8.89 180) (length 2.54)
          (name "SSRX+" (effects (font (size 1.27 1.27))))
          (number "15" (effects (font (size 1.27 1.27))))
        )
        (pin power_in line (at 0 -21.59 180) (length 2.54)
          (name "GND_DRAIN" (effects (font (size 1.27 1.27))))
          (number "16" (effects (font (size 1.27 1.27))))
        )
        (pin bidirectional line (at 0 -16.51 180) (length 2.54)
          (name "SSTX-" (effects (font (size 1.27 1.27))))
          (number "17" (effects (font (size 1.27 1.27))))
        )
        (pin bidirectional line (at 0 -13.97 180) (length 2.54)
          (name "SSTX+" (effects (font (size 1.27 1.27))))
          (number "18" (effects (font (size 1.27 1.27))))
        )
      )
    )
	(symbol "kria-k26-devboard:USB-C_GCT_USB4105-GF-A" (in_bom yes) (on_board yes)
      (property "Reference" "J" (at 38.1 -2.54 0)
        (effects (font (size 1.27 1.27) (thickness 0.15)) (justify left bottom))
      )
      (property "Value" "USB-C_GCT_USB4105-GF-A" (at 38.1 -5.08 0)
        (effects (font (size 1.27 1.27) (thickness 0.15)) (justify left bottom))
      )
      (property "Footprint" "kria-k26-devboard-footprints:USB-C_Receptacle_GCT_USB4105-GF-A" (at 38.1 -7.62 0)
        (effects (font (size 1.27 1.27) (thickness 0.15)) (justify left bottom) hide)
      )
      (property "Datasheet" "https://gct.co/files/drawings/usb4105.pdf" (at 38.1 -10.16 0)
        (effects (font (size 1.27 1.27) (thickness 0.15)) (justify left bottom) hide)
      )
      (property "Manufacturer" "GCT" (at 38.1 -12.7 0)
        (effects (font (size 1.27 1.27) (thickness 0.15)) (justify left bottom) hide)
      )
      (property "MPN" "USB4105-GF-A" (at 38.1 -15.24 0)
        (effects (font (size 1.27 1.27) (thickness 0.15)) (justify left bottom) hide)
      )
      (property "Author" "Antmicro" (at 38.1 -17.78 0)
        (effects (font (size 1.27 1.27) (thickness 0.15)) (justify left bottom) hide)
      )
      (property "License" "Apache-2.0" (at 38.1 -20.32 0)
        (effects (font (size 1.27 1.27) (thickness 0.15)) (justify left bottom) hide)
      )
      (property "VSD_Class" "USB-C" (at 38.1 -22.86 0)
        (effects (font (size 1.27 1.27)) (justify left bottom) hide)
      )
      (property "ki_keywords" "USB, CONNECTOR, SMT, HORIZONTAL" (at 0 0 0)
        (effects (font (size 1.27 1.27)) hide)
      )
      (property "ki_description" "USB-C (USB TYPE-C) USB 2.0 Receptacle Connector 24 (16+8 Dummy) Position Surface Mount, Right Angle" (at 0 0 0)
        (effects (font (size 1.27 1.27)) hide)
      )
      (symbol "USB-C_GCT_USB4105-GF-A_1_1"
        (rectangle (start -22.86 2.54) (end -3.81 -38.1)
          (stroke (width 0.254) (type default))
          (fill (type background))
        )
        (circle (center -20.066 -18.034) (radius 0.284)
          (stroke (width 0.254) (type default))
          (fill (type outline))
        )
        (circle (center -19.177 -20.828) (radius 0.5236)
          (stroke (width 0.254) (type default))
          (fill (type outline))
        )
        (rectangle (start -18.669 -18.034) (end -17.907 -17.272)
          (stroke (width 0.254) (type default))
          (fill (type outline))
        )
        (arc (start -16.51 -21.59) (mid -14.605 -23.4867) (end -12.7 -21.59)
          (stroke (width 0.254) (type default))
          (fill (type background))
        )
        (arc (start -15.24 -21.59) (mid -14.605 -22.2223) (end -13.97 -21.59)
          (stroke (width 0.254) (type default))
          (fill (type outline))
        )
        (arc (start -15.24 -21.59) (mid -14.605 -22.2223) (end -13.97 -21.59)
          (stroke (width 0.254) (type default))
          (fill (type background))
        )
        (rectangle (start -15.24 -21.59) (end -13.97 -13.97)
          (stroke (width 0.254) (type default))
          (fill (type outline))
        )
        (arc (start -13.97 -13.97) (mid -14.605 -13.3377) (end -15.24 -13.97)
          (stroke (width 0.254) (type default))
          (fill (type outline))
        )
        (arc (start -13.97 -13.97) (mid -14.605 -13.3377) (end -15.24 -13.97)
          (stroke (width 0.254) (type default))
          (fill (type background))
        )
        (arc (start -12.7 -13.97) (mid -14.605 -12.0733) (end -16.51 -13.97)
          (stroke (width 0.254) (type default))
          (fill (type background))
        )
        (polyline
          (pts
            (xy -19.177 -20.701)
            (xy -19.177 -16.383)
          )
          (stroke (width 0.254) (type default))
          (fill (type background))
        )
        (polyline
          (pts
            (xy -16.51 -21.59)
            (xy -16.51 -13.97)
          )
          (stroke (width 0.254) (type default))
          (fill (type background))
        )
        (polyline
          (pts
            (xy -12.7 -13.97)
            (xy -12.7 -21.59)
          )
          (stroke (width 0.254) (type default))
          (fill (type background))
        )
        (polyline
          (pts
            (xy -19.177 -19.939)
            (xy -20.066 -19.05)
            (xy -20.066 -18.415)
          )
          (stroke (width 0.254) (type default))
          (fill (type background))
        )
        (polyline
          (pts
            (xy -19.177 -19.558)
            (xy -18.288 -18.669)
            (xy -18.288 -18.034)
          )
          (stroke (width 0.254) (type default))
          (fill (type background))
        )
        (polyline
          (pts
            (xy -19.812 -16.383)
            (xy -19.177 -15.24)
            (xy -18.542 -16.383)
            (xy -19.812 -16.383)
          )
          (stroke (width 0.254) (type default))
          (fill (type outline))
        )
        (pin power_in line (at 0 -33.02 180) (length 3.81)
          (name "GND" (effects (font (size 1.27 1.27))))
          (number "A1" (effects (font (size 1.27 1.27))))
        )
        (pin passive line (at 0 -33.02 180) (length 3.81) hide
          (name "GND" (effects (font (size 1.27 1.27))))
          (number "A12" (effects (font (size 1.27 1.27))))
        )
        (pin passive line (at 0 0 180) (length 3.81)
          (name "VBUS" (effects (font (size 1.27 1.27))))
          (number "A4" (effects (font (size 1.27 1.27))))
        )
        (pin bidirectional line (at 0 -5.08 180) (length 3.81)
          (name "CC_{1}" (effects (font (size 1.27 1.27))))
          (number "A5" (effects (font (size 1.27 1.27))))
        )
        (pin bidirectional line (at 0 -12.7 180) (length 3.81)
          (name "D_{A}+" (effects (font (size 1.27 1.27))))
          (number "A6" (effects (font (size 1.27 1.27))))
        )
        (pin bidirectional line (at 0 -15.24 180) (length 3.81)
          (name "D_{A}-" (effects (font (size 1.27 1.27))))
          (number "A7" (effects (font (size 1.27 1.27))))
        )
        (pin bidirectional line (at 0 -25.4 180) (length 3.81)
          (name "SBU_{1}" (effects (font (size 1.27 1.27))))
          (number "A8" (effects (font (size 1.27 1.27))))
        )
        (pin passive line (at 0 0 180) (length 3.81) hide
          (name "VBUS" (effects (font (size 1.27 1.27))))
          (number "A9" (effects (font (size 1.27 1.27))))
        )
        (pin passive line (at 0 -33.02 180) (length 3.81) hide
          (name "GND" (effects (font (size 1.27 1.27))))
          (number "B1" (effects (font (size 1.27 1.27))))
        )
        (pin passive line (at 0 -33.02 180) (length 3.81) hide
          (name "GND" (effects (font (size 1.27 1.27))))
          (number "B12" (effects (font (size 1.27 1.27))))
        )
        (pin passive line (at 0 0 180) (length 3.81) hide
          (name "VBUS" (effects (font (size 1.27 1.27))))
          (number "B4" (effects (font (size 1.27 1.27))))
        )
        (pin bidirectional line (at 0 -7.62 180) (length 3.81)
          (name "CC_{2}" (effects (font (size 1.27 1.27))))
          (number "B5" (effects (font (size 1.27 1.27))))
        )
        (pin bidirectional line (at 0 -17.78 180) (length 3.81)
          (name "D_{B}+" (effects (font (size 1.27 1.27))))
          (number "B6" (effects (font (size 1.27 1.27))))
        )
        (pin bidirectional line (at 0 -20.32 180) (length 3.81)
          (name "D_{B}-" (effects (font (size 1.27 1.27))))
          (number "B7" (effects (font (size 1.27 1.27))))
        )
        (pin bidirectional line (at 0 -27.94 180) (length 3.81)
          (name "SBU_{2}" (effects (font (size 1.27 1.27))))
          (number "B8" (effects (font (size 1.27 1.27))))
        )
        (pin passive line (at 0 0 180) (length 3.81) hide
          (name "VBUS" (effects (font (size 1.27 1.27))))
          (number "B9" (effects (font (size 1.27 1.27))))
        )
        (pin passive line (at 0 -35.56 180) (length 3.81)
          (name "SH" (effects (font (size 1.27 1.27))))
          (number "SH" (effects (font (size 1.27 1.27))))
        )
      )
    )
	(symbol "kria-k26-devboard:USB3310C-CP" (in_bom yes) (on_board yes)
      (property "Reference" "U" (at 40.64 -2.54 0)
        (effects (font (size 1.27 1.27) (thickness 0.15)) (justify left bottom))
      )
      (property "Value" "USB3310C-CP" (at 40.64 -5.08 0)
        (effects (font (size 1.27 1.27) (thickness 0.15)) (justify left bottom))
      )
      (property "Footprint" "kria-k26-devboard-footprints:QFN-24-1EP_4x4mm_P0.5mm_EP2.6x2.6mm" (at 40.64 -7.62 0)
        (effects (font (size 1.27 1.27) (thickness 0.15)) (justify left bottom) hide)
      )
      (property "Datasheet" "https://ww1.microchip.com/downloads/en/DeviceDoc/00002363A.pdf" (at 40.64 -10.16 0)
        (effects (font (size 1.27 1.27) (thickness 0.15)) (justify left bottom) hide)
      )
      (property "Author" "Antmicro" (at 40.64 -12.7 0)
        (effects (font (size 1.27 1.27) (thickness 0.15)) (justify left bottom) hide)
      )
      (property "License" "Apache-2.0" (at 40.64 -15.24 0)
        (effects (font (size 1.27 1.27) (thickness 0.15)) (justify left bottom) hide)
      )
      (property "MPN" "USB3310C-CP" (at 40.64 -17.78 0)
        (effects (font (size 1.27 1.27) (thickness 0.15)) (justify left bottom) hide)
      )
      (property "Manufacturer" "Microchip Technology" (at 40.64 -20.32 0)
        (effects (font (size 1.27 1.27) (thickness 0.15)) (justify left bottom) hide)
      )
      (property "ki_keywords" "SMT, IC" (at 0 0 0)
        (effects (font (size 1.27 1.27)) hide)
      )
      (property "ki_description" "USB interface" (at 0 0 0)
        (effects (font (size 1.27 1.27)) hide)
      )
      (symbol "USB3310C-CP_1_1"
        (rectangle (start 2.54 2.54) (end 24.13 -38.1)
          (stroke (width 0.254) (type default))
          (fill (type background))
        )
        (pin input line (at 0 -17.78 0) (length 2.54)
          (name "ID" (effects (font (size 1.27 1.27))))
          (number "1" (effects (font (size 1.27 1.27))))
        )
        (pin bidirectional line (at 26.67 -7.62 180) (length 2.54)
          (name "DATA4" (effects (font (size 1.27 1.27))))
          (number "10" (effects (font (size 1.27 1.27))))
        )
        (pin output line (at 26.67 -27.94 180) (length 2.54)
          (name "CLKOUT" (effects (font (size 1.27 1.27))))
          (number "11" (effects (font (size 1.27 1.27))))
        )
        (pin bidirectional line (at 26.67 -10.16 180) (length 2.54)
          (name "DATA3" (effects (font (size 1.27 1.27))))
          (number "12" (effects (font (size 1.27 1.27))))
        )
        (pin bidirectional line (at 26.67 -12.7 180) (length 2.54)
          (name "DATA2" (effects (font (size 1.27 1.27))))
          (number "13" (effects (font (size 1.27 1.27))))
        )
        (pin input line (at 0 -25.4 0) (length 2.54)
          (name "REFSEL1" (effects (font (size 1.27 1.27))))
          (number "14" (effects (font (size 1.27 1.27))))
        )
        (pin input line (at 0 -22.86 0) (length 2.54)
          (name "REFSEL0" (effects (font (size 1.27 1.27))))
          (number "15" (effects (font (size 1.27 1.27))))
        )
        (pin bidirectional line (at 26.67 -15.24 180) (length 2.54)
          (name "DATA1" (effects (font (size 1.27 1.27))))
          (number "16" (effects (font (size 1.27 1.27))))
        )
        (pin bidirectional line (at 26.67 -17.78 180) (length 2.54)
          (name "DATA0" (effects (font (size 1.27 1.27))))
          (number "17" (effects (font (size 1.27 1.27))))
        )
        (pin output line (at 26.67 -22.86 180) (length 2.54)
          (name "NXT" (effects (font (size 1.27 1.27))))
          (number "18" (effects (font (size 1.27 1.27))))
        )
        (pin output line (at 26.67 -25.4 180) (length 2.54)
          (name "DIR" (effects (font (size 1.27 1.27))))
          (number "19" (effects (font (size 1.27 1.27))))
        )
        (pin bidirectional line (at 0 -7.62 0) (length 2.54)
          (name "VBUS" (effects (font (size 1.27 1.27))))
          (number "2" (effects (font (size 1.27 1.27))))
        )
        (pin input line (at 26.67 -20.32 180) (length 2.54)
          (name "STP" (effects (font (size 1.27 1.27))))
          (number "20" (effects (font (size 1.27 1.27))))
        )
        (pin power_in line (at 0 -2.54 0) (length 2.54)
          (name "VDD_1V8" (effects (font (size 1.27 1.27))))
          (number "21" (effects (font (size 1.27 1.27))))
        )
        (pin input line (at 0 -10.16 0) (length 2.54)
          (name "RESETB" (effects (font (size 1.27 1.27))))
          (number "22" (effects (font (size 1.27 1.27))))
        )
        (pin input line (at 0 -20.32 0) (length 2.54)
          (name "REFCLK" (effects (font (size 1.27 1.27))))
          (number "23" (effects (font (size 1.27 1.27))))
        )
        (pin passive line (at 0 -27.94 0) (length 2.54)
          (name "RBIAS" (effects (font (size 1.27 1.27))))
          (number "24" (effects (font (size 1.27 1.27))))
        )
        (pin power_in line (at 0 -35.56 0) (length 2.54)
          (name "GND" (effects (font (size 1.27 1.27))))
          (number "25" (effects (font (size 1.27 1.27))))
        )
        (pin power_in line (at 0 -5.08 0) (length 2.54)
          (name "VBAT" (effects (font (size 1.27 1.27))))
          (number "3" (effects (font (size 1.27 1.27))))
        )
        (pin power_in line (at 0 0 0) (length 2.54)
          (name "VDD_3V3" (effects (font (size 1.27 1.27))))
          (number "4" (effects (font (size 1.27 1.27))))
        )
        (pin bidirectional line (at 0 -15.24 0) (length 2.54)
          (name "DM" (effects (font (size 1.27 1.27))))
          (number "5" (effects (font (size 1.27 1.27))))
        )
        (pin bidirectional line (at 0 -12.7 0) (length 2.54)
          (name "DP" (effects (font (size 1.27 1.27))))
          (number "6" (effects (font (size 1.27 1.27))))
        )
        (pin bidirectional line (at 26.67 0 180) (length 2.54)
          (name "DATA7" (effects (font (size 1.27 1.27))))
          (number "7" (effects (font (size 1.27 1.27))))
        )
        (pin bidirectional line (at 26.67 -2.54 180) (length 2.54)
          (name "DATA6" (effects (font (size 1.27 1.27))))
          (number "8" (effects (font (size 1.27 1.27))))
        )
        (pin bidirectional line (at 26.67 -5.08 180) (length 2.54)
          (name "DATA5" (effects (font (size 1.27 1.27))))
          (number "9" (effects (font (size 1.27 1.27))))
        )
      )
    )
	(symbol "kria-k26-devboard:USB7016_KDX" (in_bom yes) (on_board yes)
      (property "Reference" "U" (at 71.12 -5.08 0)
        (effects (font (size 1.27 1.27) (thickness 0.15)) (justify left bottom))
      )
      (property "Value" "USB7016_KDX" (at 71.12 -7.62 0)
        (effects (font (size 1.27 1.27) (thickness 0.15)) (justify left bottom) hide)
      )
      (property "Footprint" "kria-k26-devboard-footprints:VQFN-100-1EP_12x12x0.85mm_P0.4mm" (at 71.12 -10.16 0)
        (effects (font (size 1.27 1.27) (thickness 0.15)) (justify left bottom) hide)
      )
      (property "Datasheet" "https://ww1.microchip.com/downloads/en/DeviceDoc/USB7016-Data-Sheet-DS00003740B.pdf" (at 71.12 -12.7 0)
        (effects (font (size 1.27 1.27) (thickness 0.15)) (justify left bottom) hide)
      )
      (property "MPN" "USB7016/KDX" (at 71.12 -15.24 0)
        (effects (font (size 1.27 1.27) (thickness 0.15)) (justify left bottom))
      )
      (property "Manufacturer" "Microchip Technology" (at 71.12 -17.78 0)
        (effects (font (size 1.27 1.27) (thickness 0.15)) (justify left bottom) hide)
      )
      (property "Author" "Antmicro" (at 71.12 -20.32 0)
        (effects (font (size 1.27 1.27) (thickness 0.15)) (justify left bottom) hide)
      )
      (property "License" "Apache-2.0" (at 71.12 -22.86 0)
        (effects (font (size 1.27 1.27) (thickness 0.15)) (justify left bottom) hide)
      )
      (property "ki_keywords" "SMT, INTERFACE, CONTROLLER, IC, USB, HUB" (at 0 0 0)
        (effects (font (size 1.27 1.27)) hide)
      )
      (property "ki_description" "USB hub controller" (at 0 0 0)
        (effects (font (size 1.27 1.27)) hide)
      )
      (property "ki_fp_filters" "VQFN100_KDX_MCH VQFN100_KDX_MCH-M VQFN100_KDX_MCH-L" (at 0 0 0)
        (effects (font (size 1.27 1.27)) hide)
      )
      (symbol "USB7016_KDX_1_1"
        (rectangle (start 3.81 2.54) (end 45.72 -128.27)
          (stroke (width 0.254) (type default))
          (fill (type background))
        )
        (pin input line (at 0 -5.08 0) (length 3.81)
          (name "RESET_N" (effects (font (size 1.27 1.27))))
          (number "1" (effects (font (size 1.27 1.27))))
        )
        (pin bidirectional line (at 49.53 -20.32 180) (length 3.81)
          (name "USB3DN_RXDP1A" (effects (font (size 1.27 1.27))))
          (number "10" (effects (font (size 1.27 1.27))))
        )
        (pin input line (at 0 -121.92 0) (length 3.81)
          (name "RBIAS" (effects (font (size 1.27 1.27))))
          (number "100" (effects (font (size 1.27 1.27))))
        )
        (pin power_in line (at 0 -124.46 0) (length 3.81)
          (name "VSS" (effects (font (size 1.27 1.27))))
          (number "101" (effects (font (size 1.27 1.27))))
        )
        (pin bidirectional line (at 49.53 -22.86 180) (length 3.81)
          (name "USB3DN_RXDM1A" (effects (font (size 1.27 1.27))))
          (number "11" (effects (font (size 1.27 1.27))))
        )
        (pin bidirectional line (at 49.53 -10.16 180) (length 3.81)
          (name "DP1_CC1" (effects (font (size 1.27 1.27))))
          (number "12" (effects (font (size 1.27 1.27))))
        )
        (pin bidirectional line (at 49.53 -12.7 180) (length 3.81)
          (name "DP1_CC2" (effects (font (size 1.27 1.27))))
          (number "13" (effects (font (size 1.27 1.27))))
        )
        (pin bidirectional line (at 49.53 -96.52 180) (length 3.81)
          (name "USB2DN_DP5/PRT_DIS_P5" (effects (font (size 1.27 1.27))))
          (number "14" (effects (font (size 1.27 1.27))))
        )
        (pin bidirectional line (at 49.53 -99.06 180) (length 3.81)
          (name "USB2DN_DM5/PRT_DIS_M5" (effects (font (size 1.27 1.27))))
          (number "15" (effects (font (size 1.27 1.27))))
        )
        (pin bidirectional line (at 49.53 -25.4 180) (length 3.81)
          (name "USB3DN_TXDP1B" (effects (font (size 1.27 1.27))))
          (number "16" (effects (font (size 1.27 1.27))))
        )
        (pin bidirectional line (at 49.53 -27.94 180) (length 3.81)
          (name "USB3DN_TXDM1B" (effects (font (size 1.27 1.27))))
          (number "17" (effects (font (size 1.27 1.27))))
        )
        (pin power_in line (at 0 0 0) (length 3.81)
          (name "VCORE" (effects (font (size 1.27 1.27))))
          (number "18" (effects (font (size 1.27 1.27))))
        )
        (pin bidirectional line (at 49.53 -30.48 180) (length 3.81)
          (name "USB3DN_RXDP1B" (effects (font (size 1.27 1.27))))
          (number "19" (effects (font (size 1.27 1.27))))
        )
        (pin bidirectional line (at 0 -83.82 0) (length 3.81)
          (name "PF30" (effects (font (size 1.27 1.27))))
          (number "2" (effects (font (size 1.27 1.27))))
        )
        (pin bidirectional line (at 49.53 -33.02 180) (length 3.81)
          (name "USB3DN_RXDM1B" (effects (font (size 1.27 1.27))))
          (number "20" (effects (font (size 1.27 1.27))))
        )
        (pin input line (at 0 -99.06 0) (length 3.81)
          (name "CFG_STRAP1" (effects (font (size 1.27 1.27))))
          (number "21" (effects (font (size 1.27 1.27))))
        )
        (pin input line (at 0 -101.6 0) (length 3.81)
          (name "CFG_STRAP2" (effects (font (size 1.27 1.27))))
          (number "22" (effects (font (size 1.27 1.27))))
        )
        (pin input line (at 0 -104.14 0) (length 3.81)
          (name "CFG_STRAP3" (effects (font (size 1.27 1.27))))
          (number "23" (effects (font (size 1.27 1.27))))
        )
        (pin bidirectional line (at 0 -116.84 0) (length 3.81)
          (name "TESTEN" (effects (font (size 1.27 1.27))))
          (number "24" (effects (font (size 1.27 1.27))))
        )
        (pin passive line (at 0 0 0) (length 3.81) hide
          (name "VCORE" (effects (font (size 1.27 1.27))))
          (number "25" (effects (font (size 1.27 1.27))))
        )
        (pin power_in line (at 49.53 0 180) (length 3.81)
          (name "VDD33" (effects (font (size 1.27 1.27))))
          (number "26" (effects (font (size 1.27 1.27))))
        )
        (pin bidirectional line (at 49.53 -53.34 180) (length 3.81)
          (name "USB2DN_DP2/PRT_DIS_P2" (effects (font (size 1.27 1.27))))
          (number "27" (effects (font (size 1.27 1.27))))
        )
        (pin bidirectional line (at 49.53 -55.88 180) (length 3.81)
          (name "USB2DN_DM2/PRT_DIS_M2" (effects (font (size 1.27 1.27))))
          (number "28" (effects (font (size 1.27 1.27))))
        )
        (pin bidirectional line (at 49.53 -43.18 180) (length 3.81)
          (name "USB3DN_TXDP2" (effects (font (size 1.27 1.27))))
          (number "29" (effects (font (size 1.27 1.27))))
        )
        (pin bidirectional line (at 0 -86.36 0) (length 3.81)
          (name "PF31" (effects (font (size 1.27 1.27))))
          (number "3" (effects (font (size 1.27 1.27))))
        )
        (pin bidirectional line (at 49.53 -45.72 180) (length 3.81)
          (name "USB3DN_TXDM2" (effects (font (size 1.27 1.27))))
          (number "30" (effects (font (size 1.27 1.27))))
        )
        (pin passive line (at 0 0 0) (length 3.81) hide
          (name "VCORE" (effects (font (size 1.27 1.27))))
          (number "31" (effects (font (size 1.27 1.27))))
        )
        (pin bidirectional line (at 49.53 -48.26 180) (length 3.81)
          (name "USB3DN_RXDP2" (effects (font (size 1.27 1.27))))
          (number "32" (effects (font (size 1.27 1.27))))
        )
        (pin bidirectional line (at 49.53 -50.8 180) (length 3.81)
          (name "USB3DN_RXDM2" (effects (font (size 1.27 1.27))))
          (number "33" (effects (font (size 1.27 1.27))))
        )
        (pin bidirectional line (at 49.53 -71.12 180) (length 3.81)
          (name "USB2DN_DP3/PRT_DIS_P3" (effects (font (size 1.27 1.27))))
          (number "34" (effects (font (size 1.27 1.27))))
        )
        (pin bidirectional line (at 49.53 -73.66 180) (length 3.81)
          (name "USB2DN_DM3/PRT_DIS_M3" (effects (font (size 1.27 1.27))))
          (number "35" (effects (font (size 1.27 1.27))))
        )
        (pin bidirectional line (at 49.53 -60.96 180) (length 3.81)
          (name "USB3DN_TXDP3" (effects (font (size 1.27 1.27))))
          (number "36" (effects (font (size 1.27 1.27))))
        )
        (pin bidirectional line (at 49.53 -63.5 180) (length 3.81)
          (name "USB3DN_TXDM3" (effects (font (size 1.27 1.27))))
          (number "37" (effects (font (size 1.27 1.27))))
        )
        (pin passive line (at 0 0 0) (length 3.81) hide
          (name "VCORE" (effects (font (size 1.27 1.27))))
          (number "38" (effects (font (size 1.27 1.27))))
        )
        (pin bidirectional line (at 49.53 -66.04 180) (length 3.81)
          (name "USB3DN_RXDP3" (effects (font (size 1.27 1.27))))
          (number "39" (effects (font (size 1.27 1.27))))
        )
        (pin bidirectional line (at 49.53 -5.08 180) (length 3.81)
          (name "DP1_VBUS_MON" (effects (font (size 1.27 1.27))))
          (number "4" (effects (font (size 1.27 1.27))))
        )
        (pin bidirectional line (at 49.53 -68.58 180) (length 3.81)
          (name "USB3DN_RXDM3" (effects (font (size 1.27 1.27))))
          (number "40" (effects (font (size 1.27 1.27))))
        )
        (pin bidirectional line (at 49.53 -106.68 180) (length 3.81)
          (name "USB2DN_DM6/PRT_DIS_M6" (effects (font (size 1.27 1.27))))
          (number "41" (effects (font (size 1.27 1.27))))
        )
        (pin bidirectional line (at 49.53 -104.14 180) (length 3.81)
          (name "USB2DN_DP6/PRT_DIS_P6" (effects (font (size 1.27 1.27))))
          (number "42" (effects (font (size 1.27 1.27))))
        )
        (pin passive line (at 49.53 0 180) (length 3.81) hide
          (name "VDD33" (effects (font (size 1.27 1.27))))
          (number "43" (effects (font (size 1.27 1.27))))
        )
        (pin bidirectional line (at 0 -30.48 0) (length 3.81)
          (name "PF3" (effects (font (size 1.27 1.27))))
          (number "44" (effects (font (size 1.27 1.27))))
        )
        (pin bidirectional line (at 0 -33.02 0) (length 3.81)
          (name "PF4" (effects (font (size 1.27 1.27))))
          (number "45" (effects (font (size 1.27 1.27))))
        )
        (pin bidirectional line (at 0 -35.56 0) (length 3.81)
          (name "PF5" (effects (font (size 1.27 1.27))))
          (number "46" (effects (font (size 1.27 1.27))))
        )
        (pin bidirectional line (at 0 -38.1 0) (length 3.81)
          (name "PF6" (effects (font (size 1.27 1.27))))
          (number "47" (effects (font (size 1.27 1.27))))
        )
        (pin bidirectional line (at 0 -40.64 0) (length 3.81)
          (name "PF7" (effects (font (size 1.27 1.27))))
          (number "48" (effects (font (size 1.27 1.27))))
        )
        (pin bidirectional line (at 0 -43.18 0) (length 3.81)
          (name "PF8" (effects (font (size 1.27 1.27))))
          (number "49" (effects (font (size 1.27 1.27))))
        )
        (pin bidirectional line (at 49.53 -35.56 180) (length 3.81)
          (name "USB2DN_DP1/PRT_DIS_P1" (effects (font (size 1.27 1.27))))
          (number "5" (effects (font (size 1.27 1.27))))
        )
        (pin bidirectional line (at 0 -45.72 0) (length 3.81)
          (name "PF9" (effects (font (size 1.27 1.27))))
          (number "50" (effects (font (size 1.27 1.27))))
        )
        (pin bidirectional line (at 0 -48.26 0) (length 3.81)
          (name "PF10" (effects (font (size 1.27 1.27))))
          (number "51" (effects (font (size 1.27 1.27))))
        )
        (pin bidirectional line (at 0 -50.8 0) (length 3.81)
          (name "PF11" (effects (font (size 1.27 1.27))))
          (number "52" (effects (font (size 1.27 1.27))))
        )
        (pin passive line (at 49.53 0 180) (length 3.81) hide
          (name "VDD33" (effects (font (size 1.27 1.27))))
          (number "53" (effects (font (size 1.27 1.27))))
        )
        (pin bidirectional line (at 0 -53.34 0) (length 3.81)
          (name "PF12" (effects (font (size 1.27 1.27))))
          (number "54" (effects (font (size 1.27 1.27))))
        )
        (pin passive line (at 0 0 0) (length 3.81) hide
          (name "VCORE" (effects (font (size 1.27 1.27))))
          (number "55" (effects (font (size 1.27 1.27))))
        )
        (pin bidirectional line (at 0 -55.88 0) (length 3.81)
          (name "PF13" (effects (font (size 1.27 1.27))))
          (number "56" (effects (font (size 1.27 1.27))))
        )
        (pin bidirectional line (at 0 -58.42 0) (length 3.81)
          (name "PF14" (effects (font (size 1.27 1.27))))
          (number "57" (effects (font (size 1.27 1.27))))
        )
        (pin bidirectional line (at 0 -60.96 0) (length 3.81)
          (name "PF15" (effects (font (size 1.27 1.27))))
          (number "58" (effects (font (size 1.27 1.27))))
        )
        (pin bidirectional line (at 0 -63.5 0) (length 3.81)
          (name "PF16" (effects (font (size 1.27 1.27))))
          (number "59" (effects (font (size 1.27 1.27))))
        )
        (pin bidirectional line (at 49.53 -38.1 180) (length 3.81)
          (name "USB2DN_DM1/PRT_DIS_M1" (effects (font (size 1.27 1.27))))
          (number "6" (effects (font (size 1.27 1.27))))
        )
        (pin bidirectional line (at 0 -66.04 0) (length 3.81)
          (name "PF17" (effects (font (size 1.27 1.27))))
          (number "60" (effects (font (size 1.27 1.27))))
        )
        (pin bidirectional line (at 0 -68.58 0) (length 3.81)
          (name "PF18" (effects (font (size 1.27 1.27))))
          (number "61" (effects (font (size 1.27 1.27))))
        )
        (pin passive line (at 49.53 0 180) (length 3.81) hide
          (name "VDD33" (effects (font (size 1.27 1.27))))
          (number "62" (effects (font (size 1.27 1.27))))
        )
        (pin passive line (at 0 -109.22 0) (length 3.81)
          (name "TEST1" (effects (font (size 1.27 1.27))))
          (number "63" (effects (font (size 1.27 1.27))))
        )
        (pin passive line (at 0 -111.76 0) (length 3.81)
          (name "TEST2" (effects (font (size 1.27 1.27))))
          (number "64" (effects (font (size 1.27 1.27))))
        )
        (pin passive line (at 0 -114.3 0) (length 3.81)
          (name "TEST3" (effects (font (size 1.27 1.27))))
          (number "65" (effects (font (size 1.27 1.27))))
        )
        (pin bidirectional line (at 0 -71.12 0) (length 3.81)
          (name "PF19" (effects (font (size 1.27 1.27))))
          (number "66" (effects (font (size 1.27 1.27))))
        )
        (pin passive line (at 49.53 0 180) (length 3.81) hide
          (name "VDD33" (effects (font (size 1.27 1.27))))
          (number "67" (effects (font (size 1.27 1.27))))
        )
        (pin bidirectional line (at 49.53 -111.76 180) (length 3.81)
          (name "SPI_CLK/PF21" (effects (font (size 1.27 1.27))))
          (number "68" (effects (font (size 1.27 1.27))))
        )
        (pin bidirectional line (at 49.53 -114.3 180) (length 3.81)
          (name "SPI_CE_N/CFG_NON_REM/PF20" (effects (font (size 1.27 1.27))))
          (number "69" (effects (font (size 1.27 1.27))))
        )
        (pin bidirectional line (at 49.53 -15.24 180) (length 3.81)
          (name "USB3DN_TXDP1A" (effects (font (size 1.27 1.27))))
          (number "7" (effects (font (size 1.27 1.27))))
        )
        (pin bidirectional line (at 49.53 -116.84 180) (length 3.81)
          (name "SPI_D0/CFG_BC_EN/PF22" (effects (font (size 1.27 1.27))))
          (number "70" (effects (font (size 1.27 1.27))))
        )
        (pin bidirectional line (at 49.53 -119.38 180) (length 3.81)
          (name "SPI_D1/PF23" (effects (font (size 1.27 1.27))))
          (number "71" (effects (font (size 1.27 1.27))))
        )
        (pin bidirectional line (at 49.53 -121.92 180) (length 3.81)
          (name "SPI_D2/PF24" (effects (font (size 1.27 1.27))))
          (number "72" (effects (font (size 1.27 1.27))))
        )
        (pin bidirectional line (at 49.53 -124.46 180) (length 3.81)
          (name "SPI_D3/PF25" (effects (font (size 1.27 1.27))))
          (number "73" (effects (font (size 1.27 1.27))))
        )
        (pin bidirectional line (at 0 -73.66 0) (length 3.81)
          (name "PF29" (effects (font (size 1.27 1.27))))
          (number "74" (effects (font (size 1.27 1.27))))
        )
        (pin bidirectional line (at 0 -76.2 0) (length 3.81)
          (name "PF26" (effects (font (size 1.27 1.27))))
          (number "75" (effects (font (size 1.27 1.27))))
        )
        (pin bidirectional line (at 0 -78.74 0) (length 3.81)
          (name "PF27" (effects (font (size 1.27 1.27))))
          (number "76" (effects (font (size 1.27 1.27))))
        )
        (pin bidirectional line (at 0 -81.28 0) (length 3.81)
          (name "PF28" (effects (font (size 1.27 1.27))))
          (number "77" (effects (font (size 1.27 1.27))))
        )
        (pin passive line (at 0 0 0) (length 3.81) hide
          (name "VCORE" (effects (font (size 1.27 1.27))))
          (number "78" (effects (font (size 1.27 1.27))))
        )
        (pin passive line (at 49.53 0 180) (length 3.81) hide
          (name "VDD33" (effects (font (size 1.27 1.27))))
          (number "79" (effects (font (size 1.27 1.27))))
        )
        (pin bidirectional line (at 49.53 -17.78 180) (length 3.81)
          (name "USB3DN_TXDM1A" (effects (font (size 1.27 1.27))))
          (number "8" (effects (font (size 1.27 1.27))))
        )
        (pin bidirectional line (at 0 -10.16 0) (length 3.81)
          (name "VBUS_MON_UP" (effects (font (size 1.27 1.27))))
          (number "80" (effects (font (size 1.27 1.27))))
        )
        (pin bidirectional line (at 49.53 -88.9 180) (length 3.81)
          (name "USB2DN_DP4/PRT_DIS_P4" (effects (font (size 1.27 1.27))))
          (number "81" (effects (font (size 1.27 1.27))))
        )
        (pin bidirectional line (at 49.53 -91.44 180) (length 3.81)
          (name "USB2DN_DM4/PRT_DIS_M4" (effects (font (size 1.27 1.27))))
          (number "82" (effects (font (size 1.27 1.27))))
        )
        (pin bidirectional line (at 49.53 -78.74 180) (length 3.81)
          (name "USB3DN_TXDP4" (effects (font (size 1.27 1.27))))
          (number "83" (effects (font (size 1.27 1.27))))
        )
        (pin bidirectional line (at 49.53 -81.28 180) (length 3.81)
          (name "USB3DN_TXDM4" (effects (font (size 1.27 1.27))))
          (number "84" (effects (font (size 1.27 1.27))))
        )
        (pin passive line (at 0 0 0) (length 3.81) hide
          (name "VCORE" (effects (font (size 1.27 1.27))))
          (number "85" (effects (font (size 1.27 1.27))))
        )
        (pin bidirectional line (at 49.53 -83.82 180) (length 3.81)
          (name "USB3DN_RXDP4" (effects (font (size 1.27 1.27))))
          (number "86" (effects (font (size 1.27 1.27))))
        )
        (pin bidirectional line (at 49.53 -86.36 180) (length 3.81)
          (name "USB3DN_RXDM4" (effects (font (size 1.27 1.27))))
          (number "87" (effects (font (size 1.27 1.27))))
        )
        (pin passive line (at 49.53 0 180) (length 3.81) hide
          (name "VDD33" (effects (font (size 1.27 1.27))))
          (number "88" (effects (font (size 1.27 1.27))))
        )
        (pin bidirectional line (at 0 -22.86 0) (length 3.81)
          (name "USB2UP_DP" (effects (font (size 1.27 1.27))))
          (number "89" (effects (font (size 1.27 1.27))))
        )
        (pin passive line (at 0 0 0) (length 3.81) hide
          (name "VCORE" (effects (font (size 1.27 1.27))))
          (number "9" (effects (font (size 1.27 1.27))))
        )
        (pin bidirectional line (at 0 -25.4 0) (length 3.81)
          (name "USB2UP_DM" (effects (font (size 1.27 1.27))))
          (number "90" (effects (font (size 1.27 1.27))))
        )
        (pin bidirectional line (at 0 -12.7 0) (length 3.81)
          (name "USB3UP_TXDP" (effects (font (size 1.27 1.27))))
          (number "91" (effects (font (size 1.27 1.27))))
        )
        (pin bidirectional line (at 0 -15.24 0) (length 3.81)
          (name "USB3UP_TXDM" (effects (font (size 1.27 1.27))))
          (number "92" (effects (font (size 1.27 1.27))))
        )
        (pin passive line (at 0 0 0) (length 3.81) hide
          (name "VCORE" (effects (font (size 1.27 1.27))))
          (number "93" (effects (font (size 1.27 1.27))))
        )
        (pin bidirectional line (at 0 -17.78 0) (length 3.81)
          (name "USB3UP_RXDP" (effects (font (size 1.27 1.27))))
          (number "94" (effects (font (size 1.27 1.27))))
        )
        (pin bidirectional line (at 0 -20.32 0) (length 3.81)
          (name "USB3UP_RXDM" (effects (font (size 1.27 1.27))))
          (number "95" (effects (font (size 1.27 1.27))))
        )
        (pin no_connect line (at 3.81 -106.68 0) (length 3.81) hide
          (name "ATEST" (effects (font (size 1.27 1.27))))
          (number "96" (effects (font (size 1.27 1.27))))
        )
        (pin output line (at 0 -93.98 0) (length 3.81)
          (name "XTALO" (effects (font (size 1.27 1.27))))
          (number "97" (effects (font (size 1.27 1.27))))
        )
        (pin input line (at 0 -91.44 0) (length 3.81)
          (name "XTALI/CLK_IN" (effects (font (size 1.27 1.27))))
          (number "98" (effects (font (size 1.27 1.27))))
        )
        (pin passive line (at 49.53 0 180) (length 3.81) hide
          (name "VDD33" (effects (font (size 1.27 1.27))))
          (number "99" (effects (font (size 1.27 1.27))))
        )
      )
    )
	(symbol "kria-k26-devboard:antmicro_logo" (in_bom yes) (on_board yes)
      (property "Reference" "N" (at 15.24 -5.08 0)
        (effects (font (size 1.27 1.27) (thickness 0.15)) (justify left bottom))
      )
      (property "Value" "antmicro_logo" (at 15.24 -7.62 0)
        (effects (font (size 1.27 1.27) (thickness 0.15)) (justify left bottom))
      )
      (property "Footprint" "kria-k26-devboard-footprints:antmicro-logo" (at 15.24 -10.16 0)
        (effects (font (size 1.27 1.27) (thickness 0.15)) (justify left bottom) hide)
      )
      (property "Datasheet" "" (at 15.24 -12.7 0)
        (effects (font (size 1.27 1.27) (thickness 0.15)) (justify left bottom) hide)
      )
      (property "MPN" "" (at 0 0 0)
        (effects (font (size 1.27 1.27)) hide)
      )
      (property "Manufacturer" "" (at 15.24 -20.32 0)
        (effects (font (size 1.27 1.27) (thickness 0.15)) (justify left bottom) hide)
      )
      (property "Author" "Antmicro" (at 15.24 -15.24 0)
        (effects (font (size 1.27 1.27) (thickness 0.15)) (justify left bottom) hide)
      )
      (property "License" "Apache-2.0" (at 15.24 -17.78 0)
        (effects (font (size 1.27 1.27) (thickness 0.15)) (justify left bottom) hide)
      )
      (symbol "antmicro_logo_1_1"
        (text "Logo" (at 0 0 0)
          (effects (font (size 1.27 1.27) (thickness 0.15)) (justify left bottom))
        )
      )
    )
	(symbol "kria-k26-devboard:oshw_logo" (in_bom yes) (on_board yes)
      (property "Reference" "N" (at 15.24 -5.08 0)
        (effects (font (size 1.27 1.27) (thickness 0.15)) (justify left bottom))
      )
      (property "Value" "oshw_logo" (at 15.24 -7.62 0)
        (effects (font (size 1.27 1.27) (thickness 0.15)) (justify left bottom))
      )
      (property "Footprint" "kria-k26-devboard-footprints:oshw-logo" (at 15.24 -10.16 0)
        (effects (font (size 1.27 1.27) (thickness 0.15)) (justify left bottom) hide)
      )
      (property "Datasheet" "" (at 15.24 -12.7 0)
        (effects (font (size 1.27 1.27) (thickness 0.15)) (justify left bottom) hide)
      )
      (property "Author" "Antmicro" (at 15.24 -15.24 0)
        (effects (font (size 1.27 1.27) (thickness 0.15)) (justify left bottom) hide)
      )
      (property "License" "Apache-2.0" (at 15.24 -17.78 0)
        (effects (font (size 1.27 1.27) (thickness 0.15)) (justify left bottom) hide)
      )
      (property "MPN" "" (at 0 0 0)
        (effects (font (size 1.27 1.27)) hide)
      )
      (property "Manufacturer" "" (at 15.24 -20.32 0)
        (effects (font (size 1.27 1.27) (thickness 0.15)) (justify left bottom) hide)
      )
      (symbol "oshw_logo_1_1"
        (text "Logo" (at 0 0 0)
          (effects (font (size 1.27 1.27) (thickness 0.15)) (justify left bottom))
        )
      )
    )
)
